FILE_TYPE=PINLIST;
{ Packager-XL run on 30-Nov-2015 AT 15:33:22 }
TIME=' COMPILATION ON 30-Nov-2015 AT 15:33:22';
primitive '0R2J-L-GP_SMD-RG5-0R2J-L-GP,63A';body '0R2J-L-GP';
    '1':'(1)';
    '2':'(2)';
end_primitive;
primitive '0R3J-0-U-GP_RCL_GP-0R3J-0-U-GPA';body '0R3J-0-U-GP';
    '1':'(1)';
    '2':'(2)';
end_primitive;
primitive '120R2F-GP_RCL_GP-120R2F-GP,64.A';body '120R2F-GP';
    '1':'(1)';
    '2':'(2)';
end_primitive;
primitive '21K5R2F-GP_RCL_GP-21K5R2F-GP,6A';body '21K5R2F-GP';
    '1':'(1)';
    '2':'(2)';
end_primitive;
primitive '232KR2F-2-GP_SMD-RG1-232KR2F-2A';body '232KR2F-2-GP';
    '1':'(1)';
    '2':'(2)';
end_primitive;
primitive '3D01R5F-GP_SMD-RG5-3D01R5F-GP,A';body '3D01R5F-GP';
    '1':'(1)';
    '2':'(2)';
end_primitive;
primitive '47KR2F-GP_RCL_GP-47KR2F-GP,64.A';body '47KR2F-GP';
    '1':'(1)';
    '2':'(2)';
end_primitive;
primitive '4K42R2F-GP_SMD-RG-4K42R2F-GP,6A';body '4K42R2F-GP';
    '1':'(1)';
    '2':'(2)';
end_primitive;
primitive '5K1R2F-2-GP_SMD-RG-5K1R2F-2-GPA';body '5K1R2F-2-GP';
    '1':'(1)';
    '2':'(2)';
end_primitive;
primitive '74CBTLV1G125_SMLF-IC,C88177-00A';body '74CBTLV1G125';
    'B':'(4)';OUT;
    'OE_N':'(1)';IN;
    'A':'(2)';IN;
end_primitive;
primitive '82K5R2F-GP_SMD-RG-82K5R2F-GP,6A';body '82K5R2F-GP';
    '1':'(1)';
    '2':'(2)';
end_primitive;
primitive 'ADC128D818_SM-IC,H63642-001';body 'ADC128D818';
    'A0':'(7)';IN;
    'A1':'(8)';IN;
    'GND':'(4)';
    'IN0':'(16)';IN;
    'IN1':'(15)';IN;
    'IN2':'(14)';IN;
    'IN3':'(13)';IN;
    'IN4':'(12)';IN;
    'IN5':'(11)';IN;
    'IN6':'(10)';IN;
    'IN7':'(9)';IN;
    'INT_N':'(6)';OUT;
    'SCL':'(3)';IN;
    'SDA':'(2)';BIDI;
    'VP':'(5)';
    'VREF':'(1)';IN;
end_primitive;
primitive 'ADM1085_SMT-IC,H46130-001';body 'ADM1085';
    'CEXT':'(5)';
    'ENIN':'(1)';IN;
    'ENOUT':'(4)';OUT;
    'GND':'(2)';
    'VCC':'(6)';
    'VIN':'(3)';IN;
end_primitive;
primitive 'ADM1278_SM-IC,G99251-001';body 'ADM1278';
    'ADR1':'(7)';
    'ADR2':'(8)';
    'CSOUT':'(19)';OUT;
    'ENABLE':'(12)';IN;
    'EP':'(33)';
    'FAULT_N':'(6)';
    'GATE':'(24)';OUT;
    'GND':'(22)';
    'GPO1_ALERT1_N_CONV':'(13)';BIDI;
    'GPO2_ALERT2_N':'(14)';BIDI;
    'HSN':'(27)';IN;
    'HSP':'(28)';IN;
    'ISET':'(3)';IN;
    'ISTART':'(4)';IN;
    'MCLK':'(10)';OUT;
    'MDAT':'(11)';OUT;
    'MON':'(26)';IN;
    'MOP':'(29)';IN;
    'OV':'(32)';IN;
    'PGND':'(23)';
    'PSET':'(1)';IN;
    'PWGIN':'(21)';IN;
    'PWRGD':'(18)';
    'RETRY_N':'(17)';
    'SCL':'(16)';IN;
    'SDA':'(15)';BIDI;
    'SPISS_N':'(9)';
    'TEMP':'(25)';IN;
    'TIMER':'(5)';
    'UV':'(31)';IN;
    'VCAP':'(2)';IN;
    'VCC':'(30)';
    'VOUT':'(20)';OUT;
end_primitive;
primitive 'ADM4073_SM-EMPTY,G12194-001';body 'ADM4073';
    'GND'<1>:'(2)';
    'GND'<0>:'(1)';
    'OUT':'(6)';OUT;
    'RSN':'(5)';BIDI;
    'RSP':'(4)';BIDI;
    'VCC':'(3)';
end_primitive;
primitive 'ADM809_SMLF-IC,D23047-001-GND=A';body 'ADM809';
    'VCC':'(3)';
    'RESET_N':'(2)';OUT;
end_primitive;
primitive 'AST2520A1-GP-GP_ASIC2-GB1-AST2A';body 'AST2520A1-GP-GP';
    'MDQ4':'(U9,0,0,0,0,0,0)';$S;BIDI;
    'MDQ3':'(AA10,0,0,0,0,0,0)';$S;BIDI;
    'MDQ2':'(Y10,0,0,0,0,0,0)';$S;BIDI;
    'MDQ1':'(W10,0,0,0,0,0,0)';$S;BIDI;
    'MDQ0':'(U10,0,0,0,0,0,0)';$S;BIDI;
    'MA15':'(U15,0,0,0,0,0,0)';$S;OUT;
    'MDQ15':'(U7,0,0,0,0,0,0)';$S;BIDI;
    'MDQ14':'(V7,0,0,0,0,0,0)';$S;BIDI;
    'MDM1':'(AB8,0,0,0,0,0,0)';$S;OUT;
    'MIOZ':'(W11,0,0,0,0,0,0)';$S;
    'MCAS#':'(AB13,0,0,0,0,0,0)';$S;OUT;
    'MA10':'(U13,0,0,0,0,0,0)';$S;OUT;
    'MA11':'(AA14,0,0,0,0,0,0)';$S;OUT;
    'MVREF':'(T9,0,0,0,0,0,0)';$S;
    'MDQ9':'(Y8,0,0,0,0,0,0)';$S;BIDI;
    'MODT':'(V11,0,0,0,0,0,0)';$S;OUT;
    'MCKE':'(Y11,0,0,0,0,0,0)';$S;OUT;
    'MCKN':'(AB12,0,0,0,0,0,0)';$S;OUT;
    'MBA2_MBG0':'(W13,0,0,0,0,0,0)';$S;OUT;
    'MBA1':'(Y13,0,0,0,0,0,0)';$S;OUT;
    'MBA0':'(U12,0,0,0,0,0,0)';$S;OUT;
    'MA9':'(Y16,0,0,0,0,0,0)';$S;OUT;
    'MA8':'(W16,0,0,0,0,0,0)';$S;OUT;
    'MA7':'(AA16,0,0,0,0,0,0)';$S;OUT;
    'MA6':'(AB16,0,0,0,0,0,0)';$S;OUT;
    'MA5':'(V15,0,0,0,0,0,0)';$S;OUT;
    'MA4':'(W15,0,0,0,0,0,0)';$S;OUT;
    'MA3':'(U14,0,0,0,0,0,0)';$S;OUT;
    'MA2':'(W14,0,0,0,0,0,0)';$S;OUT;
    'MA12':'(Y14,0,0,0,0,0,0)';$S;OUT;
    'MA1':'(AB14,0,0,0,0,0,0)';$S;OUT;
    'MA0':'(V13,0,0,0,0,0,0)';$S;OUT;
    'MDQS1P':'(AB7,0,0,0,0,0,0)';$S;BIDI;
    'MDQS1N':'(AB6,0,0,0,0,0,0)';$S;BIDI;
    'MDQS0P':'(AB9,0,0,0,0,0,0)';$S;BIDI;
    'MDQS0N':'(AB10,0,0,0,0,0,0)';$S;BIDI;
    'MDQ6':'(W9,0,0,0,0,0,0)';$S;BIDI;
    'MDQ5':'(Y9,0,0,0,0,0,0)';$S;BIDI;
    'MDQ13':'(W7,0,0,0,0,0,0)';$S;BIDI;
    'MDQ12':'(AA6,0,0,0,0,0,0)';$S;BIDI;
    'MDM0':'(U8,0,0,0,0,0,0)';$S;OUT;
    'MA13':'(AB15,0,0,0,0,0,0)';$S;OUT;
    'MA14_MACT#':'(Y15,0,0,0,0,0,0)';$S;OUT;
    'MDQ11':'(W8,0,0,0,0,0,0)';$S;BIDI;
    'MDQ10':'(Y7,0,0,0,0,0,0)';$S;BIDI;
    'MWE#':'(Y12,0,0,0,0,0,0)';$S;OUT;
    'MRAS#':'(W12,0,0,0,0,0,0)';$S;OUT;
    'MDQ7':'(V9,0,0,0,0,0,0)';$S;BIDI;
    'MDQ8':'(AA8,0,0,0,0,0,0)';$S;BIDI;
    'MCKP':'(AB11,0,0,0,0,0,0)';$S;OUT;
    'MCS#':'(AA12,0,0,0,0,0,0)';$S;OUT;
    'GPIOB6_LPCPME#':'(0,H22,0,0,0,0,0)';$S;BIDI;
    'GPIOB4_USBCKI':'(0,J20,0,0,0,0,0)';$S;BIDI;
    'GPIOY4_SCL1':'(0,M18,0,0,0,0,0)';$S;BIDI;
    'GPIOI7_SPI1MISO_VBMISO':'(0,A15,0,0,0,0,0)';$S;BIDI;
    'DACRSET':'(0,K4,0,0,0,0,0)';$S;
    'DACR':'(0,J4,0,0,0,0,0)';$S;OUT;
    'DACG':'(0,J3,0,0,0,0,0)';$S;OUT;
    'TMS':'(0,C8,0,0,0,0,0)';$S;BIDI;
    'TDI':'(0,D12,0,0,0,0,0)';$S;BIDI;
    'TCK':'(0,C10,0,0,0,0,0)';$S;BIDI;
    'RTCK':'(0,C9,0,0,0,0,0)';$S;OUT;
    'NTRST':'(0,E11,0,0,0,0,0)';$S;BIDI;
    'GPIOI1_SYSCK':'(0,E15,0,0,0,0,0)';$S;BIDI;
    'GPIOI0_SYSCS#':'(0,C18,0,0,0,0,0)';$S;BIDI;
    'GPIOI5_SPI1CK_VBCK':'(0,C15,0,0,0,0,0)';$S;BIDI;
    'GPIOI4_SPI1CS0#_VBCS#':'(0,B15,0,0,0,0,0)';$S;BIDI;
    'GPIOI6_SPI1MOSI_VBMOSI':'(0,A14,0,0,0,0,0)';$S;BIDI;
    'GPIOJ1_SGPMLD':'(0,L2,0,0,0,0,0)';$S;BIDI;
    'GPIOJ0_SGPMCK':'(0,R2,0,0,0,0,0)';$S;BIDI;
    'GPIOJ2_SGPMO':'(0,N3,0,0,0,0,0)';$S;BIDI;
    'GPIOG3_SGPS1I1':'(0,E16,0,0,0,0,0)';$S;BIDI;
    'GPIOG2_SGPS1I0':'(0,C19,0,0,0,0,0)';$S;BIDI;
    'DACB':'(0,J2,0,0,0,0,0)';$S;OUT;
    'GPIOY5_SDA1':'(0,M19,0,0,0,0,0)';$S;BIDI;
    'TDO':'(0,D11,0,0,0,0,0)';$S;BIDI;
    'GPIOB0':'(0,K19,0,0,0,0,0)';$S;BIDI;
    'GPIOB1':'(0,L19,0,0,0,0,0)';$S;BIDI;
    'GPIOB2':'(0,L18,0,0,0,0,0)';$S;BIDI;
    'GPIOB3':'(0,K18,0,0,0,0,0)';$S;BIDI;
    'GPIOB7':'(0,H20,0,0,0,0,0)';$S;BIDI;
    'GPIOY6_SCL2':'(0,M20,0,0,0,0,0)';$S;BIDI;
    'GPIOY7_SDA2':'(0,P20,0,0,0,0,0)';$S;BIDI;
    'GPIOQ0_SCL3':'(0,A11,0,0,0,0,0)';$S;BIDI;
    'GPIOQ1_SDA3':'(0,A10,0,0,0,0,0)';$S;BIDI;
    'GPIOQ2_SCL4':'(0,A9,0,0,0,0,0)';$S;BIDI;
    'GPIOQ3_SDA4':'(0,B9,0,0,0,0,0)';$S;BIDI;
    'GPIOK0_SCL5':'(0,L3,0,0,0,0,0)';$S;BIDI;
    'GPIOK1_SDA5':'(0,L4,0,0,0,0,0)';$S;BIDI;
    'GPIOK2_SCL6':'(0,L1,0,0,0,0,0)';$S;BIDI;
    'GPIOK3_SDA6':'(0,N2,0,0,0,0,0)';$S;BIDI;
    'GPIOG1_SGPS1LD':'(0,E19,0,0,0,0,0)';$S;BIDI;
    'GPIOG0_SGPS1CK':'(0,A19,0,0,0,0,0)';$S;BIDI;
    'GPIOJ3_SGPMI':'(0,N4,0,0,0,0,0)';$S;BIDI;
    'GPIOI2_SYSMOSI':'(0,B16,0,0,0,0,0)';$S;BIDI;
    'GPIOI3_SYSMISO':'(0,C16,0,0,0,0,0)';$S;BIDI;
    'GPIOA5_TIMER6_SDA9':'(0,A13,0,0,0,0,0)';$S;BIDI;
    'GPIOA4_TIMER5_SCL9':'(0,C14,0,0,0,0,0)';$S;BIDI;
    'GPIOK7_SDA8':'(0,R1,0,0,0,0,0)';$S;BIDI;
    'GPIOK6_SCL8':'(0,P2,0,0,0,0,0)';$S;BIDI;
    'GPIOK5_SDA7':'(0,P1,0,0,0,0,0)';$S;BIDI;
    'GPIOK4_SCL7':'(0,N1,0,0,0,0,0)';$S;BIDI;
    'GPIOB5_LPCPD#_LPCSMI#':'(0,H21,0,0,0,0,0)';$S;BIDI;
    'GPIOQ4_SCL14':'(0,N21,0,0,0,0,0)';$S;BIDI;
    'GPIOQ5_SDA14':'(0,N22,0,0,0,0,0)';$S;BIDI;
    'GPIOC2_SD1DAT0_SCL11':'(0,0,B12,0,0,0,0)';$S;BIDI;
    'GPIOC3_SD1DAT1_SDA11':'(0,0,D9,0,0,0,0)';$S;BIDI;
    'GPIOC1_SD1CMD_SDA10':'(0,0,A12,0,0,0,0)';$S;BIDI;
    'GPIOC0_SD1CLK_SCL10':'(0,0,C12,0,0,0,0)';$S;BIDI;
    'GPIOA0_MAC1LINK':'(0,0,B14,0,0,0,0)';$S;BIDI;
    'GPIOA1_MAC2LINK':'(0,0,D14,0,0,0,0)';$S;BIDI;
    'GPIOY3_SIOONCTRL#':'(0,0,P21,0,0,0,0)';$S;BIDI;
    'GPIOG6_SGPS2I0_SALT3':'(0,0,D15,0,0,0,0)';$S;BIDI;
    'GPIOC6_SD1CD#_SCL13':'(0,0,C11,0,0,0,0)';$S;BIDI;
    'GPIOC4_SD1DAT2_SCL12':'(0,0,D10,0,0,0,0)';$S;BIDI;
    'GPIOG7_SGPS2I1_SALT4':'(0,0,E14,0,0,0,0)';$S;BIDI;
    'GPIOA2_TIMER3_SPI1CS1#':'(0,0,D13,0,0,0,0)';$S;BIDI;
    'GPIOG5_SGPS2LD_SALT2':'(0,0,D16,0,0,0,0)';$S;BIDI;
    'GPIOG4_SGPS2CK_SALT1':'(0,0,E17,0,0,0,0)';$S;BIDI;
    'GPIOF5_NRTS4_LHFRAME#':'(0,0,H19,0,0,0,0)';$S;BIDI;
    'GPIOF7_RXD4_LHRST#':'(0,0,H18,0,0,0,0)';$S;BIDI;
    'GPIOL2_NDSR1':'(0,0,U1,0,0,0,0)';$S;BIDI;
    'GPIOL3_NRI1_VPIHS':'(0,0,U2,0,0,0,0)';$S;BIDI;
    'GPIOL4_NDTR1_VPIVS':'(0,0,P4,0,0,0,0)';$S;BIDI;
    'PEREFCLKN':'(0,0,K22,0,0,0,0)';$S;IN;
    'PEREFCLKP':'(0,0,K21,0,0,0,0)';$S;IN;
    'RXD5':'(0,0,K2,0,0,0,0)';$S;IN;
    'PECI':'(0,0,AB18,0,0,0,0)';$S;BIDI;
    'GPIOD3_SD2DAT1':'(0,0,D20,0,0,0,0)';$S;BIDI;
    'GPIOD4_SD2DAT2':'(0,0,D21,0,0,0,0)';$S;BIDI;
    'GPIOD1_SD2CMD':'(0,0,E21,0,0,0,0)';$S;BIDI;
    'CLKIN':'(0,0,W18,0,0,0,0)';$S;IN;
    'SRST#':'(0,0,U18,0,0,0,0)';$S;IN;
    'GPIOA3_TIMER4':'(0,0,E13,0,0,0,0)';$S;BIDI;
    'PERST#':'(0,0,L20,0,0,0,0)';$S;BIDI;
    'PERXN':'(0,0,M22,0,0,0,0)';$S;IN;
    'PERXP':'(0,0,M21,0,0,0,0)';$S;IN;
    'GPIOM0_NCTS2_VPIB2':'(0,0,Y1,0,0,0,0)';$S;BIDI;
    'GPIOM1_NDCD2_VPIB3':'(0,0,AB2,0,0,0,0)';$S;BIDI;
    'GPIOM2_NDSR2_VPIB4':'(0,0,AA1,0,0,0,0)';$S;BIDI;
    'GPIOM3_NRI2_VPIB5':'(0,0,Y2,0,0,0,0)';$S;BIDI;
    'GPIOM4_NDTR2_VPIB6':'(0,0,AA2,0,0,0,0)';$S;BIDI;
    'GPIOM5_NRTS2_VPIB7':'(0,0,P5,0,0,0,0)';$S;BIDI;
    'GPIOM6_TXD2_VPIB8':'(0,0,R5,0,0,0,0)';$S;BIDI;
    'GPIOM7_RXD2_VPIB9':'(0,0,T5,0,0,0,0)';$S;BIDI;
    'GPIOL1_NDCD1_VPIDE':'(0,0,T1,0,0,0,0)';$S;BIDI;
    'GPIOL5_NRTS1_VPICLK':'(0,0,P3,0,0,0,0)';$S;BIDI;
    'GPIOL7_RXD1':'(0,0,W1,0,0,0,0)';$S;BIDI;
    'GPIOF0_NCTS4_LHAD0':'(0,0,J19,0,0,0,0)';$S;BIDI;
    'GPIOF1_NDCD4_LHAD1':'(0,0,J18,0,0,0,0)';$S;BIDI;
    'GPIOF2_NDSR4_LHAD2':'(0,0,B22,0,0,0,0)';$S;BIDI;
    'GPIOE2_NDSR3':'(0,0,F18,0,0,0,0)';$S;BIDI;
    'GPIOE3_NRI3':'(0,0,F17,0,0,0,0)';$S;BIDI;
    'GPIOE4_NDTR3':'(0,0,E18,0,0,0,0)';$S;BIDI;
    'GPIOE6_TXD3':'(0,0,A20,0,0,0,0)';$S;BIDI;
    'GPIOE7_RXD3':'(0,0,B19,0,0,0,0)';$S;BIDI;
    'TXD5':'(0,0,K1,0,0,0,0)';$S;OUT;
    'PEREXT':'(0,0,K20,0,0,0,0)';$S;
    'PETXN':'(0,0,L22,0,0,0,0)';$S;OUT;
    'PETXP':'(0,0,L21,0,0,0,0)';$S;OUT;
    'GPIOE5_NRTS3':'(0,0,D19,0,0,0,0)';$S;BIDI;
    'GPIOE1_NDCD3':'(0,0,C20,0,0,0,0)';$S;BIDI;
    'GPIOE0_NCTS3':'(0,0,B20,0,0,0,0)';$S;BIDI;
    'GPIOD0_SD2CLK':'(0,0,F19,0,0,0,0)';$S;BIDI;
    'GPIOD2_SD2DAT0':'(0,0,F20,0,0,0,0)';$S;BIDI;
    'GPIOD7_SD2WP#':'(0,0,C21,0,0,0,0)';$S;BIDI;
    'GPIOC7_SD1WP#_SDA13':'(0,0,B11,0,0,0,0)';$S;BIDI;
    'GPIOC5_SD1DAT3_SDA12':'(0,0,E12,0,0,0,0)';$S;BIDI;
    'GPIOL0_NCTS1':'(0,0,T2,0,0,0,0)';$S;BIDI;
    'GPIOF3_NRI4_LHAD3':'(0,0,B21,0,0,0,0)';$S;BIDI;
    'GPIOF4_NDTR4_LHCLK':'(0,0,A21,0,0,0,0)';$S;BIDI;
    'GPIOF6_TXD4_LHSIRQ#':'(0,0,G17,0,0,0,0)';$S;BIDI;
    'GPIOL6_TXD1':'(0,0,V1,0,0,0,0)';$S;BIDI;
    'GPIOD6_SD2CD#':'(0,0,G18,0,0,0,0)';$S;BIDI;
    'GPIOD5_SD2DAT3':'(0,0,E20,0,0,0,0)';$S;BIDI;
    'USB2BVRES':'(0,0,0,B7,0,0,0)';$S;
    'USB2AVRES':'(0,0,0,B8,0,0,0)';$S;
    'GPIOH0_NCTS6':'(0,0,0,A18,0,0,0)';$S;BIDI;
    'GPIOH2_NDSR6':'(0,0,0,D17,0,0,0)';$S;BIDI;
    'GPIOH1_NDCD6':'(0,0,0,B18,0,0,0)';$S;BIDI;
    'GPIOH4_NDTR6':'(0,0,0,A17,0,0,0)';$S;BIDI;
    'GPIOH3_NRI6':'(0,0,0,C17,0,0,0)';$S;BIDI;
    'GPIOH5_NRTS6':'(0,0,0,B17,0,0,0)';$S;BIDI;
    'GPIOH7_RXD6':'(0,0,0,D18,0,0,0)';$S;BIDI;
    'GPIOH6_TXD6':'(0,0,0,A16,0,0,0)';$S;BIDI;
    'GPIOS0_VPOB2_SPI2CS1#':'(0,0,0,V20,0,0,0)';$S;BIDI;
    'GPIOS2_VPOB4_SALT5':'(0,0,0,R18,0,0,0)';$S;BIDI;
    'GPIOZ1_VPOG3_NORA1_SIOPWRGD':'(0,0,0,AB20,0,0,0)';$S;BIDI;
    'GPIOZ2_VPOG4_NORA2_SIOPBO#':'(0,0,0,AB21,0,0,0)';$S;BIDI;
    'GPIOZ3_VPOG5_NORA3_SIOSCI#':'(0,0,0,AA21,0,0,0)';$S;BIDI;
    'GPIOZ4_VPOG6_NORA4':'(0,0,0,U21,0,0,0)';$S;BIDI;
    'GPIOZ5_VPOG7_NORA5':'(0,0,0,W22,0,0,0)';$S;BIDI;
    'GPIOZ6_VPOG8_NORA6':'(0,0,0,V22,0,0,0)';$S;BIDI;
    'GPIOZ7_VPOG9_NORA7':'(0,0,0,W21,0,0,0)';$S;BIDI;
    'GPIOAA0_VPOR2_NORD0_SALT7':'(0,0,0,Y21,0,0,0)';$S;BIDI;
    'GPIOS3_VPOB5_SALT6':'(0,0,0,P18,0,0,0)';$S;BIDI;
    'GPIOS7_VPOB9':'(0,0,0,AA20,0,0,0)';$S;BIDI;
    'GPIOZ0_VPOG2_NORA0_SIOPBI#':'(0,0,0,Y20,0,0,0)';$S;BIDI;
    'GPIOAA2_VPOR4_NORD2_SALT9':'(0,0,0,Y22,0,0,0)';$S;BIDI;
    'USB2A_DP':'(0,0,0,A7,0,0,0)';$S;BIDI;
    'USB2A_DN':'(0,0,0,A8,0,0,0)';$S;BIDI;
    'USB2B_DP':'(0,0,0,B6,0,0,0)';$S;BIDI;
    'USB2B_DN':'(0,0,0,A6,0,0,0)';$S;BIDI;
    'GPIOS6_VPOB8':'(0,0,0,U20,0,0,0)';$S;BIDI;
    'GPIOS5_VPOB7':'(0,0,0,W20,0,0,0)';$S;BIDI;
    'GPIOS4_VPOB6':'(0,0,0,R19,0,0,0)';$S;BIDI;
    'GPIOS1_VPOB3_BMCINT':'(0,0,0,U19,0,0,0)';$S;BIDI;
    'GPIOAA1_VPOR3_NORD1_SALT8':'(0,0,0,V21,0,0,0)';$S;BIDI;
    'GPIOAA7_VPOR9_NORD7_SALT14':'(0,0,0,P19,0,0,0)';$S;BIDI;
    'GPIOAA6_VPOR8_NORD6_SALT13':'(0,0,0,N18,0,0,0)';$S;BIDI;
    'GPIOAA5_VPOR7_NORD5_SALT12':'(0,0,0,T20,0,0,0)';$S;BIDI;
    'GPIOAA4_VPOR6_NORD4_SALT11':'(0,0,0,U22,0,0,0)';$S;BIDI;
    'GPIOAA3_VPOR5_NORD3_SALT10':'(0,0,0,AA22,0,0,0)';$S;BIDI;
    'GPIOAC7_ESPIRST#_LPCRST#':'(0,0,0,0,G22,0,0)';$S;BIDI;
    'ENTEST':'(0,0,0,0,K3,0,0)';$S;IN;
    'EXTRST#':'(0,0,0,0,V18,0,0)';$S;IN;
    'GPIOQ6_OSCCLK':'(0,0,0,0,B10,0,0)';$S;BIDI;
    'GPIOQ7_PEWAKE#':'(0,0,0,0,N20,0,0)';$S;BIDI;
    'GPIOR5_SPI2MISO':'(0,0,0,0,V19,0,0)';$S;BIDI;
    'GPIOR2_SPI2CS0#':'(0,0,0,0,T17,0,0)';$S;BIDI;
    'GPIOR1_FWSPICS2#':'(0,0,0,0,T19,0,0)';$S;BIDI;
    'GPIOR0_FWSPICS1#':'(0,0,0,0,AA19,0,0)';$S;BIDI;
    'MRESET#':'(0,0,0,0,AB17,0,0)';$S;OUT;
    'MALERT#':'(0,0,0,0,U16,0,0)';$S;BIDI;
    'HBLED#':'(0,0,0,0,Y18,0,0)';$S;OUT;
    'GPIOJ4_VGAHS':'(0,0,0,0,N5,0,0)';$S;BIDI;
    'FWSPIMOSI':'(0,0,0,0,U17,0,0)';$S;BIDI;
    'FWSPICK':'(0,0,0,0,AA18,0,0)';$S;BIDI;
    'GPIOJ7_DDCDAT':'(0,0,0,0,T3,0,0)';$S;BIDI;
    'GPIOJ6_DDCCLK':'(0,0,0,0,R3,0,0)';$S;BIDI;
    'GPIOJ5_VGAVS':'(0,0,0,0,R4,0,0)';$S;BIDI;
    'GPIOAB3_VPOCLK_WDTRST2':'(0,0,0,0,R20,0,0)';$S;BIDI;
    'GPIOAB2_VPOVS_WDTRST1':'(0,0,0,0,T22,0,0)';$S;BIDI;
    'GPIOAB1_VPOHS_NORWE#':'(0,0,0,0,T21,0,0)';$S;BIDI;
    'GPIOAB0_VPODE_NOROE#':'(0,0,0,0,N19,0,0)';$S;BIDI;
    'GPIOAC4_ESPICK_LCLK':'(0,0,0,0,C22,0,0)';$S;BIDI;
    'GPIOAC3_ESPID3_LAD3':'(0,0,0,0,E22,0,0)';$S;BIDI;
    'GPIOAC2_ESPID2_LAD2':'(0,0,0,0,D22,0,0)';$S;BIDI;
    'GPIOAC1_ESPID1_LAD1':'(0,0,0,0,G20,0,0)';$S;BIDI;
    'GPIOAC0_ESPID0_LAD0':'(0,0,0,0,G21,0,0)';$S;BIDI;
    'FWSPIMISO':'(0,0,0,0,T18,0,0)';$S;BIDI;
    'FWSPICS0#':'(0,0,0,0,AB19,0,0)';$S;BIDI;
    'GPIOAC6_ESPIALT#_LSIRQ#':'(0,0,0,0,F22,0,0)';$S;BIDI;
    'GPIOAC5_ESPICS#_LFRAME#':'(0,0,0,0,F21,0,0)';$S;BIDI;
    'GPIOR3_SPI2CK':'(0,0,0,0,Y19,0,0)';$S;BIDI;
    'GPIOR4_SPI2MOSI':'(0,0,0,0,W19,0,0)';$S;BIDI;
    'ADC8_GPIX0':'(0,0,0,0,0,F2,0)';$S;IN;
    'ADC7_GPIW7':'(0,0,0,0,0,G4,0)';$S;IN;
    'GPIOA6_TIMER7_MDC2':'(0,0,0,0,0,C13,0)';$S;BIDI;
    'GPIOA7_TIMER8_MDIO2':'(0,0,0,0,0,B13,0)';$S;BIDI;
    'RGMIICK':'(0,0,0,0,0,D3,0)';$S;IN;
    'GPION6_PWM6_VPIG6':'(0,0,0,0,0,Y3,0)';$S;BIDI;
    'GPION7_PWM7_VPIG7':'(0,0,0,0,0,T4,0)';$S;BIDI;
    'GPION4_PWM4_VPIG4':'(0,0,0,0,0,W3,0)';$S;BIDI;
    'GPION5_PWM5_VPIG5':'(0,0,0,0,0,AA3,0)';$S;BIDI;
    'GPION3_PWM3_VPIG3':'(0,0,0,0,0,U3,0)';$S;BIDI;
    'GPION1_PWM1':'(0,0,0,0,0,W2,0)';$S;BIDI;
    'GPION2_PWM2_VPIG2':'(0,0,0,0,0,V3,0)';$S;BIDI;
    'GPION0_PWM0':'(0,0,0,0,0,V2,0)';$S;BIDI;
    'ADCVREFP':'(0,0,0,0,0,H2,0)';$S;OUT;
    'ADCREXT':'(0,0,0,0,0,J1,0)';$S;OUT;
    'ADCVREFN':'(0,0,0,0,0,H1,0)';$S;OUT;
    'ADC14_GPIX6':'(0,0,0,0,0,H3,0)';$S;IN;
    'ADC15_GPIX7':'(0,0,0,0,0,H4,0)';$S;IN;
    'ADC13_GPIX5':'(0,0,0,0,0,G1,0)';$S;IN;
    'ADC12_GPIX4':'(0,0,0,0,0,H5,0)';$S;IN;
    'ADC11_GPIX3':'(0,0,0,0,0,F1,0)';$S;IN;
    'ADC9_GPIX1':'(0,0,0,0,0,G3,0)';$S;IN;
    'ADC10_GPIX2':'(0,0,0,0,0,G2,0)';$S;IN;
    'ADC6_GPIW6':'(0,0,0,0,0,G5,0)';$S;IN;
    'ADC4_GPIW4':'(0,0,0,0,0,F3,0)';$S;IN;
    'ADC5_GPIW5':'(0,0,0,0,0,E3,0)';$S;IN;
    'ADC3_GPIW3':'(0,0,0,0,0,E1,0)';$S;IN;
    'ADC2_GPIW2':'(0,0,0,0,0,E2,0)';$S;IN;
    'ADC1_GPIW1':'(0,0,0,0,0,F5,0)';$S;IN;
    'ADC0_GPIW0':'(0,0,0,0,0,F4,0)';$S;IN;
    'GPIOP7_TACH15':'(0,0,0,0,0,V6,0)';$S;BIDI;
    'GPIOP6_TACH14':'(0,0,0,0,0,W6,0)';$S;BIDI;
    'GPIOP3_TACH11_VPIR9':'(0,0,0,0,0,AB5,0)';$S;BIDI;
    'GPIOP4_TACH12':'(0,0,0,0,0,Y6,0)';$S;BIDI;
    'GPIOP5_TACH13':'(0,0,0,0,0,Y5,0)';$S;BIDI;
    'GPIOP2_TACH10_VPIR8':'(0,0,0,0,0,AA5,0)';$S;BIDI;
    'GPIOP1_TACH9_VPIR7':'(0,0,0,0,0,W5,0)';$S;BIDI;
    'GPIOO6_TACH6_VPIR4':'(0,0,0,0,0,AA4,0)';$S;BIDI;
    'GPIOO7_TACH7_VPIR5':'(0,0,0,0,0,W4,0)';$S;BIDI;
    'GPIOP0_TACH8_VPIR6':'(0,0,0,0,0,V4,0)';$S;BIDI;
    'GPIOO4_TACH4_VPIR2':'(0,0,0,0,0,AB3,0)';$S;BIDI;
    'GPIOO5_TACH5_VPIR3':'(0,0,0,0,0,Y4,0)';$S;BIDI;
    'GPIOO3_TACH3':'(0,0,0,0,0,AB4,0)';$S;BIDI;
    'GPIOO1_TACH1_VPIG9':'(0,0,0,0,0,U4,0)';$S;BIDI;
    'GPIOO2_TACH2':'(0,0,0,0,0,V5,0)';$S;BIDI;
    'GPIOO0_TACH0_VPIG8':'(0,0,0,0,0,U5,0)';$S;BIDI;
    'RGMII2TXCTL_RMII2TXEN_GPIOT7':'(0,0,0,0,0,B1,0)';$S;OUT;
    'RGMII2TXCK_RMII2RCLKO_GPIOT6':'(0,0,0,0,0,B2,0)';$S;OUT;
    'RGMII2TXD2_GPIOU2':'(0,0,0,0,0,D5,0)';$S;OUT;
    'RGMII2TXD3_GPIOU3':'(0,0,0,0,0,D4,0)';$S;OUT;
    'RGMII2TXD1_RMII2TXD1_GPIOU1':'(0,0,0,0,0,B3,0)';$S;OUT;
    'RGMII2TXD0_RMII2TXD0_GPIOU0':'(0,0,0,0,0,A2,0)';$S;OUT;
    'RGMII1TXCK_RMII1RCLKO_GPIOT0':'(0,0,0,0,0,B5,0)';$S;OUT;
    'RGMII1TXCTL_RMII1TXEN_GPIOT1':'(0,0,0,0,0,E9,0)';$S;OUT;
    'RGMII1TXD2_GPIOT4':'(0,0,0,0,0,E7,0)';$S;OUT;
    'RGMII1TXD3_GPIOT5':'(0,0,0,0,0,D7,0)';$S;OUT;
    'RGMII1TXD0_RMII1TXD0_GPIOT2':'(0,0,0,0,0,F9,0)';$S;OUT;
    'RGMII1TXD1_RMII1TXD1_GPIOT3':'(0,0,0,0,0,A5,0)';$S;OUT;
    'RGMII2RXCTL_GPIOV3':'(0,0,0,0,0,C1,0)';$S;BIDI;
    'GPIOR6_MDC1':'(0,0,0,0,0,D8,0)';$S;BIDI;
    'GPIOR7_MDIO1':'(0,0,0,0,0,E10,0)';$S;BIDI;
    'RGMII1RXD0_RMII1RXD0_GPIOU6':'(0,0,0,0,0,A3,0)';$S;BIDI;
    'RGMII1RXD1_RMII1RXD1_GPIOU7':'(0,0,0,0,0,D6,0)';$S;BIDI;
    'RGMII1RXD2_RMII1CRSDV_GPIOV0':'(0,0,0,0,0,C5,0)';$S;BIDI;
    'RGMII1RXD3_RMII1RXER_GPIOV1':'(0,0,0,0,0,C4,0)';$S;BIDI;
    'RGMII1RXCTL_GPIOU5':'(0,0,0,0,0,A4,0)';$S;BIDI;
    'RGMII1RXCK_RMII1RCLKI_GPIOU4':'(0,0,0,0,0,B4,0)';$S;BIDI;
    'RGMII2RXD0_RMII2RXD0_GPIOV4':'(0,0,0,0,0,C3,0)';$S;BIDI;
    'RGMII2RXD1_RMII2RXD1_GPIOV5':'(0,0,0,0,0,D1,0)';$S;BIDI;
    'RGMII2RXD2_RMII2CRSDV_GPIOV6':'(0,0,0,0,0,D2,0)';$S;BIDI;
    'RGMII2RXD3_RMII2RXER_GPIOV7':'(0,0,0,0,0,E6,0)';$S;BIDI;
    'RGMII2RXCK_RMII2RCLKI_GPIOV2':'(0,0,0,0,0,C2,0)';$S;BIDI;
    'LPVDD1':'(0,0,0,0,0,0,K17)';$S;
    'LPVDD0':'(0,0,0,0,0,0,J17)';$S;
    'GND68':'(0,0,0,0,0,0,E5)';$S;
    'DACAV33':'(0,0,0,0,0,0,K6)';$S;
    'PV33D0':'(0,0,0,0,0,0,F12)';$S;
    'MVDD4':'(0,0,0,0,0,0,T8)';$S;
    'GPIOY2_SIOPWREQ#':'(0,0,0,0,0,0,P22)';$S;BIDI;
    'GPIOY1_SIOS5#':'(0,0,0,0,0,0,R21)';$S;BIDI;
    'GPIOY0_SIOS3#':'(0,0,0,0,0,0,R22)';$S;BIDI;
    'IV11D0':'(0,0,0,0,0,0,F6)';$S;
    'IV11D1':'(0,0,0,0,0,0,G10)';$S;
    'IV11D2':'(0,0,0,0,0,0,G11)';$S;
    'IV11D3':'(0,0,0,0,0,0,G12)';$S;
    'IV11D4':'(0,0,0,0,0,0,G13)';$S;
    'IV11D5':'(0,0,0,0,0,0,G14)';$S;
    'IV11D6':'(0,0,0,0,0,0,G15)';$S;
    'IV11D7':'(0,0,0,0,0,0,G7)';$S;
    'IV11D8':'(0,0,0,0,0,0,G8)';$S;
    'IV11D9':'(0,0,0,0,0,0,G9)';$S;
    'IV11D10':'(0,0,0,0,0,0,H16)';$S;
    'IV11D11':'(0,0,0,0,0,0,J16)';$S;
    'IV11D12':'(0,0,0,0,0,0,L7)';$S;
    'IV11D13':'(0,0,0,0,0,0,N16)';$S;
    'IV11D14':'(0,0,0,0,0,0,N7)';$S;
    'IV11D15':'(0,0,0,0,0,0,P10)';$S;
    'IV11D16':'(0,0,0,0,0,0,P11)';$S;
    'IV11D17':'(0,0,0,0,0,0,P12)';$S;
    'IV11D18':'(0,0,0,0,0,0,P13)';$S;
    'IV11D19':'(0,0,0,0,0,0,P14)';$S;
    'IV11D20':'(0,0,0,0,0,0,P16)';$S;
    'IV11D21':'(0,0,0,0,0,0,P7)';$S;
    'IV11D22':'(0,0,0,0,0,0,P9)';$S;
    'IV11D23':'(0,0,0,0,0,0,R16)';$S;
    'IV11D24':'(0,0,0,0,0,0,R7)';$S;
    'VPLLAV110':'(0,0,0,0,0,0,L5)';$S;
    'VPLLAV111':'(0,0,0,0,0,0,L6)';$S;
    'PEAV11':'(0,0,0,0,0,0,L17)';$S;
    'PLLDV11':'(0,0,0,0,0,0,V17)';$S;
    'PECIVDD':'(0,0,0,0,0,0,AA17)';$S;
    'MVDD0':'(0,0,0,0,0,0,T10)';$S;
    'MVDD1':'(0,0,0,0,0,0,T12)';$S;
    'MVDD2':'(0,0,0,0,0,0,T13)';$S;
    'MVDD3':'(0,0,0,0,0,0,T14)';$S;
    'PV33D1':'(0,0,0,0,0,0,F13)';$S;
    'PV33D2':'(0,0,0,0,0,0,F14)';$S;
    'PV33D3':'(0,0,0,0,0,0,F15)';$S;
    'PV33D4':'(0,0,0,0,0,0,G16)';$S;
    'PV33D5':'(0,0,0,0,0,0,H17)';$S;
    'PV33D6':'(0,0,0,0,0,0,K7)';$S;
    'PV33D7':'(0,0,0,0,0,0,N17)';$S;
    'PV33D8':'(0,0,0,0,0,0,N6)';$S;
    'PV33D9':'(0,0,0,0,0,0,P17)';$S;
    'PV33D10':'(0,0,0,0,0,0,P6)';$S;
    'PV33D11':'(0,0,0,0,0,0,R17)';$S;
    'PV33D12':'(0,0,0,0,0,0,R6)';$S;
    'PV33D13':'(0,0,0,0,0,0,T11)';$S;
    'PV33D14':'(0,0,0,0,0,0,T15)';$S;
    'PLLAV330':'(0,0,0,0,0,0,Y17)';$S;
    'PLLAV331':'(0,0,0,0,0,0,W17)';$S;
    'VPLLAV330':'(0,0,0,0,0,0,J7)';$S;
    'VPLLAV331':'(0,0,0,0,0,0,H7)';$S;
    'PEAV33':'(0,0,0,0,0,0,L16)';$S;
    'BATVDD':'(0,0,0,0,0,0,E4)';$S;
    'USB2AV33':'(0,0,0,0,0,0,C7)';$S;
    'DACDV33':'(0,0,0,0,0,0,K5)';$S;
    'ADCAV33':'(0,0,0,0,0,0,J6)';$S;
    'R2VDD0':'(0,0,0,0,0,0,F7)';$S;
    'R2VDD1':'(0,0,0,0,0,0,F8)';$S;
    'R1VDD0':'(0,0,0,0,0,0,F10)';$S;
    'R1VDD1':'(0,0,0,0,0,0,F11)';$S;
    'GND67':'(0,0,0,0,0,0,V8)';$S;
    'GND66':'(0,0,0,0,0,0,V16)';$S;
    'GND65':'(0,0,0,0,0,0,V14)';$S;
    'GND60':'(0,0,0,0,0,0,T7)';$S;
    'GND61':'(0,0,0,0,0,0,U11)';$S;
    'GND64':'(0,0,0,0,0,0,V12)';$S;
    'GND63':'(0,0,0,0,0,0,V10)';$S;
    'GND62':'(0,0,0,0,0,0,U6)';$S;
    'GND55':'(0,0,0,0,0,0,N13)';$S;
    'GND56':'(0,0,0,0,0,0,N14)';$S;
    'GND59':'(0,0,0,0,0,0,T6)';$S;
    'GND58':'(0,0,0,0,0,0,T16)';$S;
    'GND57':'(0,0,0,0,0,0,N9)';$S;
    'GND50':'(0,0,0,0,0,0,M7)';$S;
    'GND51':'(0,0,0,0,0,0,M9)';$S;
    'GND54':'(0,0,0,0,0,0,N12)';$S;
    'GND53':'(0,0,0,0,0,0,N11)';$S;
    'GND52':'(0,0,0,0,0,0,N10)';$S;
    'GND45':'(0,0,0,0,0,0,M2)';$S;
    'GND46':'(0,0,0,0,0,0,M3)';$S;
    'GND49':'(0,0,0,0,0,0,M6)';$S;
    'GND48':'(0,0,0,0,0,0,M5)';$S;
    'GND47':'(0,0,0,0,0,0,M4)';$S;
    'GND40':'(0,0,0,0,0,0,M12)';$S;
    'GND41':'(0,0,0,0,0,0,M13)';$S;
    'GND44':'(0,0,0,0,0,0,M17)';$S;
    'GND43':'(0,0,0,0,0,0,M16)';$S;
    'GND42':'(0,0,0,0,0,0,M14)';$S;
    'GND35':'(0,0,0,0,0,0,L14)';$S;
    'GND39':'(0,0,0,0,0,0,M11)';$S;
    'GND38':'(0,0,0,0,0,0,M10)';$S;
    'GND37':'(0,0,0,0,0,0,M1)';$S;
    'GND36':'(0,0,0,0,0,0,L9)';$S;
    'GND30':'(0,0,0,0,0,0,K9)';$S;
    'GND34':'(0,0,0,0,0,0,L13)';$S;
    'GND33':'(0,0,0,0,0,0,L12)';$S;
    'GND32':'(0,0,0,0,0,0,L11)';$S;
    'GND31':'(0,0,0,0,0,0,L10)';$S;
    'GND29':'(0,0,0,0,0,0,K16)';$S;
    'GND25':'(0,0,0,0,0,0,K11)';$S;
    'GND27':'(0,0,0,0,0,0,K13)';$S;
    'GND28':'(0,0,0,0,0,0,K14)';$S;
    'GND26':'(0,0,0,0,0,0,K12)';$S;
    'GND24':'(0,0,0,0,0,0,K10)';$S;
    'GND20':'(0,0,0,0,0,0,J21)';$S;
    'GND23':'(0,0,0,0,0,0,J9)';$S;
    'GND22':'(0,0,0,0,0,0,J5)';$S;
    'GND21':'(0,0,0,0,0,0,J22)';$S;
    'GND19':'(0,0,0,0,0,0,J14)';$S;
    'GND14':'(0,0,0,0,0,0,H6)';$S;
    'GND15':'(0,0,0,0,0,0,J10)';$S;
    'GND18':'(0,0,0,0,0,0,J13)';$S;
    'GND17':'(0,0,0,0,0,0,J12)';$S;
    'GND16':'(0,0,0,0,0,0,J11)';$S;
    'GND9':'(0,0,0,0,0,0,C6)';$S;
    'GND10':'(0,0,0,0,0,0,E8)';$S;
    'GND13':'(0,0,0,0,0,0,G6)';$S;
    'GND12':'(0,0,0,0,0,0,G19)';$S;
    'GND11':'(0,0,0,0,0,0,F16)';$S;
    'GND4':'(0,0,0,0,0,0,AA15)';$S;
    'GND5':'(0,0,0,0,0,0,AA7)';$S;
    'GND7':'(0,0,0,0,0,0,AB1)';$S;
    'GND8':'(0,0,0,0,0,0,AB22)';$S;
    'GND6':'(0,0,0,0,0,0,AA9)';$S;
    'GND3':'(0,0,0,0,0,0,AA13)';$S;
    'GND2':'(0,0,0,0,0,0,AA11)';$S;
    'GND1':'(0,0,0,0,0,0,A22)';$S;
    'GND0':'(0,0,0,0,0,0,A1)';$S;
end_primitive;
primitive 'AT24C64_SOICLF-IC,C47049-001-GA';body 'AT24C64';
    'A0':'(1)';IN;
    'A1':'(2)';IN;
    'A2':'(3)';IN;
    'SCL':'(6)';IN;
    'WP':'(7)';IN;
    'SDA':'(5)';BIDI;
end_primitive;
primitive 'BATTERY_PLCLF-202168-001';body 'BATTERY';
end_primitive;
primitive 'CAPP_2626-270UF,16V,20%,OSCON,A';body 'CAPP';
    'A':'(1)';
    'B':'(2)';
end_primitive;
primitive 'CAPP_3018-470UF,2.5V,20%,ALUM,A';body 'CAPP';
    'A':'(1)';
    'B':'(2)';
end_primitive;
primitive 'CAPP_3018-470UF,6.3V,20%,POSCAA';body 'CAPP';
    'A':'(1)';
    'B':'(2)';
end_primitive;
primitive 'CAPP_3018-68UF,16V,20%,TANT,72A';body 'CAPP';
    'A':'(1)';
    'B':'(2)';
end_primitive;
primitive 'CAPP_4040LF-470UF,16V,20%,ALUMA';body 'CAPP';
    'A':'(1)';
    'B':'(2)';
end_primitive;
primitive 'CAPP_7343-220UF,4V,20%,POSCAP,A';body 'CAPP';
    'A':'(1)';
    'B':'(2)';
end_primitive;
primitive 'CAPP_7343HLF-330UF,10V,20%,POSA';body 'CAPP';
    'A':'(1)';
    'B':'(2)';
end_primitive;
primitive 'CAPP_7343LF-330UF,6.3V,20%,POSA';body 'CAPP';
    'A':'(1)';
    'B':'(2)';
end_primitive;
primitive 'CAPP_SM-470UF,2V,20%,ALUM,6990A';body 'CAPP';
    'A':'(1)';
    'B':'(2)';
end_primitive;
primitive 'CAPTIVE_SCREW_TH-HDW,H57868-001';body 'CAPTIVE_SCREW';
end_primitive;
primitive 'CAP_0402-0.027UF,16V,10%,X7R,AA';body 'CAP';
    'A':'(1)';
    'B':'(2)';
end_primitive;
primitive 'CAP_0402-0.047UF,25V,10%,X7R,AA';body 'CAP';
    'A':'(1)';
    'B':'(2)';
end_primitive;
primitive 'CAP_0402-0.1UF,16V,10%,EMPTY,AA';body 'CAP';
    'A':'(1)';
    'B':'(2)';
end_primitive;
primitive 'CAP_0402-0.220UF,16V,10%,X7R,AA';body 'CAP';
    'A':'(1)';
    'B':'(2)';
end_primitive;
primitive 'CAP_0402-0.22UF,16V,10%,EMPTY,A';body 'CAP';
    'A':'(1)';
    'B':'(2)';
end_primitive;
primitive 'CAP_0402-0.22UF,16V,10%,X7R,A3A';body 'CAP';
    'A':'(1)';
    'B':'(2)';
end_primitive;
primitive 'CAP_0402-1.0UF,16V,10%,X6S,D97A';body 'CAP';
    'A':'(1)';
    'B':'(2)';
end_primitive;
primitive 'CAP_0402-1.0UF,16V,10%,X7S,G71A';body 'CAP';
    'A':'(1)';
    'B':'(2)';
end_primitive;
primitive 'CAP_0402-1.0UF,6.3V,10%,X6S,D9A';body 'CAP';
    'A':'(1)';
    'B':'(2)';
end_primitive;
primitive 'CAP_0402LF-0.01UF,25V,10%,X7R,A';body 'CAP';
    'A':'(1)';
    'B':'(2)';
end_primitive;
primitive 'CAP_0402LF-0.022UF,16V,10%,X7RA';body 'CAP';
    'A':'(1)';
    'B':'(2)';
end_primitive;
primitive 'CAP_0402LF-0.039UF,25V,10%,X7RA';body 'CAP';
    'A':'(1)';
    'B':'(2)';
end_primitive;
primitive 'CAP_0402LF-0.1UF,16V,10%,X7R,AA';body 'CAP';
    'A':'(1)';
    'B':'(2)';
end_primitive;
primitive 'CAP_0402LF-10.0PF,50V,5%,COG,AA';body 'CAP';
    'A':'(1)';
    'B':'(2)';
end_primitive;
primitive 'CAP_0402LF-100.0PF,50V,5%,COG,A';body 'CAP';
    'A':'(1)';
    'B':'(2)';
end_primitive;
primitive 'CAP_0402LF-1000PF,50V,10%,EMPTA';body 'CAP';
    'A':'(1)';
    'B':'(2)';
end_primitive;
primitive 'CAP_0402LF-1000PF,50V,10%,X7R,A';body 'CAP';
    'A':'(1)';
    'B':'(2)';
end_primitive;
primitive 'CAP_0402LF-12.0PF,50V,5%,COG,AA';body 'CAP';
    'A':'(1)';
    'B':'(2)';
end_primitive;
primitive 'CAP_0402LF-15.0PF,50V,5%,COG,AA';body 'CAP';
    'A':'(1)';
    'B':'(2)';
end_primitive;
primitive 'CAP_0402LF-18PF,50V,5%,C0G,A36A';body 'CAP';
    'A':'(1)';
    'B':'(2)';
end_primitive;
primitive 'CAP_0402LF-22.0PF,50V,5%,COG,AA';body 'CAP';
    'A':'(1)';
    'B':'(2)';
end_primitive;
primitive 'CAP_0402LF-2200PF,50V,10%,X7R,A';body 'CAP';
    'A':'(1)';
    'B':'(2)';
end_primitive;
primitive 'CAP_0402LF-220PF,50V,10%,X7R,AA';body 'CAP';
    'A':'(1)';
    'B':'(2)';
end_primitive;
primitive 'CAP_0402LF-27.0PF,50V,5%,COG,AA';body 'CAP';
    'A':'(1)';
    'B':'(2)';
end_primitive;
primitive 'CAP_0402LF-270PF,50V,10%,X7R,AA';body 'CAP';
    'A':'(1)';
    'B':'(2)';
end_primitive;
primitive 'CAP_0402LF-33.0PF,50V,5%,COG,AA';body 'CAP';
    'A':'(1)';
    'B':'(2)';
end_primitive;
primitive 'CAP_0402LF-3300PF,50V,10%,EMPTA';body 'CAP';
    'A':'(1)';
    'B':'(2)';
end_primitive;
primitive 'CAP_0402LF-47.0PF,50V,5%,COG,AA';body 'CAP';
    'A':'(1)';
    'B':'(2)';
end_primitive;
primitive 'CAP_0402LF-47.0PF,50V,5%,EMPTYA';body 'CAP';
    'A':'(1)';
    'B':'(2)';
end_primitive;
primitive 'CAP_0402LF-4700PF,50V,10%,EMPTA';body 'CAP';
    'A':'(1)';
    'B':'(2)';
end_primitive;
primitive 'CAP_0402LF-470PF,50V,10%,EMPTYA';body 'CAP';
    'A':'(1)';
    'B':'(2)';
end_primitive;
primitive 'CAP_0402LF-470PF,50V,10%,X7R,AA';body 'CAP';
    'A':'(1)';
    'B':'(2)';
end_primitive;
primitive 'CAP_0603-10UF,6.3V,20%,X6S,E15A';body 'CAP';
    'A':'(1)';
    'B':'(2)';
end_primitive;
primitive 'CAP_0603-4.7UF,6.3V,10%,X6S,E1A';body 'CAP';
    'A':'(1)';
    'B':'(2)';
end_primitive;
primitive 'CAP_0603LF-0.033UF,50V,10%,X7RA';body 'CAP';
    'A':'(1)';
    'B':'(2)';
end_primitive;
primitive 'CAP_0603LF-0.1UF,25V,10%,X7R,6A';body 'CAP';
    'A':'(1)';
    'B':'(2)';
end_primitive;
primitive 'CAP_0603LF-10UF,4V,20%,X6S,E15A';body 'CAP';
    'A':'(1)';
    'B':'(2)';
end_primitive;
primitive 'CAP_0805-100UF,4V,20%,X5R,6024A';body 'CAP';
    'A':'(1)';
    'B':'(2)';
end_primitive;
primitive 'CAP_0805-10UF,16V,10%,X6S,C953A';body 'CAP';
    'A':'(1)';
    'B':'(2)';
end_primitive;
primitive 'CAP_0805-10UF,16V,10%,X7R,G106A';body 'CAP';
    'A':'(1)';
    'B':'(2)';
end_primitive;
primitive 'CAP_0805-22UF,6.3V,20%,X6S,C95A';body 'CAP';
    'A':'(1)';
    'B':'(2)';
end_primitive;
primitive 'CAP_0805-47UF,4V,20%,X6S,C9533A';body 'CAP';
    'A':'(1)';
    'B':'(2)';
end_primitive;
primitive 'CAP_0805LF-22UF,4V,20%,X6S,C95A';body 'CAP';
    'A':'(1)';
    'B':'(2)';
end_primitive;
primitive 'CAP_1206-0.068UF,50V,20%,X7R,1A';body 'CAP';
    'A':'(1)';
    'B':'(2)';
end_primitive;
primitive 'CAP_1206LF-22UF,16V,10%,X6S,D3A';body 'CAP';
    'A':'(1)';
    'B':'(2)';
end_primitive;
primitive 'CAP_1210-100UF,16V,20%,X5R,644A';body 'CAP';
    'A':'(1)';
    'B':'(2)';
end_primitive;
primitive 'CAP_1210-47UF,16V,20%,EMPTY,D3A';body 'CAP';
    'A':'(1)';
    'B':'(2)';
end_primitive;
primitive 'CAP_1210-47UF,16V,20%,X6S,D384A';body 'CAP';
    'A':'(1)';
    'B':'(2)';
end_primitive;
primitive 'CAP_A_0402V-0.01UF,25V,10%,EMPA';body 'CAP_A';
    'A':'(1)';
    'B':'(2)';
end_primitive;
primitive 'CAP_A_0402V-0.01UF,25V,10%,X7RA';body 'CAP_A';
    'A':'(1)';
    'B':'(2)';
end_primitive;
primitive 'CAP_A_0402V-0.1UF,16V,10%,EMPTA';body 'CAP_A';
    'A':'(1)';
    'B':'(2)';
end_primitive;
primitive 'CAP_A_0402V-0.1UF,16V,10%,X7R,A';body 'CAP_A';
    'A':'(1)';
    'B':'(2)';
end_primitive;
primitive 'CAP_A_0402V-1.0UF,6.3V,10%,X6SA';body 'CAP_A';
    'A':'(1)';
    'B':'(2)';
end_primitive;
primitive 'CAP_A_0603V-22.0UF,4V,20%,EMPTA';body 'CAP_A';
    'A':'(1)';
    'B':'(2)';
end_primitive;
primitive 'CAP_A_0603V-22.0UF,4V,20%,X6S,A';body 'CAP_A';
    'A':'(1)';
    'B':'(2)';
end_primitive;
primitive 'CAP_A_0603V-47UF,4V,20%,X5R,60A';body 'CAP_A';
    'A':'(1)';
    'B':'(2)';
end_primitive;
primitive 'CHOKE_4PIN_SMLF-90 OHM,EMPTY,7A';body 'CHOKE_4PIN';
    'A1':'(1)';
    'A2':'(2)';
    'B1':'(3)';
    'B2':'(4)';
end_primitive;
primitive 'CONN12_C73564003_PIP-CONN,C735A';body 'CONN12_C73564003';
    'IO1':'(1)';BIDI;
    'IO10':'(10)';BIDI;
    'IO11':'(11)';BIDI;
    'IO12':'(12)';BIDI;
    'IO2':'(2)';BIDI;
    'IO3':'(3)';BIDI;
    'IO4':'(4)';BIDI;
    'IO5':'(5)';BIDI;
    'IO6':'(6)';BIDI;
    'IO7':'(7)';BIDI;
    'IO8':'(8)';BIDI;
    'IO9':'(9)';BIDI;
end_primitive;
primitive 'CONN12_G98257001_THMT-CONN,G98A';body 'CONN12_G98257001';
    'A1':'(A1)';BIDI;
    'A2':'(A2)';BIDI;
    'A3':'(A3)';BIDI;
    'B1':'(B1)';BIDI;
    'B2':'(B2)';BIDI;
    'B3':'(B3)';BIDI;
    'C1':'(C1)';BIDI;
    'C2':'(C2)';BIDI;
    'C3':'(C3)';BIDI;
    'D1':'(D1)';BIDI;
    'D2':'(D2)';BIDI;
    'D3':'(D3)';BIDI;
end_primitive;
primitive 'CONN14_H54902001_PIP-CONN,H549A';body 'CONN14_H54902001';
    'IO1':'(1)';BIDI;
    'IO10':'(10)';BIDI;
    'IO11':'(11)';BIDI;
    'IO12':'(12)';BIDI;
    'IO13':'(13)';BIDI;
    'IO14':'(14)';BIDI;
    'IO2':'(2)';BIDI;
    'IO3':'(3)';BIDI;
    'IO4':'(4)';BIDI;
    'IO5':'(5)';BIDI;
    'IO6':'(6)';BIDI;
    'IO7':'(7)';BIDI;
    'IO8':'(8)';BIDI;
    'IO9':'(9)';BIDI;
end_primitive;
primitive 'CONN17_H71061002_PIP1-CONN,H71A';body 'CONN17_H71061002';
    'MH2':'(MH2)';
    'MH1':'(MH1)';
    'TRCT3':'(R1)';BIDI;
    'TRD3N':'(R2)';BIDI;
    'TRD3P':'(R3)';BIDI;
    'TRD2P':'(R4)';BIDI;
    'TRD2N':'(R5)';BIDI;
    'TRCT2':'(R6)';BIDI;
    'TRCT4':'(R7)';BIDI;
    'TRD4P':'(R8)';BIDI;
    'TRD4N':'(R9)';BIDI;
    'TRD1N':'(R10)';BIDI;
    'TRD1P':'(R11)';BIDI;
    'TRCT1':'(R12)';BIDI;
    'L3':'(L3)';BIDI;
    'L2':'(L2)';BIDI;
    'L1':'(L1)';BIDI;
    'L5':'(L5)';BIDI;
    'L4':'(L4)';BIDI;
end_primitive;
primitive 'CONN36_G97614001_CP-CONN,G9761A';body 'CONN36_G97614001';
    'GND1':'(A3)';
    'GND10':'(D3)';
    'GND11':'(D6)';
    'GND12':'(D9)';
    'GND2':'(A6)';
    'GND3':'(A9)';
    'GND4':'(B3)';
    'GND5':'(B6)';
    'GND6':'(B9)';
    'GND7':'(C3)';
    'GND8':'(C6)';
    'GND9':'(C9)';
    'RXA0_DN':'(B5)';BIDI;
    'RXA0_DP':'(B4)';BIDI;
    'RXA1_DN':'(A5)';BIDI;
    'RXA1_DP':'(A4)';BIDI;
    'RXA2_DN':'(B8)';BIDI;
    'RXA2_DP':'(B7)';BIDI;
    'RXA3_DN':'(A8)';BIDI;
    'RXA3_DP':'(A7)';BIDI;
    'SIDEBAND0':'(A2)';BIDI;
    'SIDEBAND1':'(B2)';BIDI;
    'SIDEBAND2':'(C2)';BIDI;
    'SIDEBAND3':'(B1)';BIDI;
    'SIDEBAND4':'(C1)';BIDI;
    'SIDEBAND5':'(D1)';BIDI;
    'SIDEBAND6':'(D2)';BIDI;
    'SIDEBAND7':'(A1)';BIDI;
    'TXA0_DN':'(D5)';BIDI;
    'TXA0_DP':'(D4)';BIDI;
    'TXA1_DN':'(C5)';BIDI;
    'TXA1_DP':'(C4)';BIDI;
    'TXA2_DN':'(D8)';BIDI;
    'TXA2_DP':'(D7)';BIDI;
    'TXA3_DN':'(C8)';BIDI;
    'TXA3_DP':'(C7)';BIDI;
end_primitive;
primitive 'CONN3_C95678002_PIP-CONN,C9567A';body 'CONN3_C95678002';
    'IO1':'(1)';
    'IO2':'(2)';
    'IO3':'(3)';
end_primitive;
primitive 'CONN3_G98259001_PIP-CONN,G9825A';body 'CONN3_G98259001';
    'IO1':'(1)';BIDI;
    'IO2':'(2)';BIDI;
    'IO3':'(3)';BIDI;
end_primitive;
primitive 'CONN4_D42317002_PIP-CONN,D4231A';body 'CONN4_D42317002';
    'IO1':'(1)';BIDI;
    'IO2':'(2)';BIDI;
    'IO3':'(3)';BIDI;
    'IO4':'(4)';BIDI;
end_primitive;
primitive 'CONN4_H73295001_PIP-CONN,H7329A';body 'CONN4_H73295001';
    'IO1':'(1)';BIDI;
    'IO2':'(2)';BIDI;
    'IO3':'(3)';BIDI;
    'IO4':'(4)';BIDI;
end_primitive;
primitive 'CONN4_H73295001_PIP-EMPTY,H732A';body 'CONN4_H73295001';
    'IO1':'(1)';BIDI;
    'IO2':'(2)';BIDI;
    'IO3':'(3)';BIDI;
    'IO4':'(4)';BIDI;
end_primitive;
primitive 'CONN6_C74770005_PIP-HDR,C74770A';body 'CONN6_C74770005';
    'IO1':'(1)';
    'IO2':'(2)';
    'IO3':'(3)';
    'IO4':'(4)';
    'IO5':'(5)';
    'IO6':'(6)';
end_primitive;
primitive 'CONN72_G97614002_A_CP-CONN,G97A';body 'CONN72_G97614002_A';
    'GND'<23>:'(1A3)';
    'GND'<22>:'(1A6)';
    'GND'<21>:'(1A9)';
    'GND'<20>:'(1B3)';
    'GND'<19>:'(1B6)';
    'GND'<18>:'(1B9)';
    'GND'<17>:'(1C3)';
    'GND'<16>:'(1C6)';
    'GND'<15>:'(1C9)';
    'GND'<14>:'(1D3)';
    'GND'<13>:'(1D6)';BIDI;
    'GND'<12>:'(1D9)';
    'GND'<11>:'(2A3)';
    'GND'<10>:'(2A6)';
    'GND'<9>:'(2A9)';
    'GND'<8>:'(2B3)';
    'GND'<7>:'(2B6)';
    'GND'<6>:'(2B9)';
    'GND'<5>:'(2C3)';
    'GND'<4>:'(2C6)';
    'GND'<3>:'(2C9)';
    'GND'<2>:'(2D3)';
    'GND'<1>:'(2D6)';BIDI;
    'GND'<0>:'(2D9)';
    'RXA0_DN':'(1B5)';BIDI;
    'RXA0_DP':'(1B4)';BIDI;
    'RXA1_DN':'(1A5)';BIDI;
    'RXA1_DP':'(1A4)';BIDI;
    'RXA2_DN':'(1B8)';BIDI;
    'RXA2_DP':'(1B7)';BIDI;
    'RXA3_DN':'(1A8)';BIDI;
    'RXA3_DP':'(1A7)';BIDI;
    'RXB0_DN':'(2B5)';BIDI;
    'RXB0_DP':'(2B4)';BIDI;
    'RXB1_DN':'(2A5)';BIDI;
    'RXB1_DP':'(2A4)';BIDI;
    'RXB2_DN':'(2B8)';BIDI;
    'RXB2_DP':'(2B7)';BIDI;
    'RXB3_DN':'(2A8)';BIDI;
    'RXB3_DP':'(2A7)';BIDI;
    'SIDEBANDA_0':'(1A2)';BIDI;
    'SIDEBANDA_1':'(1B2)';BIDI;
    'SIDEBANDA_2':'(1C2)';BIDI;
    'SIDEBANDA_3':'(1B1)';BIDI;
    'SIDEBANDA_4':'(1C1)';BIDI;
    'SIDEBANDA_5':'(1D1)';BIDI;
    'SIDEBANDA_6':'(1D2)';BIDI;
    'SIDEBANDA_7':'(1A1)';BIDI;
    'SIDEBANDB_0':'(2A2)';BIDI;
    'SIDEBANDB_1':'(2B2)';BIDI;
    'SIDEBANDB_2':'(2C2)';BIDI;
    'SIDEBANDB_3':'(2B1)';BIDI;
    'SIDEBANDB_4':'(2C1)';BIDI;
    'SIDEBANDB_5':'(2D1)';BIDI;
    'SIDEBANDB_6':'(2D2)';BIDI;
    'SIDEBANDB_7':'(2A1)';BIDI;
    'TXA0_DN':'(1D5)';BIDI;
    'TXA0_DP':'(1D4)';BIDI;
    'TXA1_DN':'(1C5)';BIDI;
    'TXA1_DP':'(1C4)';BIDI;
    'TXA2_DN':'(1D8)';BIDI;
    'TXA2_DP':'(1D7)';BIDI;
    'TXA3_DN':'(1C8)';BIDI;
    'TXA3_DP':'(1C7)';BIDI;
    'TXB0_DN':'(2D5)';BIDI;
    'TXB0_DP':'(2D4)';BIDI;
    'TXB1_DN':'(2C5)';BIDI;
    'TXB1_DP':'(2C4)';BIDI;
    'TXB2_DN':'(2D8)';BIDI;
    'TXB2_DP':'(2D7)';BIDI;
    'TXB3_DN':'(2C8)';BIDI;
    'TXB3_DP':'(2C7)';BIDI;
end_primitive;
primitive 'CONN76_H22707001_THMT1-CONN,H2A';body 'CONN76_H22707001';
    'GNDA2':'(A2)';
    'GNDA4':'(A4)';
    'GNDA6':'(A6)';
    'GNDA8':'(A8)';
    'GNDC1':'(C1)';
    'GNDC3':'(C3)';
    'GNDC5':'(C5)';
    'GNDC7':'(C7)';
    'GNDD2':'(D2)';
    'GNDD4':'(D4)';
    'GNDD6':'(D6)';
    'GNDD8':'(D8)';
    'GNDF1':'(F1)';
    'GNDF3':'(F3)';
    'GNDF5':'(F5)';
    'GNDF7':'(F7)';
    'GNDG2':'(G2)';
    'GNDG4':'(G4)';
    'GNDG6':'(G6)';
    'GNDG8':'(G8)';
    'GNDI1':'(I1)';
    'GNDI3':'(I3)';
    'GNDI5':'(I5)';
    'GNDI7':'(I7)';
    'GNDJ2':'(J2)';
    'GNDJ4':'(J4)';
    'GNDJ6':'(J6)';
    'GNDJ8':'(J8)';
    'IOA1':'(A1)';BIDI;
    'IOA3':'(A3)';BIDI;
    'IOA5':'(A5)';BIDI;
    'IOA7':'(A7)';BIDI;
    'IOB1':'(B1)';BIDI;
    'IOB2':'(B2)';BIDI;
    'IOB3':'(B3)';BIDI;
    'IOB4':'(B4)';BIDI;
    'IOB5':'(B5)';BIDI;
    'IOB6':'(B6)';BIDI;
    'IOB7':'(B7)';BIDI;
    'IOB8':'(B8)';BIDI;
    'IOC2':'(C2)';BIDI;
    'IOC4':'(C4)';BIDI;
    'IOC6':'(C6)';BIDI;
    'IOC8':'(C8)';BIDI;
    'IOD1':'(D1)';BIDI;
    'IOD3':'(D3)';BIDI;
    'IOD5':'(D5)';BIDI;
    'IOD7':'(D7)';BIDI;
    'IOE1':'(E1)';BIDI;
    'IOE2':'(E2)';BIDI;
    'IOE3':'(E3)';BIDI;
    'IOE4':'(E4)';BIDI;
    'IOE5':'(E5)';BIDI;
    'IOE6':'(E6)';BIDI;
    'IOE7':'(E7)';BIDI;
    'IOE8':'(E8)';BIDI;
    'IOF2':'(F2)';BIDI;
    'IOF4':'(F4)';BIDI;
    'IOF6':'(F6)';BIDI;
    'IOF8':'(F8)';BIDI;
    'IOG1':'(G1)';BIDI;
    'IOG3':'(G3)';BIDI;
    'IOG5':'(G5)';BIDI;
    'IOG7':'(G7)';BIDI;
    'IOH1':'(H1)';BIDI;
    'IOH2':'(H2)';BIDI;
    'IOH3':'(H3)';BIDI;
    'IOH4':'(H4)';BIDI;
    'IOH5':'(H5)';BIDI;
    'IOH6':'(H6)';BIDI;
    'IOH7':'(H7)';BIDI;
    'IOH8':'(H8)';BIDI;
    'IOI2':'(I2)';BIDI;
    'IOI4':'(I4)';BIDI;
    'IOI6':'(I6)';BIDI;
    'IOI8':'(I8)';BIDI;
end_primitive;
primitive 'CONN7_E82125014_PIP_TH-CONN,E8A';body 'CONN7_E82125014';
    'GND'<2>:'(1)';BIDI;
    'GND'<1>:'(4)';BIDI;
    'GND'<0>:'(7)';BIDI;
    'MH1':'(MH1)';
    'MH2':'(MH2)';
    'SATA_RXN':'(5)';BIDI;
    'SATA_RXP':'(6)';BIDI;
    'SATA_TXN':'(3)';BIDI;
    'SATA_TXP':'(2)';BIDI;
end_primitive;
primitive 'CONN7_E82125014_PIP_TH-EMPTY,EA';body 'CONN7_E82125014';
    'GND'<2>:'(1)';BIDI;
    'GND'<1>:'(4)';BIDI;
    'GND'<0>:'(7)';BIDI;
    'MH1':'(MH1)';
    'MH2':'(MH2)';
    'SATA_RXN':'(5)';BIDI;
    'SATA_RXP':'(6)';BIDI;
    'SATA_TXN':'(3)';BIDI;
    'SATA_TXP':'(2)';BIDI;
end_primitive;
primitive 'CONN8_C77962004_PIP-CONN,C7796A';body 'CONN8_C77962004';
    'IO1':'(1)';BIDI;
    'IO2':'(2)';BIDI;
    'IO3':'(3)';BIDI;
    'IO4':'(4)';BIDI;
    'IO5':'(5)';BIDI;
    'IO6':'(6)';BIDI;
    'IO7':'(7)';BIDI;
    'IO8':'(8)';BIDI;
end_primitive;
primitive 'CONN8_H62179001_PIP-CONN,H6217A';body 'CONN8_H62179001';
    'IO1':'(1)';BIDI;
    'IO2':'(2)';BIDI;
    'IO3':'(3)';BIDI;
    'IO4':'(4)';BIDI;
    'IO5':'(5)';BIDI;
    'IO6':'(6)';BIDI;
    'IO7':'(7)';BIDI;
    'IO8':'(8)';BIDI;
end_primitive;
primitive 'CONN9_H51826001_PIP2-CONN,H518A';body 'CONN9_H51826001';
    'DN':'(2)';BIDI;
    'DP':'(3)';BIDI;
    'GND':'(4)';
    'GND_DRAIN':'(7)';
    'MH1':'(MH1)';
    'MH2':'(MH2)';
    'MH3':'(MH3)';
    'MH4':'(MH4)';
    'STDA_SSRXN':'(5)';BIDI;
    'STDA_SSRXP':'(6)';BIDI;
    'STDA_SSTXN':'(8)';BIDI;
    'STDA_SSTXP':'(9)';BIDI;
    'VBUS':'(1)';BIDI;
end_primitive;
primitive 'CRYSTAL_2013-25.000MHZ,IC,D717A';body 'CRYSTAL';
    'A':'(1)';
    'B':'(3)';
end_primitive;
primitive 'CRYSTAL_2013-25.000MHZ,IC,H196A';body 'CRYSTAL';
    'A':'(1)';
    'B':'(3)';
end_primitive;
primitive 'CRYSTAL_2013-48.000MHZ,IC,D717A';body 'CRYSTAL';
    'A':'(1)';
    'B':'(3)';
end_primitive;
primitive 'CRYSTAL_2013LF-25.000MHZ,IC,D7B';body 'CRYSTAL';
    'A':'(1)';
    'B':'(3)';
end_primitive;
primitive 'CRYSTAL_SM-24.000MHZ,IC,D95126A';body 'CRYSTAL';
    'A':'(1)';
    'B':'(2)';
end_primitive;
primitive 'CRYSTAL_SM-32.768KHZ,IC,C13544A';body 'CRYSTAL';
    'A':'(1)';
    'B':'(2)';
end_primitive;
primitive 'CSD87384M_SM-IC,H66258-001';body 'CSD87384M';
    'BG':'(4)';IN;
    'PGND':'(3)';
    'TG':'(1)';IN;
    'VIN':'(2)';IN;
    'VSW':'(5)';OUT;
end_primitive;
primitive 'DIODE2A_DUAL_SMLF-BAS70-05,DIOA';body 'DIODE2A_DUAL';
    'C':'(3)';
    'A1':'(1)';
    'A2':'(2)';
end_primitive;
primitive 'DIODEAC_DUAL_ARRAY_SM9-ESD3V3UA';body 'DIODEAC_DUAL_ARRAY';
    'AC0':'(1)';BIDI;
    'AC1':'(2)';BIDI;
    'AC2':'(4)';BIDI;
    'AC3':'(5)';BIDI;
    'GND'<0>:'(3)';
    'OUT0':'(9)';OUT;
    'OUT1':'(8)';OUT;
    'OUT2':'(7)';OUT;
    'OUT3':'(6)';OUT;
end_primitive;
primitive 'DIODE_SM-1N4148W,IC,D89194-001';body 'DIODE';
    'C':'(1)';
    'A':'(2)';
end_primitive;
primitive 'DIODE_SM-MBRS340T3G,EMPTY,C819A';body 'DIODE';
    'C':'(1)';
    'A':'(2)';
end_primitive;
primitive 'DIODE_SM-SDMK0340L,EMPTY,H7179A';body 'DIODE';
    'C':'(1)';
    'A':'(2)';
end_primitive;
primitive 'DIODE_SM-SDMK0340L,IC,H71799-0A';body 'DIODE';
    'C':'(1)';
    'A':'(2)';
end_primitive;
primitive 'DIODE_SMLF-1N5819HW,IC,D55839-A';body 'DIODE';
    'C':'(1)';
    'A':'(2)';
end_primitive;
primitive 'DIODE_SMLF-BAT54WS,IC,C73510-0A';body 'DIODE';
    'C':'(1)';
    'A':'(2)';
end_primitive;
primitive 'FERRITE_SM-120,FB,693286-027';body 'FERRITE';
    'A':'(1)';
    'B':'(2)';
end_primitive;
primitive 'FERRITE_SM-22,FB,656554-051';body 'FERRITE';
    'A':'(1)';
    'B':'(2)';
end_primitive;
primitive 'FERRITE_SMLF-30,FB,693286-021';body 'FERRITE';
    'A':'(1)';
    'B':'(2)';
end_primitive;
primitive 'FERRITE_SMLF-60,FB,693286-001';body 'FERRITE';
    'A':'(1)';
    'B':'(2)';
end_primitive;
primitive 'FERRITE_SMLF-600,FB,656554-043';body 'FERRITE';
    'A':'(1)';
    'B':'(2)';
end_primitive;
primitive 'FET_N_DUAL_SMLF-2N7002DW,FET,DA';body 'FET_N_DUAL';
    'GATE'<0>:'(2,5)';$S;
    'SOURCE'<0>:'(1,4)';$S;
    'DRAIN'<0>:'(6,3)';$S;
end_primitive;
primitive 'FET_N_DUAL_SMLF-NTJD4001N,FET,A';body 'FET_N_DUAL';
    'GATE'<0>:'(2,5)';$S;
    'SOURCE'<0>:'(1,4)';$S;
    'DRAIN'<0>:'(6,3)';$S;
end_primitive;
primitive 'FET_N_SOT23-2N7002,FET,C79254-A';body 'FET_N';
    'GATE':'(1)';
    'SRC':'(2)';
    'DRN':'(3)';
end_primitive;
primitive 'FET_N_SOT23LF-2N7002,FET,C7925A';body 'FET_N';
    'GATE':'(1)';
    'SRC':'(2)';
    'DRN':'(3)';
end_primitive;
primitive 'FSA3357_SM-IC,C63273-001';body 'FSA3357';
    'A':'(7)';BIDI;
    'B0':'(1)';BIDI;
    'B1':'(2)';BIDI;
    'B2':'(3)';BIDI;
    'GND':'(4)';
    'S1':'(6)';IN;
    'S2':'(5)';IN;
    'VCC':'(8)';
end_primitive;
primitive 'FUSE_SM-IC,C94311-016';body 'FUSE';
    'A'<0>:'(1)';
    'B'<0>:'(2)';
end_primitive;
primitive 'FUSE_SMLF-IC,C94311-006';body 'FUSE';
    'A'<0>:'(1)';
    'B'<0>:'(2)';
end_primitive;
primitive 'FUSE_SMT-IC,H45581-001';body 'FUSE';
    'A'<0>:'(1)';
    'B'<0>:'(2)';
end_primitive;
primitive 'GTL2014_SM-IC,D66151-001';body 'GTL2014';
    'A0':'(13)';BIDI;
    'A1':'(12)';BIDI;
    'A2':'(10)';BIDI;
    'A3':'(9)';BIDI;
    'B0':'(2)';BIDI;
    'B1':'(3)';BIDI;
    'B2':'(5)';BIDI;
    'B3':'(6)';BIDI;
    'DIR':'(1)';IN;
    'GND'<2>:'(11)';
    'GND'<1>:'(8)';
    'GND'<0>:'(7)';
    'VCC':'(14)';
    'VREF':'(4)';
end_primitive;
primitive 'H5AN4G6NAFR-TFC-GP_MEMORY-G2-HA';body 'H5AN4G6NAFR-TFC-GP';
    'VPP'<0>:'(B1)';
    'VDD'<0>:'(B3)';
    'VDD'<1>:'(B9)';
    'VDD'<2>:'(D1)';
    'VDD'<3>:'(G7)';
    'VDD'<4>:'(J1)';
    'VDD'<5>:'(J9)';
    'VDD'<6>:'(L1)';
    'VDD'<7>:'(L9)';
    'VDD'<8>:'(R1)';
    'VDD'<9>:'(T9)';
    'VDDQ'<0>:'(A1)';
    'VDDQ'<1>:'(A9)';
    'VDDQ'<2>:'(C1)';
    'VDDQ'<3>:'(D9)';
    'VDDQ'<4>:'(F2)';
    'VDDQ'<5>:'(F8)';
    'VDDQ'<6>:'(G1)';
    'VDDQ'<7>:'(G9)';
    'VDDQ'<8>:'(J2)';
    'VDDQ'<9>:'(J8)';
    'DQU4':'(C2)';
    'DQU5':'(C8)';
    'DQU6':'(D3)';
    'DQU7':'(D7)';
    'DQU0':'(A3)';
    'DQU1':'(B8)';
    'DQU2':'(C3)';
    'DQU3':'(C7)';
    'DQL1':'(F7)';
    'DQL0':'(G2)';
    'DQL4':'(H2)';
    'DQL2':'(H3)';
    'DQL3':'(H7)';
    'DQL5':'(H8)';
    'DQL6':'(J3)';
    'DQL7':'(J7)';
    'A0':'(P3)';IN;
    'A1':'(P7)';IN;
    'A2':'(R3)';IN;
    'A3':'(N7)';IN;
    'A4':'(N3)';IN;
    'A5':'(P8)';IN;
    'A6':'(P2)';IN;
    'A7':'(R8)';IN;
    'A8':'(R2)';IN;
    'A9':'(R7)';IN;
    'A10/AP':'(M3)';IN;
    'A11':'(T2)';IN;
    'A12/BC#':'(M7)';IN;
    'A13':'(T8)';IN;
    'WE#/A14':'(L2)';IN;
    'CAS#/A15':'(M8)';IN;
    'RAS#/A16':'(L8)';IN;
    'VREFCA':'(M1)';
    'ZQ':'(F9)';
    'CKE':'(K2)';IN;
    'ODT':'(K3)';IN;
    'BG0':'(M2)';IN;
    'TEN':'(N9)';IN;
    'PAR':'(T3)';IN;
    'NC#T7':'(T7)';
    'CK_T':'(K7)';IN;
    'CK_C':'(K8)';IN;
    'VPP'<1>:'(R9)';
    'ACT#':'(L3)';IN;
    'CS#':'(L7)';IN;
    'RESET#':'(P1)';IN;
    'ALERT#':'(P9)';OUT;
    'VSS'<0>:'(B2)';
    'VSS'<1>:'(E1)';
    'VSS'<2>:'(E9)';
    'VSS'<3>:'(G8)';
    'VSS'<4>:'(K1)';
    'VSS'<5>:'(K9)';
    'VSS'<6>:'(M9)';
    'VSS'<7>:'(N1)';
    'VSS'<8>:'(T1)';
    'VSSQ'<0>:'(A2)';
    'VSSQ'<1>:'(A8)';
    'VSSQ'<2>:'(C9)';
    'VSSQ'<3>:'(D2)';
    'VSSQ'<4>:'(D8)';
    'VSSQ'<5>:'(E3)';
    'VSSQ'<6>:'(E8)';
    'VSSQ'<7>:'(F1)';
    'VSSQ'<8>:'(H1)';
    'VSSQ'<9>:'(H9)';
    'DQSU_C':'(A7)';BIDI;
    'DQSU_T':'(B7)';BIDI;
    'DQSL_C':'(F3)';BIDI;
    'DQSL_T':'(G3)';BIDI;
    'DMU#/DBIU#':'(E2)';BIDI;
    'DML#/DBIL#':'(E7)';BIDI;
    'BA0':'(N2)';IN;
    'BA1':'(N8)';IN;
end_primitive;
primitive 'HCB1608KF-800T30-GP_DISCRET-G9A';body 'HCB1608KF-800T30-GP';
    '1':'(1)';
    '2':'(2)';
end_primitive;
primitive 'ICS9FGP204_MLFP-IC,E95226-001';body 'ICS9FGP204';
    'VDD32K':'(12)';
    '32KHZ':'(13)';OUT;
    'GND32K':'(14)';
    '25MHZ_0':'(16)';OUT;
    '25MHZ_1':'(17)';OUT;
    'RMII'<1>:'(32)';OUT;
    'RMII'<2>:'(29)';OUT;
    'RMII'<5>:'(24)';OUT;
    'RMII'<4>:'(25)';OUT;
    'RMII'<3>:'(28)';OUT;
    'RMII'<0>:'(33)';OUT;
    'GND'<1>:'(41)';
    'GND33':'(21)';
    'GND'<0>:'(1)';
    'DOT96SSC':'(4)';OUT;
    'DOT96SST':'(3)';OUT;
    'CPUCLKC0':'(8)';OUT;
    'GNDREF':'(18)';
    'CPUCLKT0':'(7)';OUT;
    'VDDREF':'(15)';
    'IREF':'(11)';OUT;
    'X1_25':'(19)';IN;
    'GNDRMII'<0>:'(27)';
    'VDDRMII'<0>:'(26)';
    'VDDRMII'<1>:'(31)';
    'GNDRMII'<1>:'(30)';
    '33MHZ_SMBADR':'(22)';BIDI;
    'VDD33':'(23)';
    'OE_96':'(5)';IN;
    'VDD96':'(2)';
    'OE_CPU':'(6)';IN;
    'GNDCPU':'(10)';
    'VDDCPU':'(9)';
    'VTTPWR_GD_PD_N':'(40)';IN;
    'SMBCLK':'(38)';IN;
    'X2_25':'(20)';OUT;
    'SMBDAT':'(39)';BIDI;
    'VDD_RGMII':'(34)';IN;
    'GND_RGMII':'(35)';
    'RGMII'<0>:'(37)';OUT;
    'RGMII'<1>:'(36)';OUT;
end_primitive;
primitive 'INDUCTOR_SM-0.12UH,IND,D92183-A';body 'INDUCTOR';
    'INA':'(1)';
    'INB':'(2)';
end_primitive;
primitive 'INDUCTOR_SM-0.3UH,IND,D92183-0A';body 'INDUCTOR';
    'INA':'(1)';
    'INB':'(2)';
end_primitive;
primitive 'INDUCTOR_SM-0.47UH,IND,E13358-A';body 'INDUCTOR';
    'INA':'(1)';
    'INB':'(2)';
end_primitive;
primitive 'INDUCTOR_SM-1.00UH,IND,E98679-A';body 'INDUCTOR';
    'INA':'(1)';
    'INB':'(2)';
end_primitive;
primitive 'INDUCTOR_SM-100NH,IND,D92183-0A';body 'INDUCTOR';
    'INA':'(1)';
    'INB':'(2)';
end_primitive;
primitive 'INDUCTOR_SM-100NH,IND,D92183-0B';body 'INDUCTOR';
    'INA':'(1)';
    'INB':'(2)';
end_primitive;
primitive 'INDUCTOR_SM-150NH,IND,D92183-0A';body 'INDUCTOR';
    'INA':'(1)';
    'INB':'(2)';
end_primitive;
primitive 'INDUCTOR_SM-2.2UH,IND,E98761-0A';body 'INDUCTOR';
    'INA':'(1)';
    'INB':'(2)';
end_primitive;
primitive 'INDUCTOR_SMT-0.022UH,IND,72189A';body 'INDUCTOR';
    'INA':'(1)';
    'INB':'(2)';
end_primitive;
primitive 'IR354XX_SM-IR35411,IC,H73688-0A';body 'IR354XX';
    'BOOST':'(33)';BIDI;
    'EN':'(35)';BIDI;
    'GL'<1>:'(41)';BIDI;
    'GL'<0>:'(6)';BIDI;
    'IOUT':'(38)';OUT;
    'LGND':'(2)';
    'NC':'(31)';
    'OCSET':'(37)';BIDI;
    'PGND'<2>:'(40)';
    'PGND'<1>:'(7)';
    'PGND'<0>:'(5)';
    'PHASE':'(32)';BIDI;
    'PWM':'(34)';IN;
    'REFIN':'(39)';IN;
    'SW':'(10)';BIDI;
    'TOUT_FLT':'(36)';BIDI;
    'VCC':'(3)';
    'VDRV':'(4)';BIDI;
    'VIN'<1>:'(30)';
    'VIN'<0>:'(25)';
    'VOS':'(1)';BIDI;
end_primitive;
primitive 'IR354XX_SM-IR35412,IC,H73684-0A';body 'IR354XX';
    'BOOST':'(33)';BIDI;
    'EN':'(35)';BIDI;
    'GL'<1>:'(41)';BIDI;
    'GL'<0>:'(6)';BIDI;
    'IOUT':'(38)';OUT;
    'LGND':'(2)';
    'NC':'(31)';
    'OCSET':'(37)';BIDI;
    'PGND'<2>:'(40)';
    'PGND'<1>:'(7)';
    'PGND'<0>:'(5)';
    'PHASE':'(32)';BIDI;
    'PWM':'(34)';IN;
    'REFIN':'(39)';IN;
    'SW':'(10)';BIDI;
    'TOUT_FLT':'(36)';BIDI;
    'VCC':'(3)';
    'VDRV':'(4)';BIDI;
    'VIN'<1>:'(30)';
    'VIN'<0>:'(25)';
    'VOS':'(1)';BIDI;
end_primitive;
primitive 'LBG_CORE_QAT_EXT_D_BGA1-IC,H91A';body 'LBG_CORE_QAT_EXT_D';
    'CGC_DUT_DETECT_N':'(0,0,0,0,0,0,0,C70,0,0,0,0,0,0)';$S;BIDI;
    'CLKOUT_ITPXDPN':'(A39,0,0,0,0,0,0,0,0,0,0,0,0,0)';$S;BIDI;
    'CLKOUT_ITPXDPP':'(C39,0,0,0,0,0,0,0,0,0,0,0,0,0)';$S;BIDI;
    'CLKOUT_NSSCCAP0N':'(A32,0,0,0,0,0,0,0,0,0,0,0,0,0)';$S;BIDI;
    'CLKOUT_NSSCCAP0P':'(C32,0,0,0,0,0,0,0,0,0,0,0,0,0)';$S;BIDI;
    'CLKOUT_NSSCCAP1N':'(B38,0,0,0,0,0,0,0,0,0,0,0,0,0)';$S;BIDI;
    'CLKOUT_NSSCCAP1P':'(D38,0,0,0,0,0,0,0,0,0,0,0,0,0)';$S;BIDI;
    'CLKOUT_PLAT0N':'(B29,0,0,0,0,0,0,0,0,0,0,0,0,0)';$S;BIDI;
    'CLKOUT_PLAT0P':'(D29,0,0,0,0,0,0,0,0,0,0,0,0,0)';$S;BIDI;
    'CLKOUT_PLAT1N':'(B40,0,0,0,0,0,0,0,0,0,0,0,0,0)';$S;BIDI;
    'CLKOUT_PLAT1P':'(D40,0,0,0,0,0,0,0,0,0,0,0,0,0)';$S;BIDI;
    'CLKOUT_SRCN'<15>:'(K27,0,0,0,0,0,0,0,0,0,0,0,0,0)';BIDI;
    'CLKOUT_SRCN'<14>:'(C20,0,0,0,0,0,0,0,0,0,0,0,0,0)';BIDI;
    'CLKOUT_SRCN'<13>:'(C24,0,0,0,0,0,0,0,0,0,0,0,0,0)';BIDI;
    'CLKOUT_SRCN'<12>:'(K24,0,0,0,0,0,0,0,0,0,0,0,0,0)';BIDI;
    'CLKOUT_SRCN'<11>:'(B21,0,0,0,0,0,0,0,0,0,0,0,0,0)';BIDI;
    'CLKOUT_SRCN'<10>:'(B23,0,0,0,0,0,0,0,0,0,0,0,0,0)';BIDI;
    'CLKOUT_SRCN'<9>:'(J26,0,0,0,0,0,0,0,0,0,0,0,0,0)';BIDI;
    'CLKOUT_SRCN'<8>:'(D31,0,0,0,0,0,0,0,0,0,0,0,0,0)';BIDI;
    'CLKOUT_SRCN'<7>:'(H31,0,0,0,0,0,0,0,0,0,0,0,0,0)';BIDI;
    'CLKOUT_SRCN'<6>:'(D33,0,0,0,0,0,0,0,0,0,0,0,0,0)';BIDI;
    'CLKOUT_SRCN'<5>:'(J40,0,0,0,0,0,0,0,0,0,0,0,0,0)';BIDI;
    'CLKOUT_SRCN'<4>:'(A28,0,0,0,0,0,0,0,0,0,0,0,0,0)';BIDI;
    'CLKOUT_SRCN'<3>:'(K42,0,0,0,0,0,0,0,0,0,0,0,0,0)';BIDI;
    'CLKOUT_SRCN'<2>:'(J33,0,0,0,0,0,0,0,0,0,0,0,0,0)';BIDI;
    'CLKOUT_SRCN'<1>:'(K35,0,0,0,0,0,0,0,0,0,0,0,0,0)';BIDI;
    'CLKOUT_SRCN'<0>:'(K38,0,0,0,0,0,0,0,0,0,0,0,0,0)';BIDI;
    'CLKOUT_SRCP'<15>:'(H27,0,0,0,0,0,0,0,0,0,0,0,0,0)';BIDI;
    'CLKOUT_SRCP'<14>:'(A20,0,0,0,0,0,0,0,0,0,0,0,0,0)';BIDI;
    'CLKOUT_SRCP'<13>:'(A24,0,0,0,0,0,0,0,0,0,0,0,0,0)';BIDI;
    'CLKOUT_SRCP'<12>:'(H24,0,0,0,0,0,0,0,0,0,0,0,0,0)';BIDI;
    'CLKOUT_SRCP'<11>:'(D21,0,0,0,0,0,0,0,0,0,0,0,0,0)';BIDI;
    'CLKOUT_SRCP'<10>:'(D23,0,0,0,0,0,0,0,0,0,0,0,0,0)';BIDI;
    'CLKOUT_SRCP'<9>:'(G26,0,0,0,0,0,0,0,0,0,0,0,0,0)';BIDI;
    'CLKOUT_SRCP'<8>:'(B31,0,0,0,0,0,0,0,0,0,0,0,0,0)';BIDI;
    'CLKOUT_SRCP'<7>:'(K31,0,0,0,0,0,0,0,0,0,0,0,0,0)';BIDI;
    'CLKOUT_SRCP'<6>:'(B33,0,0,0,0,0,0,0,0,0,0,0,0,0)';BIDI;
    'CLKOUT_SRCP'<5>:'(G40,0,0,0,0,0,0,0,0,0,0,0,0,0)';BIDI;
    'CLKOUT_SRCP'<4>:'(C28,0,0,0,0,0,0,0,0,0,0,0,0,0)';BIDI;
    'CLKOUT_SRCP'<3>:'(H42,0,0,0,0,0,0,0,0,0,0,0,0,0)';BIDI;
    'CLKOUT_SRCP'<2>:'(G33,0,0,0,0,0,0,0,0,0,0,0,0,0)';BIDI;
    'CLKOUT_SRCP'<1>:'(H35,0,0,0,0,0,0,0,0,0,0,0,0,0)';BIDI;
    'CLKOUT_SRCP'<0>:'(H38,0,0,0,0,0,0,0,0,0,0,0,0,0)';BIDI;
    'CLOCKSE_BMCCLK':'(BW50,0,0,0,0,0,0,0,0,0,0,0,0,0)';$S;BIDI;
    'CLOCKSE_PMSYNCCLK1':'(BY51,0,0,0,0,0,0,0,0,0,0,0,0,0)';$S;BIDI;
    'CLOCKSE_PMSYNCCLK2':'(BV51,0,0,0,0,0,0,0,0,0,0,0,0,0)';$S;BIDI;
    'CPU_TRST_N':'(0,0,0,0,AT56,0,0,0,0,0,0,0,0,0)';$S;BIDI;
    'DMI_RXN'<3>:'(0,0,0,C45,0,0,0,0,0,0,0,0,0,0)';BIDI;
    'DMI_RXN'<2>:'(0,0,0,D44,0,0,0,0,0,0,0,0,0,0)';BIDI;
    'DMI_RXN'<1>:'(0,0,0,C43,0,0,0,0,0,0,0,0,0,0)';BIDI;
    'DMI_RXN'<0>:'(0,0,0,D42,0,0,0,0,0,0,0,0,0,0)';BIDI;
    'DMI_RXP'<3>:'(0,0,0,A45,0,0,0,0,0,0,0,0,0,0)';BIDI;
    'DMI_RXP'<2>:'(0,0,0,B44,0,0,0,0,0,0,0,0,0,0)';BIDI;
    'DMI_RXP'<1>:'(0,0,0,A43,0,0,0,0,0,0,0,0,0,0)';BIDI;
    'DMI_RXP'<0>:'(0,0,0,B42,0,0,0,0,0,0,0,0,0,0)';BIDI;
    'DMI_TXN'<3>:'(0,0,0,P52,0,0,0,0,0,0,0,0,0,0)';BIDI;
    'DMI_TXN'<2>:'(0,0,0,K50,0,0,0,0,0,0,0,0,0,0)';BIDI;
    'DMI_TXN'<1>:'(0,0,0,J48,0,0,0,0,0,0,0,0,0,0)';BIDI;
    'DMI_TXN'<0>:'(0,0,0,H46,0,0,0,0,0,0,0,0,0,0)';BIDI;
    'DMI_TXP'<3>:'(0,0,0,N54,0,0,0,0,0,0,0,0,0,0)';BIDI;
    'DMI_TXP'<2>:'(0,0,0,M52,0,0,0,0,0,0,0,0,0,0)';BIDI;
    'DMI_TXP'<1>:'(0,0,0,H50,0,0,0,0,0,0,0,0,0,0)';BIDI;
    'DMI_TXP'<0>:'(0,0,0,K46,0,0,0,0,0,0,0,0,0,0)';BIDI;
    'DSW_PWROK':'(0,0,0,0,K13,0,0,0,0,0,0,0,0,0)';$S;BIDI;
    'EXTCLKN':'(0,0,D66,0,0,0,0,0,0,0,0,0,0,0)';$S;BIDI;
    'EXTCLKP':'(0,0,E67,0,0,0,0,0,0,0,0,0,0,0)';$S;BIDI;
    'GPD0':'(0,0,0,0,G15,0,0,0,0,0,0,0,0,0)';$S;BIDI;
    'GPD10_SLP_S5_N':'(0,0,0,0,B14,0,0,0,0,0,0,0,0,0)';$S;BIDI;
    'GPD11_GBEPHY':'(0,0,0,0,A13,0,0,0,0,0,0,0,0,0)';$S;BIDI;
    'GPD1_ACPRESENT':'(0,0,0,0,H13,0,0,0,0,0,0,0,0,0)';$S;BIDI;
    'GPD2_GBE_WAKE_N':'(0,0,0,0,M11,0,0,0,0,0,0,0,0,0)';$S;BIDI;
    'GPD3_PWRBTN_N':'(0,0,0,0,C15,0,0,0,0,0,0,0,0,0)';$S;BIDI;
    'GPD4_SLP_S3_N':'(0,0,0,0,D14,0,0,0,0,0,0,0,0,0)';$S;BIDI;
    'GPD5_SLP_S4_N':'(0,0,0,0,B16,0,0,0,0,0,0,0,0,0)';$S;BIDI;
    'GPD6_SLP_A_N':'(0,0,0,0,G11,0,0,0,0,0,0,0,0,0)';$S;BIDI;
    'GPD7':'(0,0,0,0,H9,0,0,0,0,0,0,0,0,0)';$S;BIDI;
    'GPD8_SUSCLK':'(0,0,0,0,C13,0,0,0,0,0,0,0,0,0)';$S;BIDI;
    'GPD9':'(0,0,0,0,A15,0,0,0,0,0,0,0,0,0)';$S;BIDI;
    'GPIO_RCOMP_1P8_3P3':'(0,0,0,0,0,0,0,AM4,0,0,0,0,0,0)';$S;BIDI;
    'GPIO_RCOMP_3P3':'(0,0,0,0,0,0,BY25,0,0,0,0,0,0,0)';$S;BIDI;
    'GPP_A0_RCIN_N_ESPI_ALERT1_N':'(0,0,0,0,0,N3,0,0,0,0,0,0,0,0)';$S;BIDI;
    'GPP_A10_CLKOUT_LPC1':'(0,0,0,0,0,AA4,0,0,0,0,0,0,0,0)';$S;BIDI;
    'GPP_A11_PME_N':'(0,0,0,0,0,AC2,0,0,0,0,0,0,0,0)';$S;BIDI;
    'GPP_A12_BMBUSY_N_SXEXITHLDOFF_N':'(0,0,0,0,0,R1,0,0,0,0,0,0,0,0)';$S;BIDI;
    'GPP_A13_SUSWARN_N_SUSPWRDNACK':'(0,0,0,0,0,T4,0,0,0,0,0,0,0,0)';$S;BIDI;
    'GPP_A14_ESPI_RESET_N':'(0,0,0,0,0,AB3,0,0,0,0,0,0,0,0)';$S;BIDI;
    'GPP_A15_SUSACK_N':'(0,0,0,0,0,AC4,0,0,0,0,0,0,0,0)';$S;BIDI;
    'GPP_A16_CLKOUT_LPC2':'(0,0,0,0,0,T2,0,0,0,0,0,0,0,0)';$S;BIDI;
    'GPP_A17':'(0,0,0,0,0,AD1,0,0,0,0,0,0,0,0)';$S;BIDI;
    'GPP_A18':'(0,0,0,0,0,AD3,0,0,0,0,0,0,0,0)';$S;BIDI;
    'GPP_A19':'(0,0,0,0,0,V3,0,0,0,0,0,0,0,0)';$S;BIDI;
    'GPP_A1_LAD0_ESPI_IO0':'(0,0,0,0,0,Y3,0,0,0,0,0,0,0,0)';$S;BIDI;
    'GPP_A20':'(0,0,0,0,0,W4,0,0,0,0,0,0,0,0)';$S;BIDI;
    'GPP_A21':'(0,0,0,0,0,AE2,0,0,0,0,0,0,0,0)';$S;BIDI;
    'GPP_A22':'(0,0,0,0,0,AE4,0,0,0,0,0,0,0,0)';$S;BIDI;
    'GPP_A23':'(0,0,0,0,0,V1,0,0,0,0,0,0,0,0)';$S;BIDI;
    'GPP_A2_LAD1_ESPI_IO1':'(0,0,0,0,0,N1,0,0,0,0,0,0,0,0)';$S;BIDI;
    'GPP_A3_LAD2_ESPI_IO2':'(0,0,0,0,0,W2,0,0,0,0,0,0,0,0)';$S;BIDI;
    'GPP_A4_LAD3_ESPI_IO3':'(0,0,0,0,0,Y1,0,0,0,0,0,0,0,0)';$S;BIDI;
    'GPP_A5_LFRAME_N_ESPI_CS0_N':'(0,0,0,0,0,P4,0,0,0,0,0,0,0,0)';$S;BIDI;
    'GPP_A6_SERIRQ_ESPI_CS1_N':'(0,0,0,0,0,P2,0,0,0,0,0,0,0,0)';$S;BIDI;
    'GPP_A7_PIRQA_N_ESPI_ALERT0_N':'(0,0,0,0,0,AA2,0,0,0,0,0,0,0,0)';$S;BIDI;
    'GPP_A8_CLKRUN_N':'(0,0,0,0,0,AB1,0,0,0,0,0,0,0,0)';$S;BIDI;
    'GPP_A9_CLKOUT_LPC0_ESPI_CLK':'(0,0,0,0,0,R3,0,0,0,0,0,0,0,0)';$S;BIDI;
    'GPP_B0_CORE_VID0':'(0,0,0,0,0,BL7,0,0,0,0,0,0,0,0)';$S;BIDI;
    'GPP_B10_SRCCLKREQ5_N':'(0,0,0,0,0,BL11,0,0,0,0,0,0,0,0)';$S;BIDI;
    'GPP_B11':'(0,0,0,0,0,BK9,0,0,0,0,0,0,0,0)';$S;BIDI;
    'GPP_B12_GLB_RST_WARN_N':'(0,0,0,0,0,BL18,0,0,0,0,0,0,0,0)';$S;BIDI;
    'GPP_B13_PLTRST_N':'(0,0,0,0,0,BN18,0,0,0,0,0,0,0,0)';$S;BIDI;
    'GPP_B14_SPKR':'(0,0,0,0,0,BH13,0,0,0,0,0,0,0,0)';$S;BIDI;
    'GPP_B15':'(0,0,0,0,0,BK13,0,0,0,0,0,0,0,0)';$S;BIDI;
    'GPP_B16':'(0,0,0,0,0,BG22,0,0,0,0,0,0,0,0)';$S;BIDI;
    'GPP_B17':'(0,0,0,0,0,BG15,0,0,0,0,0,0,0,0)';$S;BIDI;
    'GPP_B18':'(0,0,0,0,0,BL15,0,0,0,0,0,0,0,0)';$S;BIDI;
    'GPP_B19':'(0,0,0,0,0,BK20,0,0,0,0,0,0,0,0)';$S;BIDI;
    'GPP_B1_CORE_VID1':'(0,0,0,0,0,BH9,0,0,0,0,0,0,0,0)';$S;BIDI;
    'GPP_B2':'(0,0,0,0,0,BN15,0,0,0,0,0,0,0,0)';$S;BIDI;
    'GPP_B20':'(0,0,0,0,0,BJ22,0,0,0,0,0,0,0,0)';$S;BIDI;
    'GPP_B21':'(0,0,0,0,0,BH17,0,0,0,0,0,0,0,0)';$S;BIDI;
    'GPP_B22':'(0,0,0,0,0,BR17,0,0,0,0,0,0,0,0)';$S;BIDI;
    'GPP_B23_MEIE_SML1ALRT_N_PHOT_N':'(0,0,0,0,0,BM20,0,0,0,0,0,0,0,0)';$S;BIDI;~

    'GPP_B3_CPU_GP2':'(0,0,0,0,0,BR9,0,0,0,0,0,0,0,0)';$S;BIDI;
    'GPP_B4_CPU_GP3':'(0,0,0,0,0,BN7,0,0,0,0,0,0,0,0)';$S;BIDI;
    'GPP_B5_SRCCLKREQ0_N':'(0,0,0,0,0,BK17,0,0,0,0,0,0,0,0)';$S;BIDI;
    'GPP_B6_SRCCLKREQ1_N':'(0,0,0,0,0,BG18,0,0,0,0,0,0,0,0)';$S;BIDI;
    'GPP_B7_SRCCLKREQ2_N':'(0,0,0,0,0,BR13,0,0,0,0,0,0,0,0)';$S;BIDI;
    'GPP_B8_SRCCLKREQ3_N':'(0,0,0,0,0,BN11,0,0,0,0,0,0,0,0)';$S;BIDI;
    'GPP_B9_SRCCLKREQ4_N':'(0,0,0,0,0,BH20,0,0,0,0,0,0,0,0)';$S;BIDI;
    'GPP_C0_SMBCLK':'(0,0,0,0,0,BW28,0,0,0,0,0,0,0,0)';$S;BIDI;
    'GPP_C10':'(0,0,0,0,0,BV31,0,0,0,0,0,0,0,0)';$S;BIDI;
    'GPP_C11':'(0,0,0,0,0,BV33,0,0,0,0,0,0,0,0)';$S;BIDI;
    'GPP_C12':'(0,0,0,0,0,CA30,0,0,0,0,0,0,0,0)';$S;BIDI;
    'GPP_C13':'(0,0,0,0,0,BV38,0,0,0,0,0,0,0,0)';$S;BIDI;
    'GPP_C14':'(0,0,0,0,0,BY38,0,0,0,0,0,0,0,0)';$S;BIDI;
    'GPP_C15':'(0,0,0,0,0,CA32,0,0,0,0,0,0,0,0)';$S;BIDI;
    'GPP_C16':'(0,0,0,0,0,BW37,0,0,0,0,0,0,0,0)';$S;BIDI;
    'GPP_C17':'(0,0,0,0,0,BY31,0,0,0,0,0,0,0,0)';$S;BIDI;
    'GPP_C18':'(0,0,0,0,0,BY35,0,0,0,0,0,0,0,0)';$S;BIDI;
    'GPP_C19':'(0,0,0,0,0,BW39,0,0,0,0,0,0,0,0)';$S;BIDI;
    'GPP_C1_SMBDATA':'(0,0,0,0,0,BV27,0,0,0,0,0,0,0,0)';$S;BIDI;
    'GPP_C20':'(0,0,0,0,0,CA39,0,0,0,0,0,0,0,0)';$S;BIDI;
    'GPP_C21':'(0,0,0,0,0,BY33,0,0,0,0,0,0,0,0)';$S;BIDI;
    'GPP_C22':'(0,0,0,0,0,CA34,0,0,0,0,0,0,0,0)';$S;BIDI;
    'GPP_C23':'(0,0,0,0,0,CA37,0,0,0,0,0,0,0,0)';$S;BIDI;
    'GPP_C2_SMBALERT_N':'(0,0,0,0,0,BY27,0,0,0,0,0,0,0,0)';$S;BIDI;
    'GPP_C3_SML0CLK_IE':'(0,0,0,0,0,BV29,0,0,0,0,0,0,0,0)';$S;BIDI;
    'GPP_C4_SML0DATA_IE':'(0,0,0,0,0,BW30,0,0,0,0,0,0,0,0)';$S;BIDI;
    'GPP_C5_SML0ALERT_IE_N':'(0,0,0,0,0,BW34,0,0,0,0,0,0,0,0)';$S;BIDI;
    'GPP_C6_SML1CLK_IE':'(0,0,0,0,0,CA28,0,0,0,0,0,0,0,0)';$S;BIDI;
    'GPP_C7_SML1DATA_IE':'(0,0,0,0,0,BV35,0,0,0,0,0,0,0,0)';$S;BIDI;
    'GPP_C8':'(0,0,0,0,0,BW32,0,0,0,0,0,0,0,0)';$S;BIDI;
    'GPP_C9':'(0,0,0,0,0,BY29,0,0,0,0,0,0,0,0)';$S;BIDI;
    'GPP_D0':'(0,0,0,0,0,BR42,0,0,0,0,0,0,0,0)';$S;BIDI;
    'GPP_D1':'(0,0,0,0,0,BK46,0,0,0,0,0,0,0,0)';$S;BIDI;
    'GPP_D10_SSATA_DEVSLP4':'(0,0,0,0,0,BV47,0,0,0,0,0,0,0,0)';$S;BIDI;
    'GPP_D11_SSATA_DEVSLP5':'(0,0,0,0,0,BY47,0,0,0,0,0,0,0,0)';$S;BIDI;
    'GPP_D12_SSATA_SDATAOUT1':'(0,0,0,0,0,BN40,0,0,0,0,0,0,0,0)';$S;BIDI;
    'GPP_D13_SML0BCLK_IE':'(0,0,0,0,0,BY44,0,0,0,0,0,0,0,0)';$S;BIDI;
    'GPP_D14_SML0BDATA_IE':'(0,0,0,0,0,BL44,0,0,0,0,0,0,0,0)';$S;BIDI;
    'GPP_D15_SSATA_SDATAOUT0':'(0,0,0,0,0,BW43,0,0,0,0,0,0,0,0)';$S;BIDI;
    'GPP_D16_SML0BALERT_IE_N':'(0,0,0,0,0,BV42,0,0,0,0,0,0,0,0)';$S;BIDI;
    'GPP_D17':'(0,0,0,0,0,BW48,0,0,0,0,0,0,0,0)';$S;BIDI;
    'GPP_D18':'(0,0,0,0,0,CA41,0,0,0,0,0,0,0,0)';$S;BIDI;
    'GPP_D19':'(0,0,0,0,0,CA43,0,0,0,0,0,0,0,0)';$S;BIDI;
    'GPP_D2':'(0,0,0,0,0,BJ44,0,0,0,0,0,0,0,0)';$S;BIDI;
    'GPP_D20':'(0,0,0,0,0,CA48,0,0,0,0,0,0,0,0)';$S;BIDI;
    'GPP_D21_IE_UART_RX':'(0,0,0,0,0,BV44,0,0,0,0,0,0,0,0)';$S;BIDI;
    'GPP_D22_IE_UART_TX':'(0,0,0,0,0,BR46,0,0,0,0,0,0,0,0)';$S;BIDI;
    'GPP_D23':'(0,0,0,0,0,BN44,0,0,0,0,0,0,0,0)';$S;BIDI;
    'GPP_D3':'(0,0,0,0,0,BW45,0,0,0,0,0,0,0,0)';$S;BIDI;
    'GPP_D4':'(0,0,0,0,0,BM42,0,0,0,0,0,0,0,0)';$S;BIDI;
    'GPP_D5':'(0,0,0,0,0,BM38,0,0,0,0,0,0,0,0)';$S;BIDI;
    'GPP_D6':'(0,0,0,0,0,BW41,0,0,0,0,0,0,0,0)';$S;BIDI;
    'GPP_D7':'(0,0,0,0,0,CA45,0,0,0,0,0,0,0,0)';$S;BIDI;
    'GPP_D8':'(0,0,0,0,0,BR38,0,0,0,0,0,0,0,0)';$S;BIDI;
    'GPP_D9_SSATA_DEVSLP3':'(0,0,0,0,0,BY42,0,0,0,0,0,0,0,0)';$S;BIDI;
    'GPP_E0_SATAXPCIE0_SATAGP0':'(0,0,0,0,0,0,BH50,0,0,0,0,0,0,0)';$S;BIDI;
    'GPP_E10_USB2_OC1_N':'(0,0,0,0,0,0,BN48,0,0,0,0,0,0,0)';$S;BIDI;
    'GPP_E11_USB2_OC2_N':'(0,0,0,0,0,0,AW54,0,0,0,0,0,0,0)';$S;BIDI;
    'GPP_E12_USB2_OC3_N':'(0,0,0,0,0,0,AU58,0,0,0,0,0,0,0)';$S;BIDI;
    'GPP_E1_SATAXPCIE1_SATAGP1':'(0,0,0,0,0,0,AY52,0,0,0,0,0,0,0)';$S;BIDI;
    'GPP_E2_SATAXPCIE2_SATAGP2':'(0,0,0,0,0,0,BG52,0,0,0,0,0,0,0)';$S;BIDI;
    'GPP_E3_CPU_GP0':'(0,0,0,0,0,0,BE52,0,0,0,0,0,0,0)';$S;BIDI;
    'GPP_E4_SATA_DEVSLP0':'(0,0,0,0,0,0,AV52,0,0,0,0,0,0,0)';$S;BIDI;
    'GPP_E5_SATA_DEVSLP1':'(0,0,0,0,0,0,AT52,0,0,0,0,0,0,0)';$S;BIDI;
    'GPP_E6_SATA_DEVSLP2':'(0,0,0,0,0,0,BB52,0,0,0,0,0,0,0)';$S;BIDI;
    'GPP_E7_CPU_GP1':'(0,0,0,0,0,0,BJ48,0,0,0,0,0,0,0)';$S;BIDI;
    'GPP_E8_SATA_LED_N':'(0,0,0,0,0,0,AV56,0,0,0,0,0,0,0)';$S;BIDI;
    'GPP_E9_USB2_OC0_N':'(0,0,0,0,0,0,BL48,0,0,0,0,0,0,0)';$S;BIDI;
    'GPP_F0_SATAXPCIE3_SATAGP3':'(0,0,0,0,0,0,AG7,0,0,0,0,0,0,0)';$S;BIDI;
    'GPP_F10_SATA_SCLOCK':'(0,0,0,0,0,0,AL7,0,0,0,0,0,0,0)';$S;BIDI;
    'GPP_F11_SATA_SLOAD':'(0,0,0,0,0,0,AR9,0,0,0,0,0,0,0)';$S;BIDI;
    'GPP_F12_SATA_SDATAOUT1':'(0,0,0,0,0,0,AP7,0,0,0,0,0,0,0)';$S;BIDI;
    'GPP_F13_SATA_SDATAOUT0':'(0,0,0,0,0,0,AP11,0,0,0,0,0,0,0)';$S;BIDI;
    'GPP_F14_SSATA_LED_N':'(0,0,0,0,0,0,AL11,0,0,0,0,0,0,0)';$S;BIDI;
    'GPP_F15_USB2_OC4_N':'(0,0,0,0,0,0,AR13,0,0,0,0,0,0,0)';$S;BIDI;
    'GPP_F16_USB2_OC5_N':'(0,0,0,0,0,0,AU13,0,0,0,0,0,0,0)';$S;BIDI;
    'GPP_F17_USB2_OC6_N':'(0,0,0,0,0,0,AP15,0,0,0,0,0,0,0)';$S;BIDI;
    'GPP_F18_USB2_OC7_N':'(0,0,0,0,0,0,AL15,0,0,0,0,0,0,0)';$S;BIDI;
    'GPP_F19_LAN_SMBCLK':'(0,0,0,0,0,0,AU9,0,0,0,0,0,0,0)';$S;BIDI;
    'GPP_F1_SATAXPCIE4_SATAGP4':'(0,0,0,0,0,0,AK9,0,0,0,0,0,0,0)';$S;BIDI;
    'GPP_F20_LAN_SMBDATA':'(0,0,0,0,0,0,AU20,0,0,0,0,0,0,0)';$S;BIDI;
    'GPP_F21_LAN_SMBALRT_N':'(0,0,0,0,0,0,AR17,0,0,0,0,0,0,0)';$S;BIDI;
    'GPP_F22_SSATA_SCLOCK':'(0,0,0,0,0,0,AP18,0,0,0,0,0,0,0)';$S;BIDI;
    'GPP_F23_SSATA_SLOAD':'(0,0,0,0,0,0,AU17,0,0,0,0,0,0,0)';$S;BIDI;
    'GPP_F2_SATAXPCIE5_SATAGP5':'(0,0,0,0,0,0,AK20,0,0,0,0,0,0,0)';$S;BIDI;
    'GPP_F3_SATAXPCIE6_SATAGP6':'(0,0,0,0,0,0,AK13,0,0,0,0,0,0,0)';$S;BIDI;
    'GPP_F4_SATAXPCIE7_SATAGP7':'(0,0,0,0,0,0,AH13,0,0,0,0,0,0,0)';$S;BIDI;
    'GPP_F5_SATA_DEVSLP3':'(0,0,0,0,0,0,AH17,0,0,0,0,0,0,0)';$S;BIDI;
    'GPP_F6_SATA_DEVSLP4':'(0,0,0,0,0,0,AL18,0,0,0,0,0,0,0)';$S;BIDI;
    'GPP_F7_SATA_DEVSLP5':'(0,0,0,0,0,0,AK17,0,0,0,0,0,0,0)';$S;BIDI;
    'GPP_F8_SATA_DEVSLP6':'(0,0,0,0,0,0,AH9,0,0,0,0,0,0,0)';$S;BIDI;
    'GPP_F9_SATA_DEVSLP7':'(0,0,0,0,0,0,AR20,0,0,0,0,0,0,0)';$S;BIDI;
    'GPP_G0_FANTACH0_FANTACH0IE':'(0,0,0,0,0,0,AY11,0,0,0,0,0,0,0)';$S;BIDI;
    'GPP_G10_FANPWM2_FANPWM2IE':'(0,0,0,0,0,0,BE11,0,0,0,0,0,0,0)';$S;BIDI;
    'GPP_G11_FANPWM3_FANPMW3IE':'(0,0,0,0,0,0,BA20,0,0,0,0,0,0,0)';$S;BIDI;
    'GPP_G12':'(0,0,0,0,0,0,BD13,0,0,0,0,0,0,0)';$S;BIDI;
    'GPP_G13':'(0,0,0,0,0,0,AY18,0,0,0,0,0,0,0)';$S;BIDI;
    'GPP_G14':'(0,0,0,0,0,0,AV7,0,0,0,0,0,0,0)';$S;BIDI;
    'GPP_G15':'(0,0,0,0,0,0,BE18,0,0,0,0,0,0,0)';$S;BIDI;
    'GPP_G16':'(0,0,0,0,0,0,BD17,0,0,0,0,0,0,0)';$S;BIDI;
    'GPP_G17_ADR_COMPLETE':'(0,0,0,0,0,0,BD9,0,0,0,0,0,0,0)';$S;BIDI;
    'GPP_G18_NMI_N':'(0,0,0,0,0,0,BE7,0,0,0,0,0,0,0)';$S;BIDI;
    'GPP_G19_SMI_N':'(0,0,0,0,0,0,BE15,0,0,0,0,0,0,0)';$S;BIDI;
    'GPP_G1_FANTACH1_FANTACH1IE':'(0,0,0,0,0,0,AV15,0,0,0,0,0,0,0)';$S;BIDI;
    'GPP_G20_SSATA_DEVSLP0':'(0,0,0,0,0,0,BA17,0,0,0,0,0,0,0)';$S;BIDI;
    'GPP_G21_SSATA_DEVSLP1':'(0,0,0,0,0,0,BG7,0,0,0,0,0,0,0)';$S;BIDI;
    'GPP_G22_SSATA_DEVSLP2':'(0,0,0,0,0,0,BD20,0,0,0,0,0,0,0)';$S;BIDI;
    'GPP_G23_SSATAXPCIE0_SSATAGP0':'(0,0,0,0,0,0,BA13,0,0,0,0,0,0,0)';$S;BIDI;
    'GPP_G2_FANTACH2_FANTACH2IE':'(0,0,0,0,0,0,BE22,0,0,0,0,0,0,0)';$S;BIDI;
    'GPP_G3_FANTACH3_FANTACH3IE':'(0,0,0,0,0,0,AY7,0,0,0,0,0,0,0)';$S;BIDI;
    'GPP_G4_FANTACH4_FANTACH4IE':'(0,0,0,0,0,0,BA9,0,0,0,0,0,0,0)';$S;BIDI;
    'GPP_G5_FANTACH5_FANTACH5IE':'(0,0,0,0,0,0,AW20,0,0,0,0,0,0,0)';$S;BIDI;
    'GPP_G6_FANTACH6_FANTACH6IE':'(0,0,0,0,0,0,AV18,0,0,0,0,0,0,0)';$S;BIDI;
    'GPP_G7_FANTACH7_FANTACH7IE':'(0,0,0,0,0,0,AY15,0,0,0,0,0,0,0)';$S;BIDI;
    'GPP_G8_FANPWM0_FANPWM0IE':'(0,0,0,0,0,0,BG11,0,0,0,0,0,0,0)';$S;BIDI;
    'GPP_G9_FANPWM1_FAMPWM1IE':'(0,0,0,0,0,0,AV11,0,0,0,0,0,0,0)';$S;BIDI;
    'GPP_H0_SRCCLKREQ6_N':'(0,0,0,0,0,0,AT4,0,0,0,0,0,0,0)';$S;BIDI;
    'GPP_H10_SML2CLK_IE':'(0,0,0,0,0,0,BA4,0,0,0,0,0,0,0)';$S;BIDI;
    'GPP_H11_SML2DATA_IE':'(0,0,0,0,0,0,BD1,0,0,0,0,0,0,0)';$S;BIDI;
    'GPP_H12_SML2ALERT_N_IE_N':'(0,0,0,0,0,0,BB1,0,0,0,0,0,0,0)';$S;BIDI;
    'GPP_H13_SML3CLK_IE':'(0,0,0,0,0,0,AY1,0,0,0,0,0,0,0)';$S;BIDI;
    'GPP_H14_SML3DATA_IE':'(0,0,0,0,0,0,BC2,0,0,0,0,0,0,0)';$S;BIDI;
    'GPP_H15_SML3ALERT_N_IE_N':'(0,0,0,0,0,0,BB3,0,0,0,0,0,0,0)';$S;BIDI;
    'GPP_H16_SML4CLK_IE':'(0,0,0,0,0,0,BF1,0,0,0,0,0,0,0)';$S;BIDI;
    'GPP_H17_SML4DATA_IE':'(0,0,0,0,0,0,BE4,0,0,0,0,0,0,0)';$S;BIDI;
    'GPP_H18_SML4ALERT_N_IE_N':'(0,0,0,0,0,0,BC4,0,0,0,0,0,0,0)';$S;BIDI;
    'GPP_H19_SSATAXPCIE1_SSATAGP1':'(0,0,0,0,0,0,BD3,0,0,0,0,0,0,0)';$S;BIDI;
    'GPP_H1_SRCCLKREQ7_N':'(0,0,0,0,0,0,AW4,0,0,0,0,0,0,0)';$S;BIDI;
    'GPP_H20_SSATAXPCIE2_SSATAGP2':'(0,0,0,0,0,0,BF3,0,0,0,0,0,0,0)';$S;BIDI;
    'GPP_H21_SSATAXPCIE3_SSATAGP3':'(0,0,0,0,0,0,BA2,0,0,0,0,0,0,0)';$S;BIDI;
    'GPP_H22_SSATAXPCIE4_SSATAGP4':'(0,0,0,0,0,0,BH2,0,0,0,0,0,0,0)';$S;BIDI;
    'GPP_H23_SSATAXPCIE5_SSATAGP5':'(0,0,0,0,0,0,BH4,0,0,0,0,0,0,0)';$S;BIDI;
    'GPP_H2_SRCCLKREQ8_N':'(0,0,0,0,0,0,AV3,0,0,0,0,0,0,0)';$S;BIDI;
    'GPP_H3_SRCCLKREQ9_N':'(0,0,0,0,0,0,AR1,0,0,0,0,0,0,0)';$S;BIDI;
    'GPP_H4_SRCCLKREQ10_N':'(0,0,0,0,0,0,AT2,0,0,0,0,0,0,0)';$S;BIDI;
    'GPP_H5_SRCCLKREQ11_N':'(0,0,0,0,0,0,AY3,0,0,0,0,0,0,0)';$S;BIDI;
    'GPP_H6_SRCCLKREQ12_N':'(0,0,0,0,0,0,AW2,0,0,0,0,0,0,0)';$S;BIDI;
    'GPP_H7_SRCCLKREQ13_N':'(0,0,0,0,0,0,AV1,0,0,0,0,0,0,0)';$S;BIDI;
    'GPP_H8_SRCCLKREQ14_N':'(0,0,0,0,0,0,AR3,0,0,0,0,0,0,0)';$S;BIDI;
    'GPP_H9_SRCCLKREQ15_N':'(0,0,0,0,0,0,BE2,0,0,0,0,0,0,0)';$S;BIDI;
    'GPP_I0_LAN_TDO':'(0,0,0,0,0,0,CA20,0,0,0,0,0,0,0)';$S;
    'GPP_I10':'(0,0,0,0,0,0,BV25,0,0,0,0,0,0,0)';$S;BIDI;
    'GPP_I1_LAN_TCK':'(0,0,0,0,0,0,BV21,0,0,0,0,0,0,0)';$S;
    'GPP_I2_LAN_TMS':'(0,0,0,0,0,0,CA22,0,0,0,0,0,0,0)';$S;
    'GPP_I3_LAN_TDI':'(0,0,0,0,0,0,BY23,0,0,0,0,0,0,0)';$S;
    'GPP_I4_DO_RESET_IN_N':'(0,0,0,0,0,0,BW20,0,0,0,0,0,0,0)';$S;BIDI;
    'GPP_I5_DO_RESET_OUT_N':'(0,0,0,0,0,0,BW24,0,0,0,0,0,0,0)';$S;BIDI;
    'GPP_I6_RESET_DONE':'(0,0,0,0,0,0,BV23,0,0,0,0,0,0,0)';$S;BIDI;
    'GPP_I7_LAN_TRST_N':'(0,0,0,0,0,0,CA24,0,0,0,0,0,0,0)';$S;
    'GPP_I8_PCI_DIS_N':'(0,0,0,0,0,0,BW22,0,0,0,0,0,0,0)';$S;
    'GPP_I9_LAN_DIS_N':'(0,0,0,0,0,0,BY21,0,0,0,0,0,0,0)';$S;
    'GPP_J0_LAN_LED_P0_0':'(0,0,0,0,0,0,BL1,0,0,0,0,0,0,0)';$S;BIDI;
    'GPP_J10_LAN_I2C_SCL_MDC_P1':'(0,0,0,0,0,0,BW5,0,0,0,0,0,0,0)';$S;BIDI;
    'GPP_J11_LAN_I2C_SDA_MDIO_P1':'(0,0,0,0,0,0,BV8,0,0,0,0,0,0,0)';$S;BIDI;
    'GPP_J12_LAN_I2C_SCL_MDC_P2':'(0,0,0,0,0,0,BT5,0,0,0,0,0,0,0)';$S;BIDI;
    'GPP_J13_LAN_I2C_SDA_MDIO_P2':'(0,0,0,0,0,0,BW11,0,0,0,0,0,0,0)';$S;BIDI;
    'GPP_J14_LAN_I2C_SCL_MDC_P3':'(0,0,0,0,0,0,BW6,0,0,0,0,0,0,0)';$S;BIDI;
    'GPP_J15_LAN_I2C_SDA_MDIO_P3':'(0,0,0,0,0,0,BW9,0,0,0,0,0,0,0)';$S;BIDI;
    'GPP_J16_LAN_SDP_P0_0':'(0,0,0,0,0,0,BV10,0,0,0,0,0,0,0)';$S;BIDI;
    'GPP_J17_LAN_SDP_P0_1':'(0,0,0,0,0,0,CA11,0,0,0,0,0,0,0)';$S;BIDI;
    'GPP_J18_LAN_SDP_P1_0':'(0,0,0,0,0,0,BY10,0,0,0,0,0,0,0)';$S;BIDI;
    'GPP_J19_LAN_SDP_P1_1':'(0,0,0,0,0,0,BY14,0,0,0,0,0,0,0)';$S;BIDI;
    'GPP_J1_LAN_LED_P0_1':'(0,0,0,0,0,0,BK4,0,0,0,0,0,0,0)';$S;BIDI;
    'GPP_J20_LAN_SDP_P2_0':'(0,0,0,0,0,0,BW13,0,0,0,0,0,0,0)';$S;BIDI;
    'GPP_J21_LAN_SDP_P2_1':'(0,0,0,0,0,0,BV12,0,0,0,0,0,0,0)';$S;BIDI;
    'GPP_J22_LAN_SDP_P3_0':'(0,0,0,0,0,0,BY12,0,0,0,0,0,0,0)';$S;BIDI;
    'GPP_J23_LAN_SDP_P3_1':'(0,0,0,0,0,0,BV14,0,0,0,0,0,0,0)';$S;BIDI;
    'GPP_J2_LAN_LED_P1_0':'(0,0,0,0,0,0,BP4,0,0,0,0,0,0,0)';$S;BIDI;
    'GPP_J3_LAN_LED_P1_1':'(0,0,0,0,0,0,BK2,0,0,0,0,0,0,0)';$S;BIDI;
    'GPP_J4_LAN_LED_P2_0':'(0,0,0,0,0,0,BL3,0,0,0,0,0,0,0)';$S;BIDI;
    'GPP_J5_LAN_LED_P2_1':'(0,0,0,0,0,0,BU6,0,0,0,0,0,0,0)';$S;BIDI;
    'GPP_J6_LAN_LED_P3_0':'(0,0,0,0,0,0,CA13,0,0,0,0,0,0,0)';$S;BIDI;
    'GPP_J7_LAN_LED_P3_1':'(0,0,0,0,0,0,BM2,0,0,0,0,0,0,0)';$S;BIDI;
    'GPP_J8_LAN_I2C_SCL_MDC_P0':'(0,0,0,0,0,0,BM4,0,0,0,0,0,0,0)';$S;BIDI;
    'GPP_J9_LAN_I2C_SDA_MDIO_P0':'(0,0,0,0,0,0,BN3,0,0,0,0,0,0,0)';$S;BIDI;
    'GPP_K0_LAN_NCSI_CLK_IN':'(0,0,0,0,0,0,0,AJ1,0,0,0,0,0,0)';$S;BIDI;
    'GPP_K10_PE_RST_N':'(0,0,0,0,0,0,0,AH4,0,0,0,0,0,0)';$S;BIDI;
    'GPP_K1_LAN_NCSI_TXD0':'(0,0,0,0,0,0,0,AM2,0,0,0,0,0,0)';$S;BIDI;
    'GPP_K2_LAN_NCSI_TXD1':'(0,0,0,0,0,0,0,AK2,0,0,0,0,0,0)';$S;BIDI;
    'GPP_K3_LAN_NCSI_TX_EN':'(0,0,0,0,0,0,0,AL3,0,0,0,0,0,0)';$S;BIDI;
    'GPP_K4_LAN_NCSI_CRS_DV':'(0,0,0,0,0,0,0,AN3,0,0,0,0,0,0)';$S;BIDI;
    'GPP_K5_LAN_NCSI_RXD0':'(0,0,0,0,0,0,0,AL1,0,0,0,0,0,0)';$S;BIDI;
    'GPP_K6_LAN_NCSI_RXD1':'(0,0,0,0,0,0,0,AN1,0,0,0,0,0,0)';$S;BIDI;
    'GPP_K7':'(0,0,0,0,0,0,0,AH2,0,0,0,0,0,0)';$S;BIDI;
    'GPP_K8_LAN_NCSI_ARB_IN':'(0,0,0,0,0,0,0,AJ3,0,0,0,0,0,0)';$S;BIDI;
    'GPP_K9_LAN_NCSI_ARB_OUT':'(0,0,0,0,0,0,0,AK4,0,0,0,0,0,0)';$S;BIDI;
    'GPP_L10_TESTCH0_CLK':'(0,0,0,0,0,0,0,AF20,0,0,0,0,0,0)';$S;BIDI;
    'GPP_L11_TESTCH1_D0':'(0,0,0,0,0,0,0,AD20,0,0,0,0,0,0)';$S;BIDI;
    'GPP_L12_TESTCH1_D1':'(0,0,0,0,0,0,0,Y15,0,0,0,0,0,0)';$S;BIDI;
    'GPP_L13_TESTCH1_D2':'(0,0,0,0,0,0,0,AD13,0,0,0,0,0,0)';$S;BIDI;
    'GPP_L14_TESTCH1_D3':'(0,0,0,0,0,0,0,AA13,0,0,0,0,0,0)';$S;BIDI;
    'GPP_L15_TESTCH1_D4':'(0,0,0,0,0,0,0,Y11,0,0,0,0,0,0)';$S;BIDI;
    'GPP_L16_TESTCH1_D5':'(0,0,0,0,0,0,0,Y7,0,0,0,0,0,0)';$S;BIDI;
    'GPP_L17_TESTCH1_D6':'(0,0,0,0,0,0,0,AA9,0,0,0,0,0,0)';$S;BIDI;
    'GPP_L18_TESTCH1_D7':'(0,0,0,0,0,0,0,AE7,0,0,0,0,0,0)';$S;BIDI;
    'GPP_L19_TESTCH1_CLK':'(0,0,0,0,0,0,0,AG11,0,0,0,0,0,0)';$S;BIDI;
    'GPP_L2_TESTCH0_D0':'(0,0,0,0,0,0,0,AE18,0,0,0,0,0,0)';$S;BIDI;
    'GPP_L3_TESTCH0_D1':'(0,0,0,0,0,0,0,AE15,0,0,0,0,0,0)';$S;BIDI;
    'GPP_L4_TESTCH0_D2':'(0,0,0,0,0,0,0,AE11,0,0,0,0,0,0)';$S;BIDI;
    'GPP_L5_TESTCH0_D3':'(0,0,0,0,0,0,0,Y18,0,0,0,0,0,0)';$S;BIDI;
    'GPP_L6_TESTCH0_D4':'(0,0,0,0,0,0,0,AA20,0,0,0,0,0,0)';$S;BIDI;
    'GPP_L7_TESTCH0_D5':'(0,0,0,0,0,0,0,AA17,0,0,0,0,0,0)';$S;BIDI;
    'GPP_L8_TESTCH0_D6':'(0,0,0,0,0,0,0,AD9,0,0,0,0,0,0)';$S;BIDI;
    'GPP_L9_TESTCH0_D7':'(0,0,0,0,0,0,0,AD17,0,0,0,0,0,0)';$S;BIDI;
    'HDA_BCLK':'(0,0,0,0,0,0,0,P18,0,0,0,0,0,0)';$S;BIDI;
    'HDA_RST_N':'(0,0,0,0,0,0,0,M18,0,0,0,0,0,0)';$S;BIDI;
    'HDA_SDI_0':'(0,0,0,0,0,0,0,K20,0,0,0,0,0,0)';$S;BIDI;
    'HDA_SDI_1':'(0,0,0,0,0,0,0,V18,0,0,0,0,0,0)';$S;BIDI;
    'HDA_SDO':'(0,0,0,0,0,0,0,U24,0,0,0,0,0,0)';$S;BIDI;
    'HDA_SYNC':'(0,0,0,0,0,0,0,H20,0,0,0,0,0,0)';$S;BIDI;
    'INTRUDER_N':'(0,0,0,0,0,0,0,AG18,0,0,0,0,0,0)';$S;BIDI;
    'ITP_PMODE':'(0,0,0,0,AR54,0,0,0,0,0,0,0,0,0)';$S;BIDI;
    'JTAGX':'(0,0,0,0,AF54,0,0,0,0,0,0,0,0,0)';$S;BIDI;
    'JTAG_TCK':'(0,0,0,0,AL56,0,0,0,0,0,0,0,0,0)';$S;BIDI;
    'JTAG_TDI':'(0,0,0,0,AN54,0,0,0,0,0,0,0,0,0)';$S;BIDI;
    'JTAG_TDO':'(0,0,0,0,AP56,0,0,0,0,0,0,0,0,0)';$S;BIDI;
    'JTAG_TMS':'(0,0,0,0,AH54,0,0,0,0,0,0,0,0,0)';$S;BIDI;
    'LAN_RBIAS_0':'(0,0,0,0,BB29,0,0,0,0,0,0,0,0,0)';$S;BIDI;
    'LAN_RBIAS_1':'(0,0,0,0,BD42,0,0,0,0,0,0,0,0,0)';$S;BIDI;
    'LAN_RX_P0N':'(0,0,0,0,BH31,0,0,0,0,0,0,0,0,0)';$S;BIDI;
    'LAN_RX_P0P':'(0,0,0,0,BF31,0,0,0,0,0,0,0,0,0)';$S;BIDI;
    'LAN_RX_P1N':'(0,0,0,0,BG29,0,0,0,0,0,0,0,0,0)';$S;BIDI;
    'LAN_RX_P1P':'(0,0,0,0,BJ29,0,0,0,0,0,0,0,0,0)';$S;BIDI;
    'LAN_RX_P2N':'(0,0,0,0,BJ37,0,0,0,0,0,0,0,0,0)';$S;BIDI;
    'LAN_RX_P2P':'(0,0,0,0,BG37,0,0,0,0,0,0,0,0,0)';$S;BIDI;
    'LAN_RX_P3N':'(0,0,0,0,BF35,0,0,0,0,0,0,0,0,0)';$S;BIDI;
    'LAN_RX_P3P':'(0,0,0,0,BH35,0,0,0,0,0,0,0,0,0)';$S;BIDI;
    'LAN_TX_P0N':'(0,0,0,0,BM27,0,0,0,0,0,0,0,0,0)';$S;BIDI;
    'LAN_TX_P0P':'(0,0,0,0,BR27,0,0,0,0,0,0,0,0,0)';$S;BIDI;
    'LAN_TX_P1N':'(0,0,0,0,BM24,0,0,0,0,0,0,0,0,0)';$S;BIDI;
    'LAN_TX_P1P':'(0,0,0,0,BR24,0,0,0,0,0,0,0,0,0)';$S;BIDI;
    'LAN_TX_P2N':'(0,0,0,0,BM35,0,0,0,0,0,0,0,0,0)';$S;BIDI;
    'LAN_TX_P2P':'(0,0,0,0,BR35,0,0,0,0,0,0,0,0,0)';$S;BIDI;
    'LAN_TX_P3N':'(0,0,0,0,BR31,0,0,0,0,0,0,0,0,0)';$S;BIDI;
    'LAN_TX_P3P':'(0,0,0,0,BM31,0,0,0,0,0,0,0,0,0)';$S;BIDI;
    'LAN_XTAL_IN':'(0,0,0,0,BV16,0,0,0,0,0,0,0,0,0)';$S;BIDI;
    'LAN_XTAL_OUT':'(0,0,0,0,BY16,0,0,0,0,0,0,0,0,0)';$S;BIDI;
    'PCH_PWROK':'(0,0,0,0,R17,0,0,0,0,0,0,0,0,0)';$S;BIDI;
    'PCIE10_SSATA4_RXN':'(0,0,AV63,0,0,0,0,0,0,0,0,0,0,0)';$S;BIDI;
    'PCIE10_SSATA4_RXP':'(0,0,AU65,0,0,0,0,0,0,0,0,0,0,0)';$S;BIDI;
    'PCIE10_SSATA4_TXN':'(0,0,AD70,0,0,0,0,0,0,0,0,0,0,0)';$S;BIDI;
    'PCIE10_SSATA4_TXP':'(0,0,AD72,0,0,0,0,0,0,0,0,0,0,0)';$S;BIDI;
    'PCIE11_SSATA5_GBE_RXN':'(0,0,AT66,0,0,0,0,0,0,0,0,0,0,0)';$S;BIDI;
    'PCIE11_SSATA5_GBE_RXP':'(0,0,AV66,0,0,0,0,0,0,0,0,0,0,0)';$S;BIDI;
    'PCIE11_SSATA5_GBE_TXN':'(0,0,AC69,0,0,0,0,0,0,0,0,0,0,0)';$S;BIDI;
    'PCIE11_SSATA5_GBE_TXP':'(0,0,AC71,0,0,0,0,0,0,0,0,0,0,0)';$S;BIDI;
    'PCIE12_UP0_SATA0_RXN':'(0,0,AR61,0,0,0,0,0,0,0,0,0,0,0)';$S;BIDI;
    'PCIE12_UP0_SATA0_RXP':'(0,0,AT63,0,0,0,0,0,0,0,0,0,0,0)';$S;BIDI;
    'PCIE12_UP0_SATA0_TXN':'(0,0,W69,0,0,0,0,0,0,0,0,0,0,0)';$S;BIDI;
    'PCIE12_UP0_SATA0_TXP':'(0,0,W71,0,0,0,0,0,0,0,0,0,0,0)';$S;BIDI;
    'PCIE13_UP1_SATA1_RXN':'(0,0,AL66,0,0,0,0,0,0,0,0,0,0,0)';$S;BIDI;
    'PCIE13_UP1_SATA1_RXP':'(0,0,AN65,0,0,0,0,0,0,0,0,0,0,0)';$S;BIDI;
    'PCIE13_UP1_SATA1_TXN':'(0,0,V70,0,0,0,0,0,0,0,0,0,0,0)';$S;BIDI;
    'PCIE13_UP1_SATA1_TXP':'(0,0,V72,0,0,0,0,0,0,0,0,0,0,0)';$S;BIDI;
    'PCIE14_UP2_SATA2_RXN':'(0,0,AK65,0,0,0,0,0,0,0,0,0,0,0)';$S;BIDI;
    'PCIE14_UP2_SATA2_RXP':'(0,0,AJ63,0,0,0,0,0,0,0,0,0,0,0)';$S;BIDI;
    'PCIE14_UP2_SATA2_TXN':'(0,0,T69,0,0,0,0,0,0,0,0,0,0,0)';$S;BIDI;
    'PCIE14_UP2_SATA2_TXP':'(0,0,T71,0,0,0,0,0,0,0,0,0,0,0)';$S;BIDI;
    'PCIE15_UP3_SATA3_RXN':'(0,0,AP63,0,0,0,0,0,0,0,0,0,0,0)';$S;BIDI;
    'PCIE15_UP3_SATA3_RXP':'(0,0,AL63,0,0,0,0,0,0,0,0,0,0,0)';$S;BIDI;
    'PCIE15_UP3_SATA3_TXN':'(0,0,R70,0,0,0,0,0,0,0,0,0,0,0)';$S;BIDI;
    'PCIE15_UP3_SATA3_TXP':'(0,0,R72,0,0,0,0,0,0,0,0,0,0,0)';$S;BIDI;
    'PCIE16_UP4_SATA4_RXN':'(0,0,AF65,0,0,0,0,0,0,0,0,0,0,0)';$S;BIDI;
    'PCIE16_UP4_SATA4_RXP':'(0,0,AH65,0,0,0,0,0,0,0,0,0,0,0)';$S;BIDI;
    'PCIE16_UP4_SATA4_TXN':'(0,0,P69,0,0,0,0,0,0,0,0,0,0,0)';$S;BIDI;
    'PCIE16_UP4_SATA4_TXP':'(0,0,P71,0,0,0,0,0,0,0,0,0,0,0)';$S;BIDI;
    'PCIE17_UP5_SATA5_RXN':'(0,0,AH61,0,0,0,0,0,0,0,0,0,0,0)';$S;BIDI;
    'PCIE17_UP5_SATA5_RXP':'(0,0,AG63,0,0,0,0,0,0,0,0,0,0,0)';$S;BIDI;
    'PCIE17_UP5_SATA5_TXN':'(0,0,N70,0,0,0,0,0,0,0,0,0,0,0)';$S;BIDI;
    'PCIE17_UP5_SATA5_TXP':'(0,0,N72,0,0,0,0,0,0,0,0,0,0,0)';$S;BIDI;
    'PCIE18_UP6_SATA6_RXN':'(0,0,AP59,0,0,0,0,0,0,0,0,0,0,0)';$S;BIDI;
    'PCIE18_UP6_SATA6_RXP':'(0,0,AN61,0,0,0,0,0,0,0,0,0,0,0)';$S;BIDI;
    'PCIE18_UP6_SATA6_TXN':'(0,0,M69,0,0,0,0,0,0,0,0,0,0,0)';$S;BIDI;
    'PCIE18_UP6_SATA6_TXP':'(0,0,M71,0,0,0,0,0,0,0,0,0,0,0)';$S;BIDI;
    'PCIE19_UP7_SATA7_RXN':'(0,0,AA61,0,0,0,0,0,0,0,0,0,0,0)';$S;BIDI;
    'PCIE19_UP7_SATA7_RXP':'(0,0,AD61,0,0,0,0,0,0,0,0,0,0,0)';$S;BIDI;
    'PCIE19_UP7_SATA7_TXN':'(0,0,L70,0,0,0,0,0,0,0,0,0,0,0)';$S;BIDI;
    'PCIE19_UP7_SATA7_TXP':'(0,0,L72,0,0,0,0,0,0,0,0,0,0,0)';$S;BIDI;
    'PCIE4_GBE_RXN':'(0,0,AN70,0,0,0,0,0,0,0,0,0,0,0)';$S;BIDI;
    'PCIE4_GBE_RXP':'(0,0,AN72,0,0,0,0,0,0,0,0,0,0,0)';$S;BIDI;
    'PCIE4_GBE_TXN':'(0,0,BG66,0,0,0,0,0,0,0,0,0,0,0)';$S;BIDI;
    'PCIE4_GBE_TXP':'(0,0,BJ66,0,0,0,0,0,0,0,0,0,0,0)';$S;BIDI;
    'PCIE5_GBE_RXN':'(0,0,AM69,0,0,0,0,0,0,0,0,0,0,0)';$S;BIDI;
    'PCIE5_GBE_RXP':'(0,0,AM71,0,0,0,0,0,0,0,0,0,0,0)';$S;BIDI;
    'PCIE5_GBE_TXN':'(0,0,BH65,0,0,0,0,0,0,0,0,0,0,0)';$S;BIDI;
    'PCIE5_GBE_TXP':'(0,0,BJ63,0,0,0,0,0,0,0,0,0,0,0)';$S;BIDI;
    'PCIE6_SSATA0_RXN':'(0,0,BB63,0,0,0,0,0,0,0,0,0,0,0)';$S;BIDI;
    'PCIE6_SSATA0_RXP':'(0,0,BD61,0,0,0,0,0,0,0,0,0,0,0)';$S;BIDI;
    'PCIE6_SSATA0_TXN':'(0,0,AJ70,0,0,0,0,0,0,0,0,0,0,0)';$S;BIDI;
    'PCIE6_SSATA0_TXP':'(0,0,AJ72,0,0,0,0,0,0,0,0,0,0,0)';$S;BIDI;
    'PCIE7_SSATA1_RXN':'(0,0,AY59,0,0,0,0,0,0,0,0,0,0,0)';$S;BIDI;
    'PCIE7_SSATA1_RXP':'(0,0,BA61,0,0,0,0,0,0,0,0,0,0,0)';$S;BIDI;
    'PCIE7_SSATA1_TXN':'(0,0,AH69,0,0,0,0,0,0,0,0,0,0,0)';$S;BIDI;
    'PCIE7_SSATA1_TXP':'(0,0,AH71,0,0,0,0,0,0,0,0,0,0,0)';$S;BIDI;
    'PCIE8_SSATA2_GBE_RXN':'(0,0,BA65,0,0,0,0,0,0,0,0,0,0,0)';$S;BIDI;
    'PCIE8_SSATA2_GBE_RXP':'(0,0,BD65,0,0,0,0,0,0,0,0,0,0,0)';$S;BIDI;
    'PCIE8_SSATA2_GBE_TXN':'(0,0,AF70,0,0,0,0,0,0,0,0,0,0,0)';$S;BIDI;
    'PCIE8_SSATA2_GBE_TXP':'(0,0,AF72,0,0,0,0,0,0,0,0,0,0,0)';$S;BIDI;
    'PCIE9_SSATA3_RXN':'(0,0,AW65,0,0,0,0,0,0,0,0,0,0,0)';$S;BIDI;
    'PCIE9_SSATA3_RXP':'(0,0,AY66,0,0,0,0,0,0,0,0,0,0,0)';$S;BIDI;
    'PCIE9_SSATA3_TXN':'(0,0,AE69,0,0,0,0,0,0,0,0,0,0,0)';$S;BIDI;
    'PCIE9_SSATA3_TXP':'(0,0,AE71,0,0,0,0,0,0,0,0,0,0,0)';$S;BIDI;
    'PCIEUP_0_RXN':'(0,0,0,C48,0,0,0,0,0,0,0,0,0,0)';$S;BIDI;
    'PCIEUP_0_RXP':'(0,0,0,A48,0,0,0,0,0,0,0,0,0,0)';$S;BIDI;
    'PCIEUP_0_TXN':'(0,0,0,J52,0,0,0,0,0,0,0,0,0,0)';$S;BIDI;
    'PCIEUP_0_TXP':'(0,0,0,G52,0,0,0,0,0,0,0,0,0,0)';$S;BIDI;
    'PCIEUP_10_RXN':'(0,0,0,C59,0,0,0,0,0,0,0,0,0,0)';$S;BIDI;
    'PCIEUP_10_RXP':'(0,0,0,A59,0,0,0,0,0,0,0,0,0,0)';$S;BIDI;
    'PCIEUP_10_TXN':'(0,0,0,N65,0,0,0,0,0,0,0,0,0,0)';$S;BIDI;
    'PCIEUP_10_TXP':'(0,0,0,P66,0,0,0,0,0,0,0,0,0,0)';$S;BIDI;
    'PCIEUP_11_RXN':'(0,0,0,D60,0,0,0,0,0,0,0,0,0,0)';$S;BIDI;
    'PCIEUP_11_RXP':'(0,0,0,B60,0,0,0,0,0,0,0,0,0,0)';$S;BIDI;
    'PCIEUP_11_TXN':'(0,0,0,T59,0,0,0,0,0,0,0,0,0,0)';$S;BIDI;
    'PCIEUP_11_TXP':'(0,0,0,V59,0,0,0,0,0,0,0,0,0,0)';$S;BIDI;
    'PCIEUP_12_RXN':'(0,0,0,C61,0,0,0,0,0,0,0,0,0,0)';$S;BIDI;
    'PCIEUP_12_RXP':'(0,0,0,A61,0,0,0,0,0,0,0,0,0,0)';$S;BIDI;
    'PCIEUP_12_TXN':'(0,0,0,R65,0,0,0,0,0,0,0,0,0,0)';$S;BIDI;
    'PCIEUP_12_TXP':'(0,0,0,U65,0,0,0,0,0,0,0,0,0,0)';$S;BIDI;
    'PCIEUP_13_RXN':'(0,0,0,D62,0,0,0,0,0,0,0,0,0,0)';$S;BIDI;
    'PCIEUP_13_RXP':'(0,0,0,B62,0,0,0,0,0,0,0,0,0,0)';$S;BIDI;
    'PCIEUP_13_TXN':'(0,0,0,T63,0,0,0,0,0,0,0,0,0,0)';$S;BIDI;
    'PCIEUP_13_TXP':'(0,0,0,U61,0,0,0,0,0,0,0,0,0,0)';$S;BIDI;
    'PCIEUP_14_RXN':'(0,0,0,C63,0,0,0,0,0,0,0,0,0,0)';$S;BIDI;
    'PCIEUP_14_RXP':'(0,0,0,A63,0,0,0,0,0,0,0,0,0,0)';$S;BIDI;
    'PCIEUP_14_TXN':'(0,0,0,W65,0,0,0,0,0,0,0,0,0,0)';$S;BIDI;
    'PCIEUP_14_TXP':'(0,0,0,V63,0,0,0,0,0,0,0,0,0,0)';$S;BIDI;
    'PCIEUP_15_RXN':'(0,0,0,D64,0,0,0,0,0,0,0,0,0,0)';$S;BIDI;
    'PCIEUP_15_RXP':'(0,0,0,B64,0,0,0,0,0,0,0,0,0,0)';$S;BIDI;
    'PCIEUP_15_TXN':'(0,0,0,Y66,0,0,0,0,0,0,0,0,0,0)';$S;BIDI;
    'PCIEUP_15_TXP':'(0,0,0,AA65,0,0,0,0,0,0,0,0,0,0)';$S;BIDI;
    'PCIEUP_1_RXN':'(0,0,0,D49,0,0,0,0,0,0,0,0,0,0)';$S;BIDI;
    'PCIEUP_1_RXP':'(0,0,0,B49,0,0,0,0,0,0,0,0,0,0)';$S;BIDI;
    'PCIEUP_1_TXN':'(0,0,0,P56,0,0,0,0,0,0,0,0,0,0)';$S;BIDI;
    'PCIEUP_1_TXP':'(0,0,0,M56,0,0,0,0,0,0,0,0,0,0)';$S;BIDI;
    'PCIEUP_2_RXN':'(0,0,0,C50,0,0,0,0,0,0,0,0,0,0)';$S;BIDI;
    'PCIEUP_2_RXP':'(0,0,0,A50,0,0,0,0,0,0,0,0,0,0)';$S;BIDI;
    'PCIEUP_2_TXN':'(0,0,0,H54,0,0,0,0,0,0,0,0,0,0)';$S;BIDI;
    'PCIEUP_2_TXP':'(0,0,0,G56,0,0,0,0,0,0,0,0,0,0)';$S;BIDI;
    'PCIEUP_3_RXN':'(0,0,0,D51,0,0,0,0,0,0,0,0,0,0)';$S;BIDI;
    'PCIEUP_3_RXP':'(0,0,0,B51,0,0,0,0,0,0,0,0,0,0)';$S;BIDI;
    'PCIEUP_3_TXN':'(0,0,0,J56,0,0,0,0,0,0,0,0,0,0)';$S;BIDI;
    'PCIEUP_3_TXP':'(0,0,0,K58,0,0,0,0,0,0,0,0,0,0)';$S;BIDI;
    'PCIEUP_4_RXN':'(0,0,0,C52,0,0,0,0,0,0,0,0,0,0)';$S;BIDI;
    'PCIEUP_4_RXP':'(0,0,0,A52,0,0,0,0,0,0,0,0,0,0)';$S;BIDI;
    'PCIEUP_4_TXN':'(0,0,0,N58,0,0,0,0,0,0,0,0,0,0)';$S;BIDI;
    'PCIEUP_4_TXP':'(0,0,0,M59,0,0,0,0,0,0,0,0,0,0)';$S;BIDI;
    'PCIEUP_5_RXN':'(0,0,0,D53,0,0,0,0,0,0,0,0,0,0)';$S;BIDI;
    'PCIEUP_5_RXP':'(0,0,0,B53,0,0,0,0,0,0,0,0,0,0)';$S;BIDI;
    'PCIEUP_5_TXN':'(0,0,0,N61,0,0,0,0,0,0,0,0,0,0)';$S;BIDI;
    'PCIEUP_5_TXP':'(0,0,0,K61,0,0,0,0,0,0,0,0,0,0)';$S;BIDI;
    'PCIEUP_6_RXN':'(0,0,0,C54,0,0,0,0,0,0,0,0,0,0)';$S;BIDI;
    'PCIEUP_6_RXP':'(0,0,0,A54,0,0,0,0,0,0,0,0,0,0)';$S;BIDI;
    'PCIEUP_6_TXN':'(0,0,0,H61,0,0,0,0,0,0,0,0,0,0)';$S;BIDI;
    'PCIEUP_6_TXP':'(0,0,0,J63,0,0,0,0,0,0,0,0,0,0)';$S;BIDI;
    'PCIEUP_7_RXN':'(0,0,0,D55,0,0,0,0,0,0,0,0,0,0)';$S;BIDI;
    'PCIEUP_7_RXP':'(0,0,0,B55,0,0,0,0,0,0,0,0,0,0)';$S;BIDI;
    'PCIEUP_7_TXN':'(0,0,0,P59,0,0,0,0,0,0,0,0,0,0)';$S;BIDI;
    'PCIEUP_7_TXP':'(0,0,0,R61,0,0,0,0,0,0,0,0,0,0)';$S;BIDI;
    'PCIEUP_8_RXN':'(0,0,0,C57,0,0,0,0,0,0,0,0,0,0)';$S;BIDI;
    'PCIEUP_8_RXP':'(0,0,0,A57,0,0,0,0,0,0,0,0,0,0)';$S;BIDI;
    'PCIEUP_8_TXN':'(0,0,0,K65,0,0,0,0,0,0,0,0,0,0)';$S;BIDI;
    'PCIEUP_8_TXP':'(0,0,0,M63,0,0,0,0,0,0,0,0,0,0)';$S;BIDI;
    'PCIEUP_9_RXN':'(0,0,0,D58,0,0,0,0,0,0,0,0,0,0)';$S;BIDI;
    'PCIEUP_9_RXP':'(0,0,0,B58,0,0,0,0,0,0,0,0,0,0)';$S;BIDI;
    'PCIEUP_9_TXN':'(0,0,0,J66,0,0,0,0,0,0,0,0,0,0)';$S;BIDI;
    'PCIEUP_9_TXP':'(0,0,0,M66,0,0,0,0,0,0,0,0,0,0)';$S;BIDI;
    'PCIEUP_RCOMPN':'(0,0,AF58,0,0,0,0,0,0,0,0,0,0,0)';$S;BIDI;
    'PCIEUP_RCOMPP':'(0,0,AH58,0,0,0,0,0,0,0,0,0,0,0)';$S;BIDI;
    'PCIE_RCOMPN':'(0,0,BD58,0,0,0,0,0,0,0,0,0,0,0)';$S;BIDI;
    'PCIE_RCOMPP':'(0,0,BB56,0,0,0,0,0,0,0,0,0,0,0)';$S;BIDI;
    'PECI':'(0,0,0,0,U9,0,0,0,0,0,0,0,0,0)';$S;BIDI;
    'PLTRST_CPU_N':'(0,0,0,0,U17,0,0,0,0,0,0,0,0,0)';$S;BIDI;
    'PM_SYNC':'(0,0,0,0,U13,0,0,0,0,0,0,0,0,0)';$S;BIDI;
    'PM_SYNC2':'(0,0,0,0,V7,0,0,0,0,0,0,0,0,0)';$S;BIDI;
    'PRDY_N':'(0,0,0,0,AD54,0,0,0,0,0,0,0,0,0)';$S;BIDI;
    'PREQ_N':'(0,0,0,0,U54,0,0,0,0,0,0,0,0,0)';$S;BIDI;
    'PROC_PWRGD':'(0,0,0,0,R9,0,0,0,0,0,0,0,0,0)';$S;BIDI;
    'RSMRST_N':'(0,0,0,0,P15,0,0,0,0,0,0,0,0,0)';$S;BIDI;
    'RSVD'<68>:'(0,0,0,0,0,0,0,V22,0,0,0,0,0,0)';BIDI;
    'RSVD'<67>:'(0,0,0,0,0,0,0,R20,0,0,0,0,0,0)';BIDI;
    'RSVD'<66>:'(0,0,0,0,0,0,0,U20,0,0,0,0,0,0)';BIDI;
    'RSVD'<65>:'(A26,0,0,0,0,0,0,0,0,0,0,0,0,0)';
    'RSVD'<64>:'(C26,0,0,0,0,0,0,0,0,0,0,0,0,0)';
    'RSVD'<59>:'(0,0,0,0,0,0,0,0,AT27,0,0,0,0,0)';
    'RSVD'<58>:'(0,0,0,0,0,0,0,0,AP27,0,0,0,0,0)';
    'RSVD'<55>:'(0,BN68,0,0,0,0,0,0,0,0,0,0,0,0)';
    'RSVD'<54>:'(0,0,0,0,R24,0,0,0,0,0,0,0,0,0)';
    'RSVD'<53>:'(0,0,0,0,P26,0,0,0,0,0,0,0,0,0)';
    'RSVD'<52>:'(0,0,AA71,0,0,0,0,0,0,0,0,0,0,0)';
    'RSVD'<51>:'(0,0,AA69,0,0,0,0,0,0,0,0,0,0,0)';
    'RSVD'<50>:'(0,0,H69,0,0,0,0,0,0,0,0,0,0,0)';
    'RSVD'<49>:'(0,0,G67,0,0,0,0,0,0,0,0,0,0,0)';
    'RSVD'<48>:'(0,0,AP71,0,0,0,0,0,0,0,0,0,0,0)';
    'RSVD'<47>:'(0,0,AP69,0,0,0,0,0,0,0,0,0,0,0)';
    'RSVD'<46>:'(0,0,0,0,0,0,0,BW3,0,0,0,0,0,0)';
    'RSVD'<45>:'(0,0,0,0,P22,0,0,0,0,0,0,0,0,0)';
    'RSVD'<44>:'(0,0,0,0,BN33,0,0,0,0,0,0,0,0,0)';
    'RSVD'<43>:'(0,0,0,0,BL33,0,0,0,0,0,0,0,0,0)';
    'RSVD'<42>:'(0,0,0,0,BG40,0,0,0,0,0,0,0,0,0)';
    'RSVD'<41>:'(0,0,0,0,BJ40,0,0,0,0,0,0,0,0,0)';
    'RSVD'<40>:'(0,0,0,0,BN26,0,0,0,0,0,0,0,0,0)';
    'RSVD'<39>:'(0,0,0,0,BL26,0,0,0,0,0,0,0,0,0)';
    'RSVD'<38>:'(0,0,0,0,BL29,0,0,0,0,0,0,0,0,0)';
    'RSVD'<37>:'(0,0,0,0,BN29,0,0,0,0,0,0,0,0,0)';
    'RSVD'<36>:'(0,0,0,0,AK54,0,0,0,0,0,0,0,0,0)';
    'RSVD'<35>:'(0,0,0,0,W54,0,0,0,0,0,0,0,0,0)';
    'RSVD'<34>:'(0,0,0,0,Y56,0,0,0,0,0,0,0,0,0)';
    'RSVD'<33>:'(0,0,0,0,V56,0,0,0,0,0,0,0,0,0)';
    'RSVD'<32>:'(0,0,0,0,AA54,0,0,0,0,0,0,0,0,0)';
    'RSVD'<31>:'(0,0,0,0,0,0,0,0,P29,0,0,0,0,0)';
    'RSVD'<30>:'(0,0,0,0,0,0,0,0,R31,0,0,0,0,0)';
    'RSVD'<29>:'(0,0,0,0,0,0,0,0,P33,0,0,0,0,0)';
    'RSVD'<28>:'(0,0,0,0,0,0,0,0,R35,0,0,0,0,0)';
    'RSVD'<27>:'(0,0,0,0,0,0,0,BG26,0,0,0,0,0,0)';
    'RSVD'<26>:'(0,0,0,0,0,0,0,BH24,0,0,0,0,0,0)';
    'RSVD'<25>:'(0,0,0,0,0,0,0,P48,0,0,0,0,0,0)';
    'RSVD'<24>:'(0,0,0,0,0,0,0,P44,0,0,0,0,0,0)';
    'RSVD'<23>:'(0,0,0,0,0,0,0,P40,0,0,0,0,0,0)';
    'RSVD'<22>:'(0,0,0,0,0,0,0,AT71,0,0,0,0,0,0)';
    'RSVD'<21>:'(0,0,0,0,0,0,0,A11,0,0,0,0,0,0)';
    'RSVD'<20>:'(0,0,0,0,0,0,0,D10,0,0,0,0,0,0)';
    'RSVD'<19>:'(0,0,0,0,0,0,0,C9,0,0,0,0,0,0)';
    'RSVD'<18>:'(0,0,0,0,0,0,0,C11,0,0,0,0,0,0)';
    'RSVD'<17>:'(0,0,0,0,0,0,0,B10,0,0,0,0,0,0)';
    'RSVD'<16>:'(0,0,0,0,0,0,0,C5,0,0,0,0,0,0)';
    'RSVD'<15>:'(0,0,0,0,0,0,0,C6,0,0,0,0,0,0)';
    'RSVD'<14>:'(0,0,0,0,0,0,0,E18,0,0,0,0,0,0)';
    'RSVD'<13>:'(0,0,0,0,0,0,0,C67,0,0,0,0,0,0)';
    'RSVD'<12>:'(0,0,0,0,0,0,0,C68,0,0,0,0,0,0)';
    'RSVD'<11>:'(0,0,0,0,0,0,0,C18,0,0,0,0,0,0)';
    'RSVD'<10>:'(0,0,0,0,0,0,0,D8,0,0,0,0,0,0)';
    'RSVD'<9>:'(0,0,0,0,0,0,0,F66,0,0,0,0,0,0)';
    'RSVD'<8>:'(0,0,0,0,0,0,0,F69,0,0,0,0,0,0)';
    'RSVD'<7>:'(0,0,0,0,0,0,0,F8,0,0,0,0,0,0)';
    'RSVD'<6>:'(0,0,0,0,0,0,0,AT69,0,0,0,0,0,0)';
    'RSVD'<5>:'(0,0,0,0,0,0,0,AG15,0,0,0,0,0,0)';
    'RSVD'<4>:'(0,0,0,0,0,0,0,P37,0,0,0,0,0,0)';
    'RSVD'<3>:'(0,0,0,0,0,0,0,V11,0,0,0,0,0,0)';
    'RSVD'<2>:'(0,0,0,0,0,0,0,AA58,0,0,0,0,0,0)';
    'RSVD'<1>:'(0,0,0,0,0,0,0,AC56,0,0,0,0,0,0)';
    'RSVD'<0>:'(0,0,0,0,0,0,0,AF61,0,0,0,0,0,0)';
    'RTCRST_N':'(0,0,0,0,0,0,0,P11,0,0,0,0,0,0)';$S;BIDI;
    'RTCX1':'(K17,0,0,0,0,0,0,0,0,0,0,0,0,0)';$S;BIDI;
    'RTCX2':'(H17,0,0,0,0,0,0,0,0,0,0,0,0,0)';$S;BIDI;
    'SLP_GBE_N':'(0,0,0,0,M15,0,0,0,0,0,0,0,0,0)';$S;BIDI;
    'SLP_SUS_N':'(0,0,0,0,P7,0,0,0,0,0,0,0,0,0)';$S;BIDI;
    'SPI0_CLK':'(0,0,0,0,0,0,0,K2,0,0,0,0,0,0)';$S;BIDI;
    'SPI0_FLASH_CS0_N':'(0,0,0,0,0,0,0,J3,0,0,0,0,0,0)';$S;BIDI;
    'SPI0_FLASH_CS1_N':'(0,0,0,0,0,0,0,G7,0,0,0,0,0,0)';$S;BIDI;
    'SPI0_IO2':'(0,0,0,0,0,0,0,F5,0,0,0,0,0,0)';$S;BIDI;
    'SPI0_IO3':'(0,0,0,0,0,0,0,L1,0,0,0,0,0,0)';$S;BIDI;
    'SPI0_MISO_IO1':'(0,0,0,0,0,0,0,L3,0,0,0,0,0,0)';$S;BIDI;
    'SPI0_MOSI_IO0':'(0,0,0,0,0,0,0,H4,0,0,0,0,0,0)';$S;BIDI;
    'SPI0_TPM_CS_N':'(0,0,0,0,0,0,0,K4,0,0,0,0,0,0)';$S;BIDI;
    'SRTCRST_N':'(0,0,0,0,0,0,0,G18,0,0,0,0,0,0)';$S;BIDI;
    'SYS_PWROK':'(0,0,0,0,BY19,0,0,0,0,0,0,0,0,0)';$S;BIDI;
    'SYS_RESET_N':'(0,0,0,0,BV19,0,0,0,0,0,0,0,0,0)';$S;BIDI;
    'THRMTRIP_N':'(0,0,0,0,V15,0,0,0,0,0,0,0,0,0)';$S;BIDI;
    'TRIGGER_IN':'(0,0,0,0,M7,0,0,0,0,0,0,0,0,0)';$S;BIDI;
    'TRIGGER_OUT':'(0,0,0,0,R13,0,0,0,0,0,0,0,0,0)';$S;BIDI;
    'USB2N_1':'(0,BY60,0,0,0,0,0,0,0,0,0,0,0,0)';$S;BIDI;
    'USB2N_10':'(0,BW65,0,0,0,0,0,0,0,0,0,0,0,0)';$S;BIDI;
    'USB2N_11':'(0,CA54,0,0,0,0,0,0,0,0,0,0,0,0)';$S;BIDI;
    'USB2N_12':'(0,BW67,0,0,0,0,0,0,0,0,0,0,0,0)';$S;BIDI;
    'USB2N_13':'(0,BY53,0,0,0,0,0,0,0,0,0,0,0,0)';$S;BIDI;
    'USB2N_14':'(0,BW68,0,0,0,0,0,0,0,0,0,0,0,0)';$S;BIDI;
    'USB2N_2':'(0,CA61,0,0,0,0,0,0,0,0,0,0,0,0)';$S;BIDI;
    'USB2N_3':'(0,CA59,0,0,0,0,0,0,0,0,0,0,0,0)';$S;BIDI;
    'USB2N_4':'(0,BY62,0,0,0,0,0,0,0,0,0,0,0,0)';$S;BIDI;
    'USB2N_5':'(0,BY58,0,0,0,0,0,0,0,0,0,0,0,0)';$S;BIDI;
    'USB2N_6':'(0,CA63,0,0,0,0,0,0,0,0,0,0,0,0)';$S;BIDI;
    'USB2N_7':'(0,CA57,0,0,0,0,0,0,0,0,0,0,0,0)';$S;BIDI;
    'USB2N_8':'(0,BY64,0,0,0,0,0,0,0,0,0,0,0,0)';$S;BIDI;
    'USB2N_9':'(0,BY55,0,0,0,0,0,0,0,0,0,0,0,0)';$S;BIDI;
    'USB2P_1':'(0,BV60,0,0,0,0,0,0,0,0,0,0,0,0)';$S;BIDI;
    'USB2P_10':'(0,BU65,0,0,0,0,0,0,0,0,0,0,0,0)';$S;BIDI;
    'USB2P_11':'(0,BW54,0,0,0,0,0,0,0,0,0,0,0,0)';$S;BIDI;
    'USB2P_12':'(0,BV66,0,0,0,0,0,0,0,0,0,0,0,0)';$S;BIDI;
    'USB2P_13':'(0,BV53,0,0,0,0,0,0,0,0,0,0,0,0)';$S;BIDI;
    'USB2P_14':'(0,BU67,0,0,0,0,0,0,0,0,0,0,0,0)';$S;BIDI;
    'USB2P_2':'(0,BW61,0,0,0,0,0,0,0,0,0,0,0,0)';$S;BIDI;
    'USB2P_3':'(0,BW59,0,0,0,0,0,0,0,0,0,0,0,0)';$S;BIDI;
    'USB2P_4':'(0,BV62,0,0,0,0,0,0,0,0,0,0,0,0)';$S;BIDI;
    'USB2P_5':'(0,BV58,0,0,0,0,0,0,0,0,0,0,0,0)';$S;BIDI;
    'USB2P_6':'(0,BW63,0,0,0,0,0,0,0,0,0,0,0,0)';$S;BIDI;
    'USB2P_7':'(0,BW57,0,0,0,0,0,0,0,0,0,0,0,0)';$S;BIDI;
    'USB2P_8':'(0,BV64,0,0,0,0,0,0,0,0,0,0,0,0)';$S;BIDI;
    'USB2P_9':'(0,BV55,0,0,0,0,0,0,0,0,0,0,0,0)';$S;BIDI;
    'USB2_COMP':'(0,BN70,0,0,0,0,0,0,0,0,0,0,0,0)';$S;BIDI;
    'USB2_VBUS':'(0,BR67,0,0,0,0,0,0,0,0,0,0,0,0)';$S;BIDI;
    'USB3_10_PCIE3_GBE_RXN':'(0,0,AV72,0,0,0,0,0,0,0,0,0,0,0)';$S;BIDI;
    'USB3_10_PCIE3_GBE_RXP':'(0,0,AV70,0,0,0,0,0,0,0,0,0,0,0)';$S;BIDI;
    'USB3_10_PCIE3_GBE_TXN':'(0,0,BH61,0,0,0,0,0,0,0,0,0,0,0)';$S;BIDI;
    'USB3_10_PCIE3_GBE_TXP':'(0,0,BK61,0,0,0,0,0,0,0,0,0,0,0)';$S;BIDI;
    'USB3_1_RXN':'(0,BK71,0,0,0,0,0,0,0,0,0,0,0,0)';$S;BIDI;
    'USB3_1_RXP':'(0,BK69,0,0,0,0,0,0,0,0,0,0,0,0)';$S;BIDI;
    'USB3_1_TXN':'(0,BL52,0,0,0,0,0,0,0,0,0,0,0,0)';$S;BIDI;
    'USB3_1_TXP':'(0,BK54,0,0,0,0,0,0,0,0,0,0,0,0)';$S;BIDI;
    'USB3_2_RXN':'(0,BJ72,0,0,0,0,0,0,0,0,0,0,0,0)';$S;BIDI;
    'USB3_2_RXP':'(0,BJ70,0,0,0,0,0,0,0,0,0,0,0,0)';$S;BIDI;
    'USB3_2_TXN':'(0,BL56,0,0,0,0,0,0,0,0,0,0,0,0)';$S;BIDI;
    'USB3_2_TXP':'(0,BJ56,0,0,0,0,0,0,0,0,0,0,0,0)';$S;BIDI;
    'USB3_3_RXN':'(0,BH71,0,0,0,0,0,0,0,0,0,0,0,0)';$S;BIDI;
    'USB3_3_RXP':'(0,BH69,0,0,0,0,0,0,0,0,0,0,0,0)';$S;BIDI;
    'USB3_3_TXN':'(0,BM54,0,0,0,0,0,0,0,0,0,0,0,0)';$S;BIDI;
    'USB3_3_TXP':'(0,BN56,0,0,0,0,0,0,0,0,0,0,0,0)';$S;BIDI;
    'USB3_4_RXN':'(0,BF72,0,0,0,0,0,0,0,0,0,0,0,0)';$S;BIDI;
    'USB3_4_RXP':'(0,BF70,0,0,0,0,0,0,0,0,0,0,0,0)';$S;BIDI;
    'USB3_4_TXN':'(0,BH58,0,0,0,0,0,0,0,0,0,0,0,0)';$S;BIDI;
    'USB3_4_TXP':'(0,BG56,0,0,0,0,0,0,0,0,0,0,0,0)';$S;BIDI;
    'USB3_5_RXN':'(0,BE71,0,0,0,0,0,0,0,0,0,0,0,0)';$S;BIDI;
    'USB3_5_RXP':'(0,BE69,0,0,0,0,0,0,0,0,0,0,0,0)';$S;BIDI;
    'USB3_5_TXN':'(0,BK58,0,0,0,0,0,0,0,0,0,0,0,0)';$S;BIDI;
    'USB3_5_TXP':'(0,BJ59,0,0,0,0,0,0,0,0,0,0,0,0)';$S;BIDI;
    'USB3_6_RXN':'(0,BD72,0,0,0,0,0,0,0,0,0,0,0,0)';$S;BIDI;
    'USB3_6_RXP':'(0,BD70,0,0,0,0,0,0,0,0,0,0,0,0)';$S;BIDI;
    'USB3_6_TXN':'(0,BL59,0,0,0,0,0,0,0,0,0,0,0,0)';$S;BIDI;
    'USB3_6_TXP':'(0,BM61,0,0,0,0,0,0,0,0,0,0,0,0)';$S;BIDI;
    'USB3_7_PCIE0_RXN':'(0,0,BA71,0,0,0,0,0,0,0,0,0,0,0)';$S;BIDI;
    'USB3_7_PCIE0_RXP':'(0,0,BA69,0,0,0,0,0,0,0,0,0,0,0)';$S;BIDI;
    'USB3_7_PCIE0_TXN':'(0,0,BR61,0,0,0,0,0,0,0,0,0,0,0)';$S;BIDI;
    'USB3_7_PCIE0_TXP':'(0,0,BN63,0,0,0,0,0,0,0,0,0,0,0)';$S;BIDI;
    'USB3_8_PCIE1_RXN':'(0,0,AY72,0,0,0,0,0,0,0,0,0,0,0)';$S;BIDI;
    'USB3_8_PCIE1_RXP':'(0,0,AY70,0,0,0,0,0,0,0,0,0,0,0)';$S;BIDI;
    'USB3_8_PCIE1_TXN':'(0,0,BM65,0,0,0,0,0,0,0,0,0,0,0)';$S;BIDI;
    'USB3_8_PCIE1_TXP':'(0,0,BR65,0,0,0,0,0,0,0,0,0,0,0)';$S;BIDI;
    'USB3_9_PCIE2_RXN':'(0,0,AW71,0,0,0,0,0,0,0,0,0,0,0)';$S;BIDI;
    'USB3_9_PCIE2_RXP':'(0,0,AW69,0,0,0,0,0,0,0,0,0,0,0)';$S;BIDI;
    'USB3_9_PCIE2_TXN':'(0,0,BK65,0,0,0,0,0,0,0,0,0,0,0)';$S;BIDI;
    'USB3_9_PCIE2_TXP':'(0,0,BL66,0,0,0,0,0,0,0,0,0,0,0)';$S;BIDI;
    'VCCA_CLKFILT_1P05'<4>:'(0,0,0,0,0,0,0,0,AE46,0,0,0,0,0)';
    'VCCA_CLKFILT_1P05'<3>:'(0,0,0,0,0,0,0,0,AJ48,0,0,0,0,0)';
    'VCCA_CLKFILT_1P05'<2>:'(0,0,0,0,0,0,0,0,AJ46,0,0,0,0,0)';
    'VCCA_CLKFILT_1P05'<1>:'(0,0,0,0,0,0,0,0,AG45,0,0,0,0,0)';
    'VCCA_CLKFILT_1P05'<0>:'(0,0,0,0,0,0,0,0,W50,0,0,0,0,0)';
    'VCCA_CLKUNF_1P05'<1>:'(0,0,0,0,0,0,0,0,U50,0,0,0,0,0)';
    'VCCA_CLKUNF_1P05'<0>:'(0,0,0,0,0,0,0,0,AH50,0,0,0,0,0)';
    'VCCA_CLKXTAL_1P05':'(0,0,0,0,0,0,0,0,AD50,0,0,0,0,0)';$S;
    'VCCA_PLL0_1P05':'(0,0,0,0,0,0,0,0,AG48,0,0,0,0,0)';$S;
    'VCCA_PLL1_1P05':'(0,0,0,0,0,0,0,0,AE45,0,0,0,0,0)';$S;
    'VCCMPHY_1P05'<13>:'(0,0,0,0,0,0,0,0,0,AE27,0,0,0,0)';
    'VCCMPHY_1P05'<12>:'(0,0,0,0,0,0,0,0,AK43,0,0,0,0,0)';
    'VCCMPHY_1P05'<11>:'(0,0,0,0,0,0,0,0,AK45,0,0,0,0,0)';
    'VCCMPHY_1P05'<10>:'(0,0,0,0,0,0,0,0,AM43,0,0,0,0,0)';
    'VCCMPHY_1P05'<9>:'(0,0,0,0,0,0,0,0,AM45,0,0,0,0,0)';
    'VCCMPHY_1P05'<8>:'(0,0,0,0,0,0,0,0,AP43,0,0,0,0,0)';
    'VCCMPHY_1P05'<7>:'(0,0,0,0,0,0,0,0,AP45,0,0,0,0,0)';
    'VCCMPHY_1P05'<6>:'(0,0,0,0,0,0,0,0,AT43,0,0,0,0,0)';
    'VCCMPHY_1P05'<5>:'(0,0,0,0,0,0,0,0,AT45,0,0,0,0,0)';
    'VCCMPHY_1P05'<4>:'(0,0,0,0,0,0,0,0,AU43,0,0,0,0,0)';
    'VCCMPHY_1P05'<3>:'(0,0,0,0,0,0,0,0,AU45,0,0,0,0,0)';
    'VCCMPHY_1P05'<2>:'(0,0,0,0,0,0,0,0,AJ43,0,0,0,0,0)';
    'VCCMPHY_1P05'<1>:'(0,0,0,0,0,0,0,0,AW43,0,0,0,0,0)';
    'VCCMPHY_1P05'<0>:'(0,0,0,0,0,0,0,0,AW45,0,0,0,0,0)';
    'VCCP10GBEPLL_1P05'<3>:'(0,0,0,0,0,0,0,0,BA39,0,0,0,0,0)';
    'VCCP10GBEPLL_1P05'<2>:'(0,0,0,0,0,0,0,0,BA41,0,0,0,0,0)';
    'VCCP10GBEPLL_1P05'<1>:'(0,0,0,0,0,0,0,0,BB40,0,0,0,0,0)';
    'VCCP10GBEPLL_1P05'<0>:'(0,0,0,0,0,0,0,0,BD38,0,0,0,0,0)';
    'VCCP10GBE_HV_1P8'<1>:'(0,0,0,0,0,0,0,0,BA27,0,0,0,0,0)';
    'VCCP10GBE_HV_1P8'<0>:'(0,0,0,0,0,0,0,0,BA29,0,0,0,0,0)';
    'VCCP10GBE_LV_1P05'<6>:'(0,0,0,0,0,0,0,0,BA30,0,0,0,0,0)';
    'VCCP10GBE_LV_1P05'<5>:'(0,0,0,0,0,0,0,0,BA32,0,0,0,0,0)';
    'VCCP10GBE_LV_1P05'<4>:'(0,0,0,0,0,0,0,0,BA34,0,0,0,0,0)';
    'VCCP10GBE_LV_1P05'<3>:'(0,0,0,0,0,0,0,0,BA36,0,0,0,0,0)';
    'VCCP10GBE_LV_1P05'<2>:'(0,0,0,0,0,0,0,0,BA37,0,0,0,0,0)';
    'VCCP10GBE_LV_1P05'<1>:'(0,0,0,0,0,0,0,0,BB33,0,0,0,0,0)';
    'VCCP10GBE_LV_1P05'<0>:'(0,0,0,0,0,0,0,0,BB37,0,0,0,0,0)';
    'VCCPDSW_3P3':'(0,0,0,0,0,0,0,0,AH24,0,0,0,0,0)';$S;
    'VCCPGPPA':'(0,0,0,0,0,0,0,0,AW24,0,0,0,0,0)';$S;
    'VCCPGPPB':'(0,0,0,0,0,0,0,0,BE26,0,0,0,0,0)';$S;
    'VCCPGPPC':'(0,0,0,0,0,0,0,0,BE40,0,0,0,0,0)';$S;
    'VCCPGPPD':'(0,0,0,0,0,0,0,0,BA43,0,0,0,0,0)';$S;
    'VCCPGPPE':'(0,0,0,0,0,0,0,0,BE44,0,0,0,0,0)';$S;
    'VCCPGPPF':'(0,0,0,0,0,0,0,0,AU27,0,0,0,0,0)';$S;
    'VCCPGPPG':'(0,0,0,0,0,0,0,0,BA26,0,0,0,0,0)';$S;
    'VCCPGPPH':'(0,0,0,0,0,0,0,0,BA24,0,0,0,0,0)';$S;
    'VCCPGPPJ':'(0,0,0,0,0,0,0,0,BB26,0,0,0,0,0)';$S;
    'VCCPGPPK':'(0,0,0,0,0,0,0,0,AU24,0,0,0,0,0)';$S;
    'VCCPGPP_1P8'<6>:'(0,0,0,0,0,0,0,0,AK24,0,0,0,0,0)';
    'VCCPGPP_1P8'<5>:'(0,0,0,0,0,0,0,0,AW27,0,0,0,0,0)';
    'VCCPGPP_1P8'<4>:'(0,0,0,0,0,0,0,0,AP29,0,0,0,0,0)';
    'VCCPGPP_1P8'<3>:'(0,0,0,0,0,0,0,0,AM29,0,0,0,0,0)';
    'VCCPGPP_1P8'<2>:'(0,0,0,0,0,0,0,0,AT29,0,0,0,0,0)';
    'VCCPGPP_1P8'<1>:'(0,0,0,0,0,0,0,0,AW29,0,0,0,0,0)';
    'VCCPGPP_1P8'<0>:'(0,0,0,0,0,0,0,0,AU29,0,0,0,0,0)';
    'VCCPHDA_1P8':'(0,0,0,0,0,0,0,0,AG27,0,0,0,0,0)';$S;
    'VCCPRIM_1P05'<19>:'(0,0,0,0,0,0,0,0,Y26,0,0,0,0,0)';
    'VCCPRIM_1P05'<18>:'(0,0,0,0,0,0,0,0,AA24,0,0,0,0,0)';
    'VCCPRIM_1P05'<17>:'(0,0,0,0,0,0,0,0,AK27,0,0,0,0,0)';
    'VCCPRIM_1P05'<16>:'(0,0,0,0,0,0,0,0,R42,0,0,0,0,0)';
    'VCCPRIM_1P05'<15>:'(0,0,0,0,0,0,0,0,R46,0,0,0,0,0)';
    'VCCPRIM_1P05'<14>:'(0,0,0,0,0,0,0,0,T44,0,0,0,0,0)';
    'VCCPRIM_1P05'<13>:'(0,0,0,0,0,0,0,0,U46,0,0,0,0,0)';
    'VCCPRIM_1P05'<12>:'(0,0,0,0,0,0,0,0,V44,0,0,0,0,0)';
    'VCCPRIM_1P05'<11>:'(0,0,0,0,0,0,0,0,Y45,0,0,0,0,0)';
    'VCCPRIM_1P05'<10>:'(0,0,0,0,0,0,0,0,Y46,0,0,0,0,0)';
    'VCCPRIM_1P05'<9>:'(0,0,0,0,0,0,0,0,AA45,0,0,0,0,0)';
    'VCCPRIM_1P05'<8>:'(0,0,0,0,0,0,0,0,AA46,0,0,0,0,0)';
    'VCCPRIM_1P05'<7>:'(0,0,0,0,0,0,0,0,AC26,0,0,0,0,0)';
    'VCCPRIM_1P05'<6>:'(0,0,0,0,0,0,0,0,AJ29,0,0,0,0,0)';
    'VCCPRIM_1P05'<5>:'(0,0,0,0,0,0,0,0,AM27,0,0,0,0,0)';
    'VCCPRIM_1P05'<4>:'(0,0,0,0,0,0,0,0,AT39,0,0,0,0,0)';
    'VCCPRIM_1P05'<3>:'(0,0,0,0,0,0,0,0,AU37,0,0,0,0,0)';
    'VCCPRIM_1P05'<2>:'(0,0,0,0,0,0,0,0,AU39,0,0,0,0,0)';
    'VCCPRIM_1P05'<1>:'(0,0,0,0,0,0,0,0,BE48,0,0,0,0,0)';
    'VCCPRIM_1P05'<0>:'(0,0,0,0,0,0,0,0,BF46,0,0,0,0,0)';
    'VCCPRIM_AVID'<62>:'(0,0,0,0,0,0,0,0,0,AK32,0,0,0,0)';
    'VCCPRIM_AVID'<61>:'(0,0,0,0,0,0,0,0,0,U31,0,0,0,0)';
    'VCCPRIM_AVID'<60>:'(0,0,0,0,0,0,0,0,0,U35,0,0,0,0)';
    'VCCPRIM_AVID'<59>:'(0,0,0,0,0,0,0,0,0,U38,0,0,0,0)';
    'VCCPRIM_AVID'<58>:'(0,0,0,0,0,0,0,0,0,V29,0,0,0,0)';
    'VCCPRIM_AVID'<57>:'(0,0,0,0,0,0,0,0,0,V33,0,0,0,0)';
    'VCCPRIM_AVID'<56>:'(0,0,0,0,0,0,0,0,0,V40,0,0,0,0)';
    'VCCPRIM_AVID'<55>:'(0,0,0,0,0,0,0,0,0,Y29,0,0,0,0)';
    'VCCPRIM_AVID'<54>:'(0,0,0,0,0,0,0,0,0,Y30,0,0,0,0)';
    'VCCPRIM_AVID'<53>:'(0,0,0,0,0,0,0,0,0,Y32,0,0,0,0)';
    'VCCPRIM_AVID'<52>:'(0,0,0,0,0,0,0,0,0,Y34,0,0,0,0)';
    'VCCPRIM_AVID'<51>:'(0,0,0,0,0,0,0,0,0,Y36,0,0,0,0)';
    'VCCPRIM_AVID'<50>:'(0,0,0,0,0,0,0,0,0,Y37,0,0,0,0)';
    'VCCPRIM_AVID'<49>:'(0,0,0,0,0,0,0,0,0,Y39,0,0,0,0)';
    'VCCPRIM_AVID'<48>:'(0,0,0,0,0,0,0,0,0,Y41,0,0,0,0)';
    'VCCPRIM_AVID'<47>:'(0,0,0,0,0,0,0,0,0,AA29,0,0,0,0)';
    'VCCPRIM_AVID'<46>:'(0,0,0,0,0,0,0,0,0,AA30,0,0,0,0)';
    'VCCPRIM_AVID'<45>:'(0,0,0,0,0,0,0,0,0,AA32,0,0,0,0)';
    'VCCPRIM_AVID'<44>:'(0,0,0,0,0,0,0,0,0,AA34,0,0,0,0)';
    'VCCPRIM_AVID'<43>:'(0,0,0,0,0,0,0,0,0,AA36,0,0,0,0)';
    'VCCPRIM_AVID'<42>:'(0,0,0,0,0,0,0,0,0,AA37,0,0,0,0)';
    'VCCPRIM_AVID'<41>:'(0,0,0,0,0,0,0,0,0,AA39,0,0,0,0)';
    'VCCPRIM_AVID'<40>:'(0,0,0,0,0,0,0,0,0,AA41,0,0,0,0)';
    'VCCPRIM_AVID'<39>:'(0,0,0,0,0,0,0,0,0,AC29,0,0,0,0)';
    'VCCPRIM_AVID'<38>:'(0,0,0,0,0,0,0,0,0,AC30,0,0,0,0)';
    'VCCPRIM_AVID'<37>:'(0,0,0,0,0,0,0,0,0,AC32,0,0,0,0)';
    'VCCPRIM_AVID'<36>:'(0,0,0,0,0,0,0,0,0,AC34,0,0,0,0)';
    'VCCPRIM_AVID'<35>:'(0,0,0,0,0,0,0,0,0,AC36,0,0,0,0)';
    'VCCPRIM_AVID'<34>:'(0,0,0,0,0,0,0,0,0,AC37,0,0,0,0)';
    'VCCPRIM_AVID'<33>:'(0,0,0,0,0,0,0,0,0,AC39,0,0,0,0)';
    'VCCPRIM_AVID'<32>:'(0,0,0,0,0,0,0,0,0,AC41,0,0,0,0)';
    'VCCPRIM_AVID'<31>:'(0,0,0,0,0,0,0,0,0,U27,0,0,0,0)';
    'VCCPRIM_AVID'<30>:'(0,0,0,0,0,0,0,0,0,AE30,0,0,0,0)';
    'VCCPRIM_AVID'<29>:'(0,0,0,0,0,0,0,0,0,AE32,0,0,0,0)';
    'VCCPRIM_AVID'<28>:'(0,0,0,0,0,0,0,0,0,AE34,0,0,0,0)';
    'VCCPRIM_AVID'<27>:'(0,0,0,0,0,0,0,0,0,AE36,0,0,0,0)';
    'VCCPRIM_AVID'<26>:'(0,0,0,0,0,0,0,0,0,AE37,0,0,0,0)';
    'VCCPRIM_AVID'<25>:'(0,0,0,0,0,0,0,0,0,AE39,0,0,0,0)';
    'VCCPRIM_AVID'<24>:'(0,0,0,0,0,0,0,0,0,AE41,0,0,0,0)';
    'VCCPRIM_AVID'<23>:'(0,0,0,0,0,0,0,0,0,AG32,0,0,0,0)';
    'VCCPRIM_AVID'<22>:'(0,0,0,0,0,0,0,0,0,AG34,0,0,0,0)';
    'VCCPRIM_AVID'<21>:'(0,0,0,0,0,0,0,0,0,AG36,0,0,0,0)';
    'VCCPRIM_AVID'<20>:'(0,0,0,0,0,0,0,0,0,AG37,0,0,0,0)';
    'VCCPRIM_AVID'<19>:'(0,0,0,0,0,0,0,0,0,AG39,0,0,0,0)';
    'VCCPRIM_AVID'<18>:'(0,0,0,0,0,0,0,0,0,AK34,0,0,0,0)';
    'VCCPRIM_AVID'<17>:'(0,0,0,0,0,0,0,0,0,AK37,0,0,0,0)';
    'VCCPRIM_AVID'<16>:'(0,0,0,0,0,0,0,0,0,AK39,0,0,0,0)';
    'VCCPRIM_AVID'<15>:'(0,0,0,0,0,0,0,0,0,AM32,0,0,0,0)';
    'VCCPRIM_AVID'<14>:'(0,0,0,0,0,0,0,0,0,AM34,0,0,0,0)';
    'VCCPRIM_AVID'<13>:'(0,0,0,0,0,0,0,0,0,AM36,0,0,0,0)';
    'VCCPRIM_AVID'<12>:'(0,0,0,0,0,0,0,0,0,AM37,0,0,0,0)';
    'VCCPRIM_AVID'<11>:'(0,0,0,0,0,0,0,0,0,AM39,0,0,0,0)';
    'VCCPRIM_AVID'<10>:'(0,0,0,0,0,0,0,0,0,AP32,0,0,0,0)';
    'VCCPRIM_AVID'<9>:'(0,0,0,0,0,0,0,0,0,AP34,0,0,0,0)';
    'VCCPRIM_AVID'<8>:'(0,0,0,0,0,0,0,0,0,AP36,0,0,0,0)';
    'VCCPRIM_AVID'<7>:'(0,0,0,0,0,0,0,0,0,AP37,0,0,0,0)';
    'VCCPRIM_AVID'<6>:'(0,0,0,0,0,0,0,0,0,AP39,0,0,0,0)';
    'VCCPRIM_AVID'<5>:'(0,0,0,0,0,0,0,0,0,AT32,0,0,0,0)';
    'VCCPRIM_AVID'<4>:'(0,0,0,0,0,0,0,0,0,AT34,0,0,0,0)';
    'VCCPRIM_AVID'<3>:'(0,0,0,0,0,0,0,0,0,AT36,0,0,0,0)';
    'VCCPRIM_AVID'<2>:'(0,0,0,0,0,0,0,0,0,AU32,0,0,0,0)';
    'VCCPRIM_AVID'<1>:'(0,0,0,0,0,0,0,0,0,AU34,0,0,0,0)';
    'VCCPRIM_AVID'<0>:'(0,0,0,0,0,0,0,0,0,AU36,0,0,0,0)';
    'VCCPRIM_AVID_QAT_SENSE':'(0,0,0,0,0,0,0,0,0,V37,0,0,0,0)';$S;
    'VCCPRIM_AVID_SENSE':'(0,0,0,0,0,0,0,0,0,AK36,0,0,0,0)';$S;BIDI;
    'VCCPRTC':'(0,0,0,0,0,0,0,0,AJ27,0,0,0,0,0)';$S;
    'VCCPRTCPRIM_3P3':'(0,0,0,0,0,0,0,0,AG29,0,0,0,0,0)';$S;
    'VCCPSPI':'(0,0,0,0,0,0,0,0,AR24,0,0,0,0,0)';$S;
    'VCCPSPI_1P8':'(0,0,0,0,0,0,0,0,AK29,0,0,0,0,0)';$S;
    'VCCPUSBDSW_3P3':'(0,0,0,0,0,0,0,0,BA48,0,0,0,0,0)';$S;
    'VCCP_1P8'<1>:'(0,0,0,0,0,0,0,0,AE26,0,0,0,0,0)';
    'VCCP_1P8'<0>:'(0,0,0,0,0,0,0,0,BD46,0,0,0,0,0)';
    'VCCP_3P3'<5>:'(0,0,0,0,0,0,0,0,AN24,0,0,0,0,0)';
    'VCCP_3P3'<2>:'(0,0,0,0,0,0,0,0,AD24,0,0,0,0,0)';
    'VCCP_3P3'<1>:'(0,0,0,0,0,0,0,0,BA45,0,0,0,0,0)';
    'VCCP_3P3'<0>:'(0,0,0,0,0,0,0,0,BA46,0,0,0,0,0)';
    'VCCP_HSIOPLLUNF_1P05':'(0,0,0,0,0,0,0,0,AT48,0,0,0,0,0)';$S;
    'VCCP_HSIOPLL_1P05'<3>:'(0,0,0,0,0,0,0,0,AP48,0,0,0,0,0)';
    'VCCP_HSIOPLL_1P05'<2>:'(0,0,0,0,0,0,0,0,AU48,0,0,0,0,0)';
    'VCCP_HSIOPLL_1P05'<0>:'(0,0,0,0,0,0,0,0,AW48,0,0,0,0,0)';
    'VCCP_UPPLLUNF_1P05':'(0,0,0,0,0,0,0,0,AM48,0,0,0,0,0)';$S;
    'VCCP_UPPLL_1P05'<2>:'(0,0,0,0,0,0,0,0,AK50,0,0,0,0,0)';
    'VCCP_UPPLL_1P05'<0>:'(0,0,0,0,0,0,0,0,AN50,0,0,0,0,0)';
    'VCCRTCEXT':'(0,0,0,0,0,0,0,0,AG22,0,0,0,0,0)';$S;
    'VSS'<494>:'(0,0,0,0,0,0,0,0,0,0,BP69,0,0,0)';
    'VSS'<493>:'(0,0,0,0,0,0,0,0,0,0,BT69,0,0,0)';
    'VSS'<492>:'(0,0,0,0,0,0,0,0,0,0,BU70,0,0,0)';
    'VSS'<491>:'(0,0,0,0,0,0,0,0,0,0,BR70,0,0,0)';
    'VSS'<490>:'(0,0,0,0,0,0,0,0,0,0,F70,0,0,0)';
    'VSS'<489>:'(0,0,0,0,0,0,0,0,0,0,E70,0,0,0)';
    'VSS'<488>:'(0,0,0,0,0,0,0,0,0,0,BU3,0,0,0)';
    'VSS'<487>:'(0,0,0,0,0,0,0,0,0,0,BR3,0,0,0)';
    'VSS'<486>:'(0,0,0,0,0,0,0,0,0,0,F3,0,0,0)';
    'VSS'<485>:'(0,0,0,0,0,0,0,0,0,0,E3,0,0,0)';
    'VSS'<484>:'(0,0,0,0,0,0,0,0,0,0,A5,0,0,0)';
    'VSS'<483>:'(0,0,0,0,0,0,0,0,0,0,A7,0,0,0)';
    'VSS'<482>:'(0,0,0,0,0,0,0,0,0,0,A9,0,0,0)';
    'VSS'<481>:'(0,0,0,0,0,0,0,0,0,0,A65,0,0,0)';
    'VSS'<480>:'(0,0,0,0,0,0,0,0,0,0,A66,0,0,0)';
    'VSS'<479>:'(0,0,0,0,0,0,0,0,0,0,A68,0,0,0)';
    'VSS'<478>:'(0,0,0,0,0,0,0,0,0,0,J1,0,0,0)';
    'VSS'<477>:'(0,0,0,0,0,0,0,0,0,0,J72,0,0,0)';
    'VSS'<476>:'(0,0,0,0,0,0,0,0,0,0,BN1,0,0,0)';
    'VSS'<475>:'(0,0,0,0,0,0,0,0,0,0,BN72,0,0,0)';
    'VSS'<474>:'(0,0,0,0,0,0,0,0,0,0,CA68,0,0,0)';
    'VSS'<473>:'(0,0,0,0,0,0,0,0,0,0,CA66,0,0,0)';
    'VSS'<472>:'(0,0,0,0,0,0,0,0,0,0,CA65,0,0,0)';
    'VSS'<471>:'(0,0,0,0,0,0,0,0,0,0,CA9,0,0,0)';
    'VSS'<470>:'(0,0,0,0,0,0,0,0,0,0,CA7,0,0,0)';
    'VSS'<469>:'(0,0,0,0,0,0,0,0,0,0,CA5,0,0,0)';
    'VSS'<468>:'(0,0,0,0,0,0,0,0,0,0,A70,0,0,0)';
    'VSS'<467>:'(0,0,0,0,0,0,0,0,0,0,CA3,0,0,0)';
    'VSS'<466>:'(0,0,0,0,0,0,0,0,0,0,BW1,0,0,0)';
    'VSS'<465>:'(0,0,0,0,0,0,0,0,0,0,BU1,0,0,0)';
    'VSS'<464>:'(0,0,0,0,0,0,0,0,0,0,BR1,0,0,0)';
    'VSS'<463>:'(0,0,0,0,0,0,0,0,0,0,C3,0,0,0)';
    'VSS'<462>:'(0,0,0,0,0,0,0,0,0,0,C72,0,0,0)';
    'VSS'<461>:'(0,0,0,0,0,0,0,0,0,0,E1,0,0,0)';
    'VSS'<460>:'(0,0,0,0,0,0,0,0,0,0,E72,0,0,0)';
    'VSS'<459>:'(0,0,0,0,0,0,0,0,0,0,G1,0,0,0)';
    'VSS'<458>:'(0,0,0,0,0,0,0,0,0,0,G72,0,0,0)';
    'VSS'<457>:'(0,0,0,0,0,0,0,0,0,0,BR72,0,0,0)';
    'VSS'<456>:'(0,0,0,0,0,0,0,0,0,0,BU72,0,0,0)';
    'VSS'<455>:'(0,0,0,0,0,0,0,0,0,0,BW70,0,0,0)';
    'VSS'<454>:'(0,0,0,0,0,0,0,0,0,0,BW72,0,0,0)';
    'VSS'<453>:'(0,0,0,0,0,0,0,0,0,0,CA70,0,0,0)';
    'VSS'<452>:'(0,0,0,0,0,0,0,0,0,0,BB48,0,0,0)';
    'VSS'<451>:'(0,0,0,0,0,0,0,0,0,0,AT37,0,0,0)';
    'VSS'<450>:'(0,0,0,0,0,0,0,0,0,0,Y72,0,0,0)';
    'VSS'<449>:'(0,0,0,0,0,0,0,0,0,0,Y70,0,0,0)';
    'VSS'<448>:'(0,0,0,0,0,0,0,0,0,0,A18,0,0,0)';
    'VSS'<447>:'(0,0,0,0,0,0,0,0,0,0,A22,0,0,0)';
    'VSS'<446>:'(0,0,0,0,0,0,0,0,0,0,A30,0,0,0)';
    'VSS'<445>:'(0,0,0,0,0,0,0,0,0,0,A34,0,0,0)';
    'VSS'<444>:'(0,0,0,0,0,0,0,0,0,0,A37,0,0,0)';
    'VSS'<443>:'(0,0,0,0,0,0,0,0,0,0,A41,0,0,0)';
    'VSS'<442>:'(0,0,0,0,0,0,0,0,0,0,B12,0,0,0)';
    'VSS'<441>:'(0,0,0,0,0,0,0,0,0,0,B19,0,0,0)';
    'VSS'<440>:'(0,0,0,0,0,0,0,0,0,0,B25,0,0,0)';
    'VSS'<439>:'(0,0,0,0,0,0,0,0,0,0,B27,0,0,0)';
    'VSS'<438>:'(0,0,0,0,0,0,0,0,0,0,B47,0,0,0)';
    'VSS'<437>:'(0,0,0,0,0,0,0,0,0,0,C22,0,0,0)';
    'VSS'<436>:'(0,0,0,0,0,0,0,0,0,0,C30,0,0,0)';
    'VSS'<435>:'(0,0,0,0,0,0,0,0,0,0,C34,0,0,0)';
    'VSS'<434>:'(0,0,0,0,0,0,0,0,0,0,C37,0,0,0)';
    'VSS'<433>:'(0,0,0,0,0,0,0,0,0,0,C41,0,0,0)';
    'VSS'<432>:'(0,0,0,0,0,0,0,0,0,0,C65,0,0,0)';
    'VSS'<431>:'(0,0,0,0,0,0,0,0,0,0,D12,0,0,0)';
    'VSS'<430>:'(0,0,0,0,0,0,0,0,0,0,D16,0,0,0)';
    'VSS'<429>:'(0,0,0,0,0,0,0,0,0,0,D19,0,0,0)';
    'VSS'<428>:'(0,0,0,0,0,0,0,0,0,0,D25,0,0,0)';
    'VSS'<427>:'(0,0,0,0,0,0,0,0,0,0,D27,0,0,0)';
    'VSS'<426>:'(0,0,0,0,0,0,0,0,0,0,E59,0,0,0)';
    'VSS'<425>:'(0,0,0,0,0,0,0,0,0,0,E65,0,0,0)';
    'VSS'<424>:'(0,0,0,0,0,0,0,0,0,0,D47,0,0,0)';
    'VSS'<423>:'(0,0,0,0,0,0,0,0,0,0,E11,0,0,0)';
    'VSS'<422>:'(0,0,0,0,0,0,0,0,0,0,E13,0,0,0)';
    'VSS'<421>:'(0,0,0,0,0,0,0,0,0,0,E15,0,0,0)';
    'VSS'<420>:'(0,0,0,0,0,0,0,0,0,0,E20,0,0,0)';
    'VSS'<419>:'(0,0,0,0,0,0,0,0,0,0,E22,0,0,0)';
    'VSS'<418>:'(0,0,0,0,0,0,0,0,0,0,E24,0,0,0)';
    'VSS'<417>:'(0,0,0,0,0,0,0,0,0,0,E26,0,0,0)';
    'VSS'<416>:'(0,0,0,0,0,0,0,0,0,0,E28,0,0,0)';
    'VSS'<415>:'(0,0,0,0,0,0,0,0,0,0,E30,0,0,0)';
    'VSS'<414>:'(0,0,0,0,0,0,0,0,0,0,E32,0,0,0)';
    'VSS'<413>:'(0,0,0,0,0,0,0,0,0,0,E34,0,0,0)';
    'VSS'<412>:'(0,0,0,0,0,0,0,0,0,0,E37,0,0,0)';
    'VSS'<411>:'(0,0,0,0,0,0,0,0,0,0,E39,0,0,0)';
    'VSS'<410>:'(0,0,0,0,0,0,0,0,0,0,E41,0,0,0)';
    'VSS'<409>:'(0,0,0,0,0,0,0,0,0,0,E43,0,0,0)';
    'VSS'<408>:'(0,0,0,0,0,0,0,0,0,0,E45,0,0,0)';
    'VSS'<407>:'(0,0,0,0,0,0,0,0,0,0,E48,0,0,0)';
    'VSS'<406>:'(0,0,0,0,0,0,0,0,0,0,E50,0,0,0)';
    'VSS'<405>:'(0,0,0,0,0,0,0,0,0,0,E52,0,0,0)';
    'VSS'<404>:'(0,0,0,0,0,0,0,0,0,0,E54,0,0,0)';
    'VSS'<403>:'(0,0,0,0,0,0,0,0,0,0,E57,0,0,0)';
    'VSS'<402>:'(0,0,0,0,0,0,0,0,0,0,E6,0,0,0)';
    'VSS'<401>:'(0,0,0,0,0,0,0,0,0,0,E61,0,0,0)';
    'VSS'<400>:'(0,0,0,0,0,0,0,0,0,0,E63,0,0,0)';
    'VSS'<399>:'(0,0,0,0,0,0,0,0,0,0,G59,0,0,0)';
    'VSS'<398>:'(0,0,0,0,0,0,0,0,0,0,E9,0,0,0)';
    'VSS'<397>:'(0,0,0,0,0,0,0,0,0,0,G22,0,0,0)';
    'VSS'<396>:'(0,0,0,0,0,0,0,0,0,0,G29,0,0,0)';
    'VSS'<395>:'(0,0,0,0,0,0,0,0,0,0,G37,0,0,0)';
    'VSS'<394>:'(0,0,0,0,0,0,0,0,0,0,G48,0,0,0)';
    'VSS'<393>:'(0,0,0,0,0,0,0,0,0,0,G6,0,0,0)';
    'VSS'<392>:'(0,0,0,0,0,0,0,0,0,0,G63,0,0,0)';
    'VSS'<391>:'(0,0,0,0,0,0,0,0,0,0,G66,0,0,0)';
    'VSS'<390>:'(0,0,0,0,0,0,0,0,0,0,H58,0,0,0)';
    'VSS'<389>:'(0,0,0,0,0,0,0,0,0,0,J29,0,0,0)';
    'VSS'<388>:'(0,0,0,0,0,0,0,0,0,0,J5,0,0,0)';
    'VSS'<387>:'(0,0,0,0,0,0,0,0,0,0,J7,0,0,0)';
    'VSS'<386>:'(0,0,0,0,0,0,0,0,0,0,H65,0,0,0)';
    'VSS'<385>:'(0,0,0,0,0,0,0,0,0,0,J11,0,0,0)';
    'VSS'<384>:'(0,0,0,0,0,0,0,0,0,0,J15,0,0,0)';
    'VSS'<383>:'(0,0,0,0,0,0,0,0,0,0,J22,0,0,0)';
    'VSS'<382>:'(0,0,0,0,0,0,0,0,0,0,J37,0,0,0)';
    'VSS'<381>:'(0,0,0,0,0,0,0,0,0,0,J44,0,0,0)';
    'VSS'<380>:'(0,0,0,0,0,0,0,0,0,0,J59,0,0,0)';
    'VSS'<379>:'(0,0,0,0,0,0,0,0,0,0,J68,0,0,0)';
    'VSS'<378>:'(0,0,0,0,0,0,0,0,0,0,J70,0,0,0)';
    'VSS'<377>:'(0,0,0,0,0,0,0,0,0,0,K54,0,0,0)';
    'VSS'<376>:'(0,0,0,0,0,0,0,0,0,0,K69,0,0,0)';
    'VSS'<375>:'(0,0,0,0,0,0,0,0,0,0,K71,0,0,0)';
    'VSS'<374>:'(0,0,0,0,0,0,0,0,0,0,L5,0,0,0)';
    'VSS'<373>:'(0,0,0,0,0,0,0,0,0,0,L68,0,0,0)';
    'VSS'<372>:'(0,0,0,0,0,0,0,0,0,0,M2,0,0,0)';
    'VSS'<371>:'(0,0,0,0,0,0,0,0,0,0,M22,0,0,0)';
    'VSS'<370>:'(0,0,0,0,0,0,0,0,0,0,M26,0,0,0)';
    'VSS'<369>:'(0,0,0,0,0,0,0,0,0,0,M29,0,0,0)';
    'VSS'<368>:'(0,0,0,0,0,0,0,0,0,0,M33,0,0,0)';
    'VSS'<367>:'(0,0,0,0,0,0,0,0,0,0,M37,0,0,0)';
    'VSS'<366>:'(0,0,0,0,0,0,0,0,0,0,M4,0,0,0)';
    'VSS'<365>:'(0,0,0,0,0,0,0,0,0,0,M40,0,0,0)';
    'VSS'<364>:'(0,0,0,0,0,0,0,0,0,0,N42,0,0,0)';
    'VSS'<363>:'(0,0,0,0,0,0,0,0,0,0,N50,0,0,0)';
    'VSS'<362>:'(0,0,0,0,0,0,0,0,0,0,M44,0,0,0)';
    'VSS'<361>:'(0,0,0,0,0,0,0,0,0,0,M48,0,0,0)';
    'VSS'<360>:'(0,0,0,0,0,0,0,0,0,0,N13,0,0,0)';
    'VSS'<359>:'(0,0,0,0,0,0,0,0,0,0,N17,0,0,0)';
    'VSS'<358>:'(0,0,0,0,0,0,0,0,0,0,N20,0,0,0)';
    'VSS'<357>:'(0,0,0,0,0,0,0,0,0,0,N24,0,0,0)';
    'VSS'<356>:'(0,0,0,0,0,0,0,0,0,0,N27,0,0,0)';
    'VSS'<355>:'(0,0,0,0,0,0,0,0,0,0,N31,0,0,0)';
    'VSS'<354>:'(0,0,0,0,0,0,0,0,0,0,0,N35,0,0)';
    'VSS'<353>:'(0,0,0,0,0,0,0,0,0,0,0,N38,0,0)';
    'VSS'<352>:'(0,0,0,0,0,0,0,0,0,0,0,N46,0,0)';
    'VSS'<351>:'(0,0,0,0,0,0,0,0,0,0,0,N5,0,0)';
    'VSS'<350>:'(0,0,0,0,0,0,0,0,0,0,0,R38,0,0)';
    'VSS'<349>:'(0,0,0,0,0,0,0,0,0,0,0,N68,0,0)';
    'VSS'<348>:'(0,0,0,0,0,0,0,0,0,0,0,N9,0,0)';
    'VSS'<347>:'(0,0,0,0,0,0,0,0,0,0,0,AE43,0,0)';
    'VSS'<346>:'(0,0,0,0,0,0,0,0,0,0,0,P63,0,0)';
    'VSS'<345>:'(0,0,0,0,0,0,0,0,0,0,0,R27,0,0)';
    'VSS'<344>:'(0,0,0,0,0,0,0,0,0,0,0,U42,0,0)';
    'VSS'<343>:'(0,0,0,0,0,0,0,0,0,0,0,R5,0,0)';
    'VSS'<342>:'(0,0,0,0,0,0,0,0,0,0,0,R50,0,0)';
    'VSS'<341>:'(0,0,0,0,0,0,0,0,0,0,0,R54,0,0)';
    'VSS'<340>:'(0,0,0,0,0,0,0,0,0,0,0,T56,0,0)';
    'VSS'<339>:'(0,0,0,0,0,0,0,0,0,0,0,R58,0,0)';
    'VSS'<338>:'(0,0,0,0,0,0,0,0,0,0,0,R68,0,0)';
    'VSS'<337>:'(0,0,0,0,0,0,0,0,0,0,0,T11,0,0)';
    'VSS'<336>:'(0,0,0,0,0,0,0,0,0,0,0,T15,0,0)';
    'VSS'<335>:'(0,0,0,0,0,0,0,0,0,0,0,T18,0,0)';
    'VSS'<334>:'(0,0,0,0,0,0,0,0,0,0,0,T22,0,0)';
    'VSS'<333>:'(0,0,0,0,0,0,0,0,0,0,0,T26,0,0)';
    'VSS'<332>:'(0,0,0,0,0,0,0,0,0,0,0,T29,0,0)';
    'VSS'<331>:'(0,0,0,0,0,0,0,0,0,0,0,T33,0,0)';
    'VSS'<330>:'(0,0,0,0,0,0,0,0,0,0,0,T37,0,0)';
    'VSS'<329>:'(0,0,0,0,0,0,0,0,0,0,0,T40,0,0)';
    'VSS'<328>:'(0,0,0,0,0,0,0,0,0,0,0,AJ45,0,0)';
    'VSS'<327>:'(0,0,0,0,0,0,0,0,0,0,0,T48,0,0)';
    'VSS'<326>:'(0,0,0,0,0,0,0,0,0,0,0,T52,0,0)';
    'VSS'<325>:'(0,0,0,0,0,0,0,0,0,0,0,T66,0,0)';
    'VSS'<324>:'(0,0,0,0,0,0,0,0,0,0,0,T7,0,0)';
    'VSS'<323>:'(0,0,0,0,0,0,0,0,0,0,0,AF50,0,0)';
    'VSS'<322>:'(0,0,0,0,0,0,0,0,0,0,0,AG46,0,0)';
    'VSS'<321>:'(0,0,0,0,0,0,0,0,0,0,0,U58,0,0)';
    'VSS'<320>:'(0,0,0,0,0,0,0,0,0,0,0,V26,0,0)';
    'VSS'<319>:'(0,0,0,0,0,0,0,0,0,0,0,V48,0,0)';
    'VSS'<318>:'(0,0,0,0,0,0,0,0,0,0,0,V5,0,0)';
    'VSS'<317>:'(0,0,0,0,0,0,0,0,0,0,0,V52,0,0)';
    'VSS'<316>:'(0,0,0,0,0,0,0,0,0,0,0,W58,0,0)';
    'VSS'<315>:'(0,0,0,0,0,0,0,0,0,0,0,V66,0,0)';
    'VSS'<314>:'(0,0,0,0,0,0,0,0,0,0,0,V68,0,0)';
    'VSS'<313>:'(0,0,0,0,0,0,0,0,0,0,0,W13,0,0)';
    'VSS'<312>:'(0,0,0,0,0,0,0,0,0,0,0,W17,0,0)';
    'VSS'<311>:'(0,0,0,0,0,0,0,0,0,0,0,W20,0,0)';
    'VSS'<310>:'(0,0,0,0,0,0,0,0,0,0,0,W24,0,0)';
    'VSS'<309>:'(0,0,0,0,0,0,0,0,0,0,0,AA50,0,0)';
    'VSS'<308>:'(0,0,0,0,0,0,0,0,0,0,0,Y43,0,0)';
    'VSS'<307>:'(0,0,0,0,0,0,0,0,0,0,0,W61,0,0)';
    'VSS'<306>:'(0,0,0,0,0,0,0,0,0,0,0,W9,0,0)';
    'VSS'<305>:'(0,0,0,0,0,0,0,0,0,0,0,Y22,0,0)';
    'VSS'<304>:'(0,0,0,0,0,0,0,0,0,0,0,Y27,0,0)';
    'VSS'<303>:'(0,0,0,0,0,0,0,0,0,0,0,Y48,0,0)';
    'VSS'<302>:'(0,0,0,0,0,0,0,0,0,0,0,Y5,0,0)';
    'VSS'<301>:'(0,0,0,0,0,0,0,0,0,0,0,Y52,0,0)';
    'VSS'<300>:'(0,0,0,0,0,0,0,0,0,0,0,Y59,0,0)';
    'VSS'<299>:'(0,0,0,0,0,0,0,0,0,0,0,Y63,0,0)';
    'VSS'<298>:'(0,0,0,0,0,0,0,0,0,0,0,Y68,0,0)';
    'VSS'<297>:'(0,0,0,0,0,0,0,0,0,0,0,AA26,0,0)';
    'VSS'<296>:'(0,0,0,0,0,0,0,0,0,0,0,AA27,0,0)';
    'VSS'<295>:'(0,0,0,0,0,0,0,0,0,0,0,AA43,0,0)';
    'VSS'<294>:'(0,0,0,0,0,0,0,0,0,0,0,AA48,0,0)';
    'VSS'<293>:'(0,0,0,0,0,0,0,0,0,0,0,AB5,0,0)';
    'VSS'<292>:'(0,0,0,0,0,0,0,0,0,0,0,AB68,0,0)';
    'VSS'<291>:'(0,0,0,0,0,0,0,0,0,0,0,AB70,0,0)';
    'VSS'<290>:'(0,0,0,0,0,0,0,0,0,0,0,AB72,0,0)';
    'VSS'<289>:'(0,0,0,0,0,0,0,0,0,0,0,AC11,0,0)';
    'VSS'<288>:'(0,0,0,0,0,0,0,0,0,0,0,AC15,0,0)';
    'VSS'<287>:'(0,0,0,0,0,0,0,0,0,0,0,AC18,0,0)';
    'VSS'<286>:'(0,0,0,0,0,0,0,0,0,0,0,AC22,0,0)';
    'VSS'<285>:'(0,0,0,0,0,0,0,0,0,0,0,AC45,0,0)';
    'VSS'<284>:'(0,0,0,0,0,0,0,0,0,0,0,AD58,0,0)';
    'VSS'<283>:'(0,0,0,0,0,0,0,0,0,0,0,AC27,0,0)';
    'VSS'<282>:'(0,0,0,0,0,0,0,0,0,0,0,AC43,0,0)';
    'VSS'<281>:'(0,0,0,0,0,0,0,0,0,0,0,AC46,0,0)';
    'VSS'<280>:'(0,0,0,0,0,0,0,0,0,0,0,AC48,0,0)';
    'VSS'<279>:'(0,0,0,0,0,0,0,0,0,0,0,AC52,0,0)';
    'VSS'<278>:'(0,0,0,0,0,0,0,0,0,0,0,AC59,0,0)';
    'VSS'<277>:'(0,0,0,0,0,0,0,0,0,0,0,AC63,0,0)';
    'VSS'<276>:'(0,0,0,0,0,0,0,0,0,0,0,AC66,0,0)';
    'VSS'<275>:'(0,0,0,0,0,0,0,0,0,0,0,AC7,0,0)';
    'VSS'<274>:'(0,0,0,0,0,0,0,0,0,0,0,AD5,0,0)';
    'VSS'<273>:'(0,0,0,0,0,0,0,0,0,0,0,AD65,0,0)';
    'VSS'<272>:'(0,0,0,0,0,0,0,0,0,0,0,AD68,0,0)';
    'VSS'<271>:'(0,0,0,0,0,0,0,0,0,0,0,AE29,0,0)';
    'VSS'<270>:'(0,0,0,0,0,0,0,0,0,0,0,J18,0,0)';
    'VSS'<269>:'(0,0,0,0,0,0,0,0,0,0,0,AE48,0,0)';
    'VSS'<268>:'(0,0,0,0,0,0,0,0,0,0,0,AE52,0,0)';
    'VSS'<267>:'(0,0,0,0,0,0,0,0,0,0,0,AE56,0,0)';
    'VSS'<266>:'(0,0,0,0,0,0,0,0,0,0,0,AE59,0,0)';
    'VSS'<265>:'(0,0,0,0,0,0,0,0,0,0,0,AE63,0,0)';
    'VSS'<264>:'(0,0,0,0,0,0,0,0,0,0,0,AE66,0,0)';
    'VSS'<263>:'(0,0,0,0,0,0,0,0,0,0,0,AF1,0,0)';
    'VSS'<262>:'(0,0,0,0,0,0,0,0,0,0,0,AF13,0,0)';
    'VSS'<261>:'(0,0,0,0,0,0,0,0,0,0,0,AF5,0,0)';
    'VSS'<260>:'(0,0,0,0,0,0,0,0,0,0,0,AF9,0,0)';
    'VSS'<259>:'(0,0,0,0,0,0,0,0,0,0,0,AF17,0,0)';
    'VSS'<258>:'(0,0,0,0,0,0,0,0,0,0,0,AF24,0,0)';
    'VSS'<257>:'(0,0,0,0,0,0,0,0,0,0,0,AF3,0,0)';
    'VSS'<256>:'(0,0,0,0,0,0,0,0,0,0,0,AF68,0,0)';
    'VSS'<255>:'(0,0,0,0,0,0,0,0,0,0,0,AG26,0,0)';
    'VSS'<254>:'(0,0,0,0,0,0,0,0,0,0,0,AG30,0,0)';
    'VSS'<253>:'(0,0,0,0,0,0,0,0,0,0,0,AG41,0,0)';
    'VSS'<252>:'(0,0,0,0,0,0,0,0,0,0,0,AG43,0,0)';
    'VSS'<251>:'(0,0,0,0,0,0,0,0,0,0,0,AG52,0,0)';
    'VSS'<250>:'(0,0,0,0,0,0,0,0,0,0,0,AG56,0,0)';
    'VSS'<249>:'(0,0,0,0,0,0,0,0,0,0,0,AG59,0,0)';
    'VSS'<248>:'(0,0,0,0,0,0,0,0,0,0,0,AG66,0,0)';
    'VSS'<247>:'(0,0,0,0,0,0,0,0,0,0,0,AH20,0,0)';
    'VSS'<246>:'(0,0,0,0,0,0,0,0,0,0,0,AJ11,0,0)';
    'VSS'<245>:'(0,0,0,0,0,0,0,0,0,0,0,AJ32,0,0)';
    'VSS'<244>:'(0,0,0,0,0,0,0,0,0,0,0,AJ56,0,0)';
    'VSS'<243>:'(0,0,0,0,0,0,0,0,0,0,0,AK30,0,0)';
    'VSS'<242>:'(0,0,0,0,0,0,0,0,0,0,0,AJ15,0,0)';
    'VSS'<241>:'(0,0,0,0,0,0,0,0,0,0,0,AJ18,0,0)';
    'VSS'<240>:'(0,0,0,0,0,0,0,0,0,0,0,AJ22,0,0)';
    'VSS'<239>:'(0,0,0,0,0,0,0,0,0,0,0,AJ26,0,0)';
    'VSS'<238>:'(0,0,0,0,0,0,0,0,0,0,0,AJ30,0,0)';
    'VSS'<237>:'(0,0,0,0,0,0,0,0,0,0,0,AJ34,0,0)';
    'VSS'<236>:'(0,0,0,0,0,0,0,0,0,0,0,AJ36,0,0)';
    'VSS'<235>:'(0,0,0,0,0,0,0,0,0,0,0,AJ37,0,0)';
    'VSS'<234>:'(0,0,0,0,0,0,0,0,0,0,0,AJ39,0,0)';
    'VSS'<233>:'(0,0,0,0,0,0,0,0,0,0,0,AJ41,0,0)';
    'VSS'<232>:'(0,0,0,0,0,0,0,0,0,0,0,AJ5,0,0)';
    'VSS'<231>:'(0,0,0,0,0,0,0,0,0,0,0,AJ52,0,0)';
    'VSS'<230>:'(0,0,0,0,0,0,0,0,0,0,0,AJ59,0,0)';
    'VSS'<229>:'(0,0,0,0,0,0,0,0,0,0,0,AJ66,0,0)';
    'VSS'<228>:'(0,0,0,0,0,0,0,0,0,0,0,AJ68,0,0)';
    'VSS'<227>:'(0,0,0,0,0,0,0,0,0,0,0,AJ7,0,0)';
    'VSS'<226>:'(0,0,0,0,0,0,0,0,0,0,0,AK26,0,0)';
    'VSS'<225>:'(0,0,0,0,0,0,0,0,0,0,0,AK41,0,0)';
    'VSS'<224>:'(0,0,0,0,0,0,0,0,0,0,0,AK46,0,0)';
    'VSS'<223>:'(0,0,0,0,0,0,0,0,0,0,0,AK48,0,0)';
    'VSS'<222>:'(0,0,0,0,0,0,0,0,0,0,0,AK58,0,0)';
    'VSS'<221>:'(0,0,0,0,0,0,0,0,0,0,0,AK61,0,0)';
    'VSS'<220>:'(0,0,0,0,0,0,0,0,0,0,0,AK69,0,0)';
    'VSS'<219>:'(0,0,0,0,0,0,0,0,0,0,0,AK71,0,0)';
    'VSS'<218>:'(0,0,0,0,0,0,0,0,0,0,0,AL22,0,0)';
    'VSS'<217>:'(0,0,0,0,0,0,0,0,0,0,0,AL5,0,0)';
    'VSS'<216>:'(0,0,0,0,0,0,0,0,0,0,0,AL52,0,0)';
    'VSS'<215>:'(0,0,0,0,0,0,0,0,0,0,0,AL59,0,0)';
    'VSS'<214>:'(0,0,0,0,0,0,0,0,0,0,0,0,AL68,0)';
    'VSS'<213>:'(0,0,0,0,0,0,0,0,0,0,0,0,AL70,0)';
    'VSS'<212>:'(0,0,0,0,0,0,0,0,0,0,0,0,AL72,0)';
    'VSS'<211>:'(0,0,0,0,0,0,0,0,0,0,0,0,AM26,0)';
    'VSS'<210>:'(0,0,0,0,0,0,0,0,0,0,0,0,AM30,0)';
    'VSS'<209>:'(0,0,0,0,0,0,0,0,0,0,0,0,AM41,0)';
    'VSS'<208>:'(0,0,0,0,0,0,0,0,0,0,0,0,AM46,0)';
    'VSS'<207>:'(0,0,0,0,0,0,0,0,0,0,0,0,AN13,0)';
    'VSS'<206>:'(0,0,0,0,0,0,0,0,0,0,0,0,AN17,0)';
    'VSS'<205>:'(0,0,0,0,0,0,0,0,0,0,0,0,AN68,0)';
    'VSS'<204>:'(0,0,0,0,0,0,0,0,0,0,0,0,AP22,0)';
    'VSS'<203>:'(0,0,0,0,0,0,0,0,0,0,0,0,AN20,0)';
    'VSS'<202>:'(0,0,0,0,0,0,0,0,0,0,0,0,AN5,0)';
    'VSS'<201>:'(0,0,0,0,0,0,0,0,0,0,0,0,AN58,0)';
    'VSS'<200>:'(0,0,0,0,0,0,0,0,0,0,0,0,AN9,0)';
    'VSS'<199>:'(0,0,0,0,0,0,0,0,0,0,0,0,AP2,0)';
    'VSS'<198>:'(0,0,0,0,0,0,0,0,0,0,0,0,AP26,0)';
    'VSS'<197>:'(0,0,0,0,0,0,0,0,0,0,0,0,AP30,0)';
    'VSS'<196>:'(0,0,0,0,0,0,0,0,0,0,0,0,AP4,0)';
    'VSS'<195>:'(0,0,0,0,0,0,0,0,0,0,0,0,AP41,0)';
    'VSS'<194>:'(0,0,0,0,0,0,0,0,0,0,0,0,AP46,0)';
    'VSS'<193>:'(0,0,0,0,0,0,0,0,0,0,0,0,AP52,0)';
    'VSS'<192>:'(0,0,0,0,0,0,0,0,0,0,0,0,AP66,0)';
    'VSS'<191>:'(0,0,0,0,0,0,0,0,0,0,0,0,AR5,0)';
    'VSS'<190>:'(0,0,0,0,0,0,0,0,0,0,0,0,AR50,0)';
    'VSS'<189>:'(0,0,0,0,0,0,0,0,0,0,0,0,AR58,0)';
    'VSS'<188>:'(0,0,0,0,0,0,0,0,0,0,0,0,AR65,0)';
    'VSS'<187>:'(0,0,0,0,0,0,0,0,0,0,0,0,AR68,0)';
    'VSS'<186>:'(0,0,0,0,0,0,0,0,0,0,0,0,AR70,0)';
    'VSS'<185>:'(0,0,0,0,0,0,0,0,0,0,0,0,AR72,0)';
    'VSS'<184>:'(0,0,0,0,0,0,0,0,0,0,0,0,AT7,0)';
    'VSS'<183>:'(0,0,0,0,0,0,0,0,0,0,0,0,AT11,0)';
    'VSS'<182>:'(0,0,0,0,0,0,0,0,0,0,0,0,AT15,0)';
    'VSS'<181>:'(0,0,0,0,0,0,0,0,0,0,0,0,AT18,0)';
    'VSS'<180>:'(0,0,0,0,0,0,0,0,0,0,0,0,AT22,0)';
    'VSS'<179>:'(0,0,0,0,0,0,0,0,0,0,0,0,AT26,0)';
    'VSS'<178>:'(0,0,0,0,0,0,0,0,0,0,0,0,AT30,0)';
    'VSS'<177>:'(0,0,0,0,0,0,0,0,0,0,0,0,AT41,0)';
    'VSS'<176>:'(0,0,0,0,0,0,0,0,0,0,0,0,AT46,0)';
    'VSS'<175>:'(0,0,0,0,0,0,0,0,0,0,0,0,AT59,0)';
    'VSS'<174>:'(0,0,0,0,0,0,0,0,0,0,0,0,AU26,0)';
    'VSS'<173>:'(0,0,0,0,0,0,0,0,0,0,0,0,AU30,0)';
    'VSS'<172>:'(0,0,0,0,0,0,0,0,0,0,0,0,AE22,0)';
    'VSS'<171>:'(0,0,0,0,0,0,0,0,0,0,0,0,AU41,0)';
    'VSS'<170>:'(0,0,0,0,0,0,0,0,0,0,0,0,AU46,0)';
    'VSS'<169>:'(0,0,0,0,0,0,0,0,0,0,0,0,AU50,0)';
    'VSS'<168>:'(0,0,0,0,0,0,0,0,0,0,0,0,AU54,0)';
    'VSS'<167>:'(0,0,0,0,0,0,0,0,0,0,0,0,AU61,0)';
    'VSS'<166>:'(0,0,0,0,0,0,0,0,0,0,0,0,AV5,0)';
    'VSS'<165>:'(0,0,0,0,0,0,0,0,0,0,0,0,AV22,0)';
    'VSS'<164>:'(0,0,0,0,0,0,0,0,0,0,0,0,AV59,0)';
    'VSS'<163>:'(0,0,0,0,0,0,0,0,0,0,0,0,AV68,0)';
    'VSS'<162>:'(0,0,0,0,0,0,0,0,0,0,0,0,AW9,0)';
    'VSS'<161>:'(0,0,0,0,0,0,0,0,0,0,0,0,AW13,0)';
    'VSS'<160>:'(0,0,0,0,0,0,0,0,0,0,0,0,AW17,0)';
    'VSS'<159>:'(0,0,0,0,0,0,0,0,0,0,0,0,AW26,0)';
    'VSS'<158>:'(0,0,0,0,0,0,0,0,0,0,0,0,AW30,0)';
    'VSS'<157>:'(0,0,0,0,0,0,0,0,0,0,0,0,AW32,0)';
    'VSS'<156>:'(0,0,0,0,0,0,0,0,0,0,0,0,AW34,0)';
    'VSS'<155>:'(0,0,0,0,0,0,0,0,0,0,0,0,AW36,0)';
    'VSS'<154>:'(0,0,0,0,0,0,0,0,0,0,0,0,AW37,0)';
    'VSS'<153>:'(0,0,0,0,0,0,0,0,0,0,0,0,AW39,0)';
    'VSS'<152>:'(0,0,0,0,0,0,0,0,0,0,0,0,AW41,0)';
    'VSS'<151>:'(0,0,0,0,0,0,0,0,0,0,0,0,AW46,0)';
    'VSS'<150>:'(0,0,0,0,0,0,0,0,0,0,0,0,AW50,0)';
    'VSS'<149>:'(0,0,0,0,0,0,0,0,0,0,0,0,AW58,0)';
    'VSS'<148>:'(0,0,0,0,0,0,0,0,0,0,0,0,AW61,0)';
    'VSS'<147>:'(0,0,0,0,0,0,0,0,0,0,0,0,AY5,0)';
    'VSS'<146>:'(0,0,0,0,0,0,0,0,0,0,0,0,AY22,0)';
    'VSS'<145>:'(0,0,0,0,0,0,0,0,0,0,0,0,AY56,0)';
    'VSS'<144>:'(0,0,0,0,0,0,0,0,0,0,0,0,AY63,0)';
    'VSS'<143>:'(0,0,0,0,0,0,0,0,0,0,0,0,AY68,0)';
    'VSS'<142>:'(0,0,0,0,0,0,0,0,0,0,0,0,BA50,0)';
    'VSS'<141>:'(0,0,0,0,0,0,0,0,0,0,0,0,BA54,0)';
    'VSS'<140>:'(0,0,0,0,0,0,0,0,0,0,0,0,BA58,0)';
    'VSS'<139>:'(0,0,0,0,0,0,0,0,0,0,0,0,BB5,0)';
    'VSS'<138>:'(0,0,0,0,0,0,0,0,0,0,0,0,BB7,0)';
    'VSS'<137>:'(0,0,0,0,0,0,0,0,0,0,0,0,BB11,0)';
    'VSS'<136>:'(0,0,0,0,0,0,0,0,0,0,0,0,BB15,0)';
    'VSS'<135>:'(0,0,0,0,0,0,0,0,0,0,0,0,BB18,0)';
    'VSS'<134>:'(0,0,0,0,0,0,0,0,0,0,0,0,BB22,0)';
    'VSS'<133>:'(0,0,0,0,0,0,0,0,0,0,0,0,BB44,0)';
    'VSS'<132>:'(0,0,0,0,0,0,0,0,0,0,0,0,BB59,0)';
    'VSS'<131>:'(0,0,0,0,0,0,0,0,0,0,0,0,BB66,0)';
    'VSS'<130>:'(0,0,0,0,0,0,0,0,0,0,0,0,BB68,0)';
    'VSS'<129>:'(0,0,0,0,0,0,0,0,0,0,0,0,BB70,0)';
    'VSS'<128>:'(0,0,0,0,0,0,0,0,0,0,0,0,BB72,0)';
    'VSS'<127>:'(0,0,0,0,0,0,0,0,0,0,0,0,BC69,0)';
    'VSS'<126>:'(0,0,0,0,0,0,0,0,0,0,0,0,BC71,0)';
    'VSS'<125>:'(0,0,0,0,0,0,0,0,0,0,0,0,BD24,0)';
    'VSS'<124>:'(0,0,0,0,0,0,0,0,0,0,0,0,BD27,0)';
    'VSS'<123>:'(0,0,0,0,0,0,0,0,0,0,0,0,BD31,0)';
    'VSS'<122>:'(0,0,0,0,0,0,0,0,0,0,0,0,BD35,0)';
    'VSS'<121>:'(0,0,0,0,0,0,0,0,0,0,0,0,BD5,0)';
    'VSS'<120>:'(0,0,0,0,0,0,0,0,0,0,0,0,BD50,0)';
    'VSS'<119>:'(0,0,0,0,0,0,0,0,0,0,0,0,BD54,0)';
    'VSS'<118>:'(0,0,0,0,0,0,0,0,0,0,0,0,BD68,0)';
    'VSS'<117>:'(0,0,0,0,0,0,0,0,0,0,0,0,BE29,0)';
    'VSS'<116>:'(0,0,0,0,0,0,0,0,0,0,0,0,BE33,0)';
    'VSS'<115>:'(0,0,0,0,0,0,0,0,0,0,0,0,BE37,0)';
    'VSS'<114>:'(0,0,0,0,0,0,0,0,0,0,0,0,BE56,0)';
    'VSS'<113>:'(0,0,0,0,0,0,0,0,0,0,0,0,BE59,0)';
    'VSS'<112>:'(0,0,0,0,0,0,0,0,0,0,0,0,BE63,0)';
    'VSS'<111>:'(0,0,0,0,0,0,0,0,0,0,0,0,BE66,0)';
    'VSS'<110>:'(0,0,0,0,0,0,0,0,0,0,0,0,BF13,0)';
    'VSS'<109>:'(0,0,0,0,0,0,0,0,0,0,0,0,BF17,0)';
    'VSS'<108>:'(0,0,0,0,0,0,0,0,0,0,0,0,BF54,0)';
    'VSS'<107>:'(0,0,0,0,0,0,0,0,0,0,0,0,BG44,0)';
    'VSS'<106>:'(0,0,0,0,0,0,0,0,0,0,0,0,BF20,0)';
    'VSS'<105>:'(0,0,0,0,0,0,0,0,0,0,0,0,BF24,0)';
    'VSS'<104>:'(0,0,0,0,0,0,0,0,0,0,0,0,BF27,0)';
    'VSS'<103>:'(0,0,0,0,0,0,0,0,0,0,0,0,BF38,0)';
    'VSS'<102>:'(0,0,0,0,0,0,0,0,0,0,0,0,BF42,0)';
    'VSS'<101>:'(0,0,0,0,0,0,0,0,0,0,0,0,BF5,0)';
    'VSS'<100>:'(0,0,0,0,0,0,0,0,0,0,0,0,BF50,0)';
    'VSS'<99>:'(0,0,0,0,0,0,0,0,0,0,0,0,BF58,0)';
    'VSS'<98>:'(0,0,0,0,0,0,0,0,0,0,0,0,BF61,0)';
    'VSS'<97>:'(0,0,0,0,0,0,0,0,0,0,0,0,BF65,0)';
    'VSS'<96>:'(0,0,0,0,0,0,0,0,0,0,0,0,BF68,0)';
    'VSS'<95>:'(0,0,0,0,0,0,0,0,0,0,0,0,BF9,0)';
    'VSS'<94>:'(0,0,0,0,0,0,0,0,0,0,0,0,BG33,0)';
    'VSS'<93>:'(0,0,0,0,0,0,0,0,0,0,0,0,BG48,0)';
    'VSS'<92>:'(0,0,0,0,0,0,0,0,0,0,0,0,BG59,0)';
    'VSS'<91>:'(0,0,0,0,0,0,0,0,0,0,0,0,BG63,0)';
    'VSS'<90>:'(0,0,0,0,0,0,0,0,0,0,0,0,BH27,0)';
    'VSS'<89>:'(0,0,0,0,0,0,0,0,0,0,0,0,BH38,0)';
    'VSS'<88>:'(0,0,0,0,0,0,0,0,0,0,0,0,BH42,0)';
    'VSS'<87>:'(0,0,0,0,0,0,0,0,0,0,0,0,BH46,0)';
    'VSS'<86>:'(0,0,0,0,0,0,0,0,0,0,0,0,BH54,0)';
    'VSS'<85>:'(0,0,0,0,0,0,0,0,0,0,0,0,BJ1,0)';
    'VSS'<84>:'(0,0,0,0,0,0,0,0,0,0,0,0,BJ11,0)';
    'VSS'<83>:'(0,0,0,0,0,0,0,0,0,0,0,0,BJ5,0)';
    'VSS'<82>:'(0,0,0,0,0,0,0,0,0,0,0,0,BJ7,0)';
    'VSS'<81>:'(0,0,0,0,0,0,0,0,0,0,0,0,BJ15,0)';
    'VSS'<80>:'(0,0,0,0,0,0,0,0,0,0,0,0,BJ18,0)';
    'VSS'<79>:'(0,0,0,0,0,0,0,0,0,0,0,0,BJ26,0)';
    'VSS'<78>:'(0,0,0,0,0,0,0,0,0,0,0,0,BJ3,0)';
    'VSS'<77>:'(0,0,0,0,0,0,0,0,0,0,0,0,BJ33,0)';
    'VSS'<76>:'(0,0,0,0,0,0,0,0,0,0,0,0,BJ52,0)';
    'VSS'<75>:'(0,0,0,0,0,0,0,0,0,0,0,0,BJ68,0)';
    'VSS'<74>:'(0,0,0,0,0,0,0,0,0,0,0,0,0,BK24)';
    'VSS'<73>:'(0,0,0,0,0,0,0,0,0,0,0,0,0,BK27)';
    'VSS'<72>:'(0,0,0,0,0,0,0,0,0,0,0,0,0,BK31)';
    'VSS'<71>:'(0,0,0,0,0,0,0,0,0,0,0,0,0,BK35)';
    'VSS'<70>:'(0,0,0,0,0,0,0,0,0,0,0,0,0,BK38)';
    'VSS'<69>:'(0,0,0,0,0,0,0,0,0,0,0,0,0,BK42)';
    'VSS'<68>:'(0,0,0,0,0,0,0,0,0,0,0,0,0,BK50)';
    'VSS'<67>:'(0,0,0,0,0,0,0,0,0,0,0,0,0,BL22)';
    'VSS'<66>:'(0,0,0,0,0,0,0,0,0,0,0,0,0,BL40)';
    'VSS'<65>:'(0,0,0,0,0,0,0,0,0,0,0,0,0,BL68)';
    'VSS'<64>:'(0,0,0,0,0,0,0,0,0,0,0,0,0,BL37)';
    'VSS'<63>:'(0,0,0,0,0,0,0,0,0,0,0,0,0,BL5)';
    'VSS'<62>:'(0,0,0,0,0,0,0,0,0,0,0,0,0,BL63)';
    'VSS'<61>:'(0,0,0,0,0,0,0,0,0,0,0,0,0,BL70)';
    'VSS'<60>:'(0,0,0,0,0,0,0,0,0,0,0,0,0,BL72)';
    'VSS'<59>:'(0,0,0,0,0,0,0,0,0,0,0,0,0,BM13)';
    'VSS'<58>:'(0,0,0,0,0,0,0,0,0,0,0,0,0,BM17)';
    'VSS'<57>:'(0,0,0,0,0,0,0,0,0,0,0,0,0,BN37)';
    'VSS'<56>:'(0,0,0,0,0,0,0,0,0,0,0,0,0,BM46)';
    'VSS'<55>:'(0,0,0,0,0,0,0,0,0,0,0,0,0,BM50)';
    'VSS'<54>:'(0,0,0,0,0,0,0,0,0,0,0,0,0,BM58)';
    'VSS'<53>:'(0,0,0,0,0,0,0,0,0,0,0,0,0,BM69)';
    'VSS'<52>:'(0,0,0,0,0,0,0,0,0,0,0,0,0,BM71)';
    'VSS'<51>:'(0,0,0,0,0,0,0,0,0,0,0,0,0,BM9)';
    'VSS'<50>:'(0,0,0,0,0,0,0,0,0,0,0,0,0,BN22)';
    'VSS'<49>:'(0,0,0,0,0,0,0,0,0,0,0,0,0,BN59)';
    'VSS'<48>:'(0,0,0,0,0,0,0,0,0,0,0,0,0,BN5)';
    'VSS'<47>:'(0,0,0,0,0,0,0,0,0,0,0,0,0,BN52)';
    'VSS'<46>:'(0,0,0,0,0,0,0,0,0,0,0,0,0,BN66)';
    'VSS'<45>:'(0,0,0,0,0,0,0,0,0,0,0,0,0,BR20)';
    'VSS'<44>:'(0,0,0,0,0,0,0,0,0,0,0,0,0,BR50)';
    'VSS'<43>:'(0,0,0,0,0,0,0,0,0,0,0,0,0,BT8)';
    'VSS'<42>:'(0,0,0,0,0,0,0,0,0,0,0,0,0,BR54)';
    'VSS'<41>:'(0,0,0,0,0,0,0,0,0,0,0,0,0,BR58)';
    'VSS'<40>:'(0,0,0,0,0,0,0,0,0,0,0,0,0,BR6)';
    'VSS'<39>:'(0,0,0,0,0,0,0,0,0,0,0,0,0,BT66)';
    'VSS'<38>:'(0,0,0,0,0,0,0,0,0,0,0,0,0,BU13)';
    'VSS'<37>:'(0,0,0,0,0,0,0,0,0,0,0,0,0,BU11)';
    'VSS'<36>:'(0,0,0,0,0,0,0,0,0,0,0,0,0,BV49)';
    'VSS'<35>:'(0,0,0,0,0,0,0,0,0,0,0,0,0,BU15)';
    'VSS'<34>:'(0,0,0,0,0,0,0,0,0,0,0,0,0,BU18)';
    'VSS'<33>:'(0,0,0,0,0,0,0,0,0,0,0,0,0,BU20)';
    'VSS'<32>:'(0,0,0,0,0,0,0,0,0,0,0,0,0,BU22)';
    'VSS'<31>:'(0,0,0,0,0,0,0,0,0,0,0,0,0,BU24)';
    'VSS'<30>:'(0,0,0,0,0,0,0,0,0,0,0,0,0,BU26)';
    'VSS'<29>:'(0,0,0,0,0,0,0,0,0,0,0,0,0,BU28)';
    'VSS'<28>:'(0,0,0,0,0,0,0,0,0,0,0,0,0,BU30)';
    'VSS'<27>:'(0,0,0,0,0,0,0,0,0,0,0,0,0,BU32)';
    'VSS'<26>:'(0,0,0,0,0,0,0,0,0,0,0,0,0,BU34)';
    'VSS'<25>:'(0,0,0,0,0,0,0,0,0,0,0,0,0,BU37)';
    'VSS'<24>:'(0,0,0,0,0,0,0,0,0,0,0,0,0,BU39)';
    'VSS'<23>:'(0,0,0,0,0,0,0,0,0,0,0,0,0,BU41)';
    'VSS'<22>:'(0,0,0,0,0,0,0,0,0,0,0,0,0,BU43)';
    'VSS'<21>:'(0,0,0,0,0,0,0,0,0,0,0,0,0,BU45)';
    'VSS'<20>:'(0,0,0,0,0,0,0,0,0,0,0,0,0,BU48)';
    'VSS'<19>:'(0,0,0,0,0,0,0,0,0,0,0,0,0,BU50)';
    'VSS'<18>:'(0,0,0,0,0,0,0,0,0,0,0,0,0,BU52)';
    'VSS'<17>:'(0,0,0,0,0,0,0,0,0,0,0,0,0,BU54)';
    'VSS'<16>:'(0,0,0,0,0,0,0,0,0,0,0,0,0,BU57)';
    'VSS'<15>:'(0,0,0,0,0,0,0,0,0,0,0,0,0,BU59)';
    'VSS'<14>:'(0,0,0,0,0,0,0,0,0,0,0,0,0,BU61)';
    'VSS'<13>:'(0,0,0,0,0,0,0,0,0,0,0,0,0,BU63)';
    'VSS'<12>:'(0,0,0,0,0,0,0,0,0,0,0,0,0,BU9)';
    'VSS'<11>:'(0,0,0,0,0,0,0,0,0,0,0,0,0,BV40)';
    'VSS'<10>:'(0,0,0,0,0,0,0,0,0,0,0,0,0,BW15)';
    'VSS'<9>:'(0,0,0,0,0,0,0,0,0,0,0,0,0,BW18)';
    'VSS'<8>:'(0,0,0,0,0,0,0,0,0,0,0,0,0,BW26)';
    'VSS'<7>:'(0,0,0,0,0,0,0,0,0,0,0,0,0,BW52)';
    'VSS'<6>:'(0,0,0,0,0,0,0,0,0,0,0,0,0,BY40)';
    'VSS'<5>:'(0,0,0,0,0,0,0,0,0,0,0,0,0,BY49)';
    'VSS'<4>:'(0,0,0,0,0,0,0,0,0,0,0,0,0,CA15)';
    'VSS'<3>:'(0,0,0,0,0,0,0,0,0,0,0,0,0,CA18)';
    'VSS'<2>:'(0,0,0,0,0,0,0,0,0,0,0,0,0,CA26)';
    'VSS'<1>:'(0,0,0,0,0,0,0,0,0,0,0,0,0,CA50)';
    'VSS'<0>:'(0,0,0,0,0,0,0,0,0,0,0,0,0,CA52)';
    'WAKE_N':'(0,0,0,0,K9,0,0,0,0,0,0,0,0,0)';$S;BIDI;
    'XCLK_BIASREF':'(G44,0,0,0,0,0,0,0,0,0,0,0,0,0)';$S;BIDI;
    'XTAL_IN':'(B35,0,0,0,0,0,0,0,0,0,0,0,0,0)';$S;BIDI;
    'XTAL_OUT':'(D35,0,0,0,0,0,0,0,0,0,0,0,0,0)';$S;BIDI;
end_primitive;
primitive 'LCMXO2_A_256BGA-IC,H63395-001';body 'LCMXO2_A';
    'PB3A':'(P4,0,0)';$S;BIDI;
    'PB3B':'(T4,0,0)';$S;BIDI;
    'PB3C':'(T2,0,0)';$S;BIDI;
    'PB3D':'(R3,0,0)';$S;BIDI;
    'PB5A_CSSPIN':'(R5,0,0)';$S;BIDI;
    'PB5B':'(P5,0,0)';$S;BIDI;
    'PB6A':'(T5,0,0)';$S;BIDI;
    'PB6B':'(R6,0,0)';$S;BIDI;
    'PB6C':'(T3,0,0)';$S;BIDI;
    'PB6D':'(R4,0,0)';$S;BIDI;
    'PB8A_MCLK_CCLK':'(P6,0,0)';$S;BIDI;
    'PB8B_SO_SPISO':'(T6,0,0)';$S;BIDI;
    'PB8C':'(N6,0,0)';$S;BIDI;
    'PB8D':'(L7,0,0)';$S;BIDI;
    'PB9A':'(R7,0,0)';$S;BIDI;
    'PB9B':'(P7,0,0)';$S;BIDI;
    'PB9C':'(M7,0,0)';$S;BIDI;
    'PB9D':'(N7,0,0)';$S;BIDI;
    'PB11A_PCLKT2_0':'(T7,0,0)';$S;BIDI;
    'PB11B_PCLKC2_0':'(R8,0,0)';$S;BIDI;
    'PB11C':'(M6,0,0)';$S;BIDI;
    'PB11D':'(L8,0,0)';$S;BIDI;
    'PB12A':'(P8,0,0)';$S;BIDI;
    'PB12B':'(T8,0,0)';$S;BIDI;
    'PB12C':'(N8,0,0)';$S;BIDI;
    'PB12D':'(L9,0,0)';$S;BIDI;
    'PB16A_PCLKT2_1':'(T9,0,0)';$S;BIDI;
    'PB16B_PCLKC2_1':'(P9,0,0)';$S;BIDI;
    'PB16C':'(M8,0,0)';$S;BIDI;
    'PB16D':'(N9,0,0)';$S;BIDI;
    'PB18A':'(R9,0,0)';$S;BIDI;
    'PB18B':'(T10,0,0)';$S;BIDI;
    'PB18C':'(M9,0,0)';$S;BIDI;
    'PB18D':'(L10,0,0)';$S;BIDI;
    'PB19A':'(P10,0,0)';$S;BIDI;
    'PB19B':'(R10,0,0)';$S;BIDI;
    'PB19C':'(N10,0,0)';$S;BIDI;
    'PB19D':'(M11,0,0)';$S;BIDI;
    'PB21A':'(T11,0,0)';$S;BIDI;
    'PB21B':'(P11,0,0)';$S;BIDI;
    'PB21C':'(M10,0,0)';$S;BIDI;
    'PB21D':'(N11,0,0)';$S;BIDI;
    'PB22A':'(R11,0,0)';$S;BIDI;
    'PB22B':'(T12,0,0)';$S;BIDI;
    'PB22C':'(R13,0,0)';$S;BIDI;
    'PB22D':'(T14,0,0)';$S;BIDI;
    'PB24A':'(P12,0,0)';$S;BIDI;
    'PB24B':'(T13,0,0)';$S;BIDI;
    'PB25A_SN':'(R12,0,0)';$S;BIDI;
    'PB25B_SI_SISPI':'(P13,0,0)';$S;BIDI;
    'PB25C':'(T15,0,0)';$S;BIDI;
    'PB25D':'(R14,0,0)';$S;BIDI;
    'PL1A_L_GPLLT_FB':'(D3,0,0)';$S;BIDI;
    'PL1B_L_GPLLC_FB':'(D1,0,0)';$S;BIDI;
    'PL1C':'(B1,0,0)';$S;BIDI;
    'PL1D':'(C2,0,0)';$S;BIDI;
    'PL2A_L_GPLLT_IN':'(E2,0,0)';$S;BIDI;
    'PL2B_L_GPLLC_IN':'(E3,0,0)';$S;BIDI;
    'PL2C':'(C1,0,0)';$S;BIDI;
    'PL2D':'(D2,0,0)';$S;BIDI;
    'PL3A_PCLKT5_0':'(E1,0,0)';$S;BIDI;
    'PL3B_PCLKC5_0':'(F2,0,0)';$S;BIDI;
    'PL3C':'(F4,0,0)';$S;BIDI;
    'PL3D':'(G6,0,0)';$S;BIDI;
    'PL4A':'(F3,0,0)';$S;BIDI;
    'PL4B':'(F1,0,0)';$S;BIDI;
    'PL4C':'(G5,0,0)';$S;BIDI;
    'PL4D':'(G4,0,0)';$S;BIDI;
    'PL5A':'(G2,0,0)';$S;BIDI;
    'PL5B':'(G3,0,0)';$S;BIDI;
    'PL5C':'(F5,0,0)';$S;BIDI;
    'PL5D':'(H6,0,0)';$S;BIDI;
    'PL6A':'(G1,0,0)';$S;BIDI;
    'PL6B':'(H2,0,0)';$S;BIDI;
    'PL6C':'(H4,0,0)';$S;BIDI;
    'PL6D':'(J6,0,0)';$S;BIDI;
    'PL7A':'(H3,0,0)';$S;BIDI;
    'PL7B':'(H1,0,0)';$S;BIDI;
    'PL7C_PCLKT4_0':'(J1,0,0)';$S;BIDI;
    'PL7D_PCLKC4_0':'(J3,0,0)';$S;BIDI;
    'PL9A':'(J2,0,0)';$S;BIDI;
    'PL9B':'(K1,0,0)';$S;BIDI;
    'PL9C':'(H5,0,0)';$S;BIDI;
    'PL9D':'(J4,0,0)';$S;BIDI;
    'PL10A':'(K3,0,0)';$S;BIDI;
    'PL10B':'(K2,0,0)';$S;BIDI;
    'PL10C':'(J5,0,0)';$S;BIDI;
    'PL10D':'(K6,0,0)';$S;BIDI;
    'PL11A':'(L1,0,0)';$S;BIDI;
    'PL11B':'(L3,0,0)';$S;BIDI;
    'PL11C':'(K4,0,0)';$S;BIDI;
    'PL11D':'(L5,0,0)';$S;BIDI;
    'PL12A_PCLKT3_0':'(L2,0,0)';$S;BIDI;
    'PL12B_PCLKC3_0':'(M1,0,0)';$S;BIDI;
    'PL12C':'(K5,0,0)';$S;BIDI;
    'PL12D':'(L4,0,0)';$S;BIDI;
    'PL13A':'(M3,0,0)';$S;BIDI;
    'PL13B':'(N1,0,0)';$S;BIDI;
    'PL13C':'(N2,0,0)';$S;BIDI;
    'PL13D':'(P1,0,0)';$S;BIDI;
    'PL14A':'(M2,0,0)';$S;BIDI;
    'PL14B':'(N3,0,0)';$S;BIDI;
    'PL14C':'(R1,0,0)';$S;BIDI;
    'PL14D':'(P2,0,0)';$S;BIDI;
    'PR1A':'(0,D14,0)';$S;BIDI;
    'PR1B':'(0,E15,0)';$S;BIDI;
    'PR1C':'(0,C15,0)';$S;BIDI;
    'PR1D':'(0,B16,0)';$S;BIDI;
    'PR2A':'(0,D16,0)';$S;BIDI;
    'PR2B':'(0,E14,0)';$S;BIDI;
    'PR2C':'(0,C16,0)';$S;BIDI;
    'PR2D':'(0,D15,0)';$S;BIDI;
    'PR3A':'(0,E16,0)';$S;BIDI;
    'PR3B':'(0,F15,0)';$S;BIDI;
    'PR3C':'(0,F13,0)';$S;BIDI;
    'PR3D':'(0,G12,0)';$S;BIDI;
    'PR4A':'(0,F14,0)';$S;BIDI;
    'PR4B':'(0,F16,0)';$S;BIDI;
    'PR4C':'(0,F12,0)';$S;BIDI;
    'PR4D':'(0,G13,0)';$S;BIDI;
    'PR5A':'(0,G15,0)';$S;BIDI;
    'PR5B':'(0,G14,0)';$S;BIDI;
    'PR5C':'(0,G11,0)';$S;BIDI;
    'PR5D':'(0,H12,0)';$S;BIDI;
    'PR6A':'(0,G16,0)';$S;BIDI;
    'PR6B':'(0,H15,0)';$S;BIDI;
    'PR6C':'(0,H13,0)';$S;BIDI;
    'PR6D':'(0,J12,0)';$S;BIDI;
    'PR7A_PCLKT1_0':'(0,H14,0)';$S;BIDI;
    'PR7B_PCLKC1_0':'(0,H16,0)';$S;BIDI;
    'PR7C':'(0,J16,0)';$S;BIDI;
    'PR7D':'(0,J14,0)';$S;BIDI;
    'PR9A':'(0,J15,0)';$S;BIDI;
    'PR9B':'(0,K16,0)';$S;BIDI;
    'PR9C':'(0,H11,0)';$S;BIDI;
    'PR9D':'(0,J13,0)';$S;BIDI;
    'PR10A':'(0,K14,0)';$S;BIDI;
    'PR10B':'(0,K15,0)';$S;BIDI;
    'PR10C':'(0,J11,0)';$S;BIDI;
    'PR10D':'(0,L12,0)';$S;BIDI;
    'PR11A':'(0,L16,0)';$S;BIDI;
    'PR11B':'(0,L14,0)';$S;BIDI;
    'PR11C':'(0,K13,0)';$S;BIDI;
    'PR11D':'(0,K12,0)';$S;BIDI;
    'PR12A':'(0,L15,0)';$S;BIDI;
    'PR12B':'(0,M16,0)';$S;BIDI;
    'PR12C':'(0,K11,0)';$S;BIDI;
    'PR12D':'(0,L13,0)';$S;BIDI;
    'PR13A':'(0,M14,0)';$S;BIDI;
    'PR13B':'(0,M15,0)';$S;BIDI;
    'PR13C':'(0,N15,0)';$S;BIDI;
    'PR13D':'(0,P16,0)';$S;BIDI;
    'PR14A':'(0,N16,0)';$S;BIDI;
    'PR14B':'(0,N14,0)';$S;BIDI;
    'PR14C':'(0,P15,0)';$S;BIDI;
    'PR14D':'(0,R16,0)';$S;BIDI;
    'PT9A':'(0,C4,0)';$S;BIDI;
    'PT9B':'(0,B5,0)';$S;BIDI;
    'PT9C':'(0,B3,0)';$S;BIDI;
    'PT10A':'(0,A4,0)';$S;BIDI;
    'PT10B':'(0,C5,0)';$S;BIDI;
    'PT11A':'(0,A5,0)';$S;BIDI;
    'PT11B':'(0,B6,0)';$S;BIDI;
    'PT11C':'(0,A3,0)';$S;BIDI;
    'PT11D':'(0,B4,0)';$S;BIDI;
    'PT12A':'(0,D6,0)';$S;BIDI;
    'PT12B':'(0,E7,0)';$S;BIDI;
    'PT12C_TDO':'(0,C6,0)';$S;BIDI;
    'PT12D_TDI':'(0,A6,0)';$S;BIDI;
    'PT13A':'(0,B7,0)';$S;BIDI;
    'PT13B':'(0,C7,0)';$S;BIDI;
    'PT13C':'(0,E6,0)';$S;BIDI;
    'PT13D':'(0,D7,0)';$S;BIDI;
    'PT16A':'(0,F7,0)';$S;BIDI;
    'PT16B':'(0,E8,0)';$S;BIDI;
    'PT16C_TCK':'(0,A7,0)';$S;BIDI;
    'PT16D_TMS':'(0,B8,0)';$S;BIDI;
    'PT17A_PCLKT0_1':'(0,C8,0)';$S;BIDI;
    'PT17B_PCLKC0_1':'(0,A8,0)';$S;BIDI;
    'PT17C':'(0,D8,0)';$S;BIDI;
    'PT17D':'(0,E9,0)';$S;BIDI;
    'PT18A':'(0,F8,0)';$S;BIDI;
    'PT18B':'(0,D9,0)';$S;BIDI;
    'PT18C_SCL_PCLKT0_0':'(0,A9,0)';$S;BIDI;
    'PT18D_SDA_PCLKC0_0':'(0,C9,0)';$S;BIDI;
    'PT19A':'(0,B9,0)';$S;BIDI;
    'PT19B':'(0,A10,0)';$S;BIDI;
    'PT19C':'(0,F9,0)';$S;BIDI;
    'PT19D':'(0,E11,0)';$S;BIDI;
    'PT20A':'(0,D10,0)';$S;BIDI;
    'PT20B':'(0,E10,0)';$S;BIDI;
    'PT20C_JTAGENB':'(0,C10,0)';$S;BIDI;
    'PT20D_PROGRAMN':'(0,B10,0)';$S;BIDI;
    'PT21A':'(0,A11,0)';$S;BIDI;
    'PT21B':'(0,C11,0)';$S;BIDI;
    'PT21C':'(0,F10,0)';$S;BIDI;
    'PT21D':'(0,D11,0)';$S;BIDI;
    'PT22A':'(0,B11,0)';$S;BIDI;
    'PT22B':'(0,A12,0)';$S;BIDI;
    'PT22C':'(0,B13,0)';$S;BIDI;
    'PT22D':'(0,A14,0)';$S;BIDI;
    'PT23A':'(0,C12,0)';$S;BIDI;
    'PT23B':'(0,B12,0)';$S;BIDI;
    'PT24A':'(0,B14,0)';$S;BIDI;
    'PT24B':'(0,A15,0)';$S;BIDI;
    'PT24C_INITN':'(0,A13,0)';$S;BIDI;
    'PT24D_DONE':'(0,C13,0)';$S;BIDI;
    'GND'<0>:'(0,0,B2)';
    'GND'<1>:'(0,0,B15)';
    'GND'<2>:'(0,0,C3)';
    'GND'<3>:'(0,0,C14)';
    'GND'<4>:'(0,0,D4)';
    'GND'<5>:'(0,0,D13)';
    'GND'<6>:'(0,0,E5)';
    'GND'<7>:'(0,0,E12)';
    'GND'<8>:'(0,0,F6)';
    'GND'<9>:'(0,0,F11)';
    'GND'<10>:'(0,0,H8)';
    'GND'<11>:'(0,0,H9)';
    'GND'<12>:'(0,0,J8)';
    'GND'<13>:'(0,0,J9)';
    'GND'<14>:'(0,0,L6)';
    'GND'<15>:'(0,0,L11)';
    'GND'<16>:'(0,0,M5)';
    'GND'<17>:'(0,0,M12)';
    'GND'<18>:'(0,0,N4)';
    'GND'<19>:'(0,0,N13)';
    'GND'<20>:'(0,0,P3)';
    'GND'<21>:'(0,0,P14)';
    'GND'<22>:'(0,0,R2)';
    'GND'<23>:'(0,0,R15)';
    'VCC'<0>:'(0,0,A1)';
    'VCC'<1>:'(0,0,A16)';
    'VCC'<2>:'(0,0,T1)';
    'VCC'<3>:'(0,0,T16)';
    'VCC'<4>:'(0,0,G7)';
    'VCC'<5>:'(0,0,G10)';
    'VCC'<6>:'(0,0,K7)';
    'VCC'<7>:'(0,0,K10)';
    'VCCIO0'<0>:'(0,0,G8)';
    'VCCIO0'<1>:'(0,0,D12)';
    'VCCIO0'<2>:'(0,0,G9)';
    'VCCIO1'<0>:'(0,0,E13)';
    'VCCIO1'<1>:'(0,0,H10)';
    'VCCIO1'<2>:'(0,0,J10)';
    'VCCIO1'<3>:'(0,0,M13)';
    'VCCIO2'<0>:'(0,0,K9)';
    'VCCIO2'<1>:'(0,0,N12)';
    'VCCIO2'<2>:'(0,0,K8)';
    'VCCIO2'<3>:'(0,0,N5)';
    'VCCIO4'<0>:'(0,0,J7)';
    'VCCIO4'<1>:'(0,0,H7)';
    'VCCIO5'<0>:'(0,0,E4)';$S;
    'VCCIO0'<3>:'(0,0,D5)';
    'NC'<0>:'(0,0,A2)';$S;
    'VCCIO3'<0>:'(0,0,M4)';$S;
end_primitive;
primitive 'LED_1NC-BLUE,IC,C96565-012';body 'LED';
    'C':'(1)';
    'A':'(2)';
end_primitive;
primitive 'LED_1NCLF-GREEN,IC,C96565-011';body 'LED';
    'C':'(1)';
    'A':'(2)';
end_primitive;
primitive 'LED_1NCLF-YELLOW,IC,C96565-003';body 'LED';
    'C':'(1)';
    'A':'(2)';
end_primitive;
primitive 'LED_A1-RED,IC,D14725-005';body 'LED';
    'C':'(2)';
    'A':'(1)';
end_primitive;
primitive 'LED_A1LF-GREEN,IC,C97278-010';body 'LED';
    'C':'(2)';
    'A':'(1)';
end_primitive;
primitive 'LED_A1LF-GREEN,IC,D14725-022';body 'LED';
    'C':'(2)';
    'A':'(1)';
end_primitive;
primitive 'LMV331IDCKRG4-GP_DISCRET-G-LMVA';body 'LMV331IDCKRG4-GP';
    '+IN':'(1)';IN;
    '-IN':'(3)';IN;
    'OUT':'(4)';OUT;
    'VCC':'(5)';
    'GND':'(2)';
end_primitive;
primitive 'M25PE16_SM-IC,H77797-001';body 'M25PE16';
    'S_N':'(1)';IN;
    'RESET_N':'(7)';IN;
    'C':'(6)';IN;
    'DQ0':'(5)';IN;
    'DQ1':'(2)';OUT;
    'VCC':'(8)';
    'VSS':'(4)';
    'W_N':'(3)';IN;
end_primitive;
primitive 'MAX9634_SOT-IC,H35789-001';body 'MAX9634';
    'GND'<1>:'(1)';
    'GND'<0>:'(2)';
    'OUT':'(3)';OUT;
    'RSN':'(4)';IN;
    'RSP':'(5)';IN;
end_primitive;
primitive 'MIC5166_DFN-IC,H55101-001';body 'MIC5166';
    'EN':'(7)';IN;
    'VIN':'(10)';
    'VREF':'(1)';OUT;
    'BIAS':'(2)';BIDI;
    'AGND':'(3)';
    'PG':'(5)';OUT;
    'VDDQ':'(4)';
    'SNS':'(6)';IN;
    'PGND':'(8)';
    'VTT':'(9)';OUT;
    'THPAD':'(11)';
end_primitive;
primitive 'MOSFETN_1D3S_SOT5-IC,G68777-001';body 'MOSFETN_1D3S';
    'S1':'(1)';
    'S2':'(2)';
    'S3':'(3)';
    'D':'(5)';
    'G':'(4)';IN;
end_primitive;
primitive 'MOSFET_N_LCC3-BSZ019N03LS,NFETA';body 'MOSFET_N';
    'GATE':'(4)';
    'SRC':'(1)';
    'DRN':'(5)';
end_primitive;
primitive 'MTG_KEYHOLE_TH-EMPTY,NA';body 'MTG_KEYHOLE';
    '1':'(1)';
end_primitive;
primitive 'NB3W1200L_LCC-IC,H13585-001';body 'NB3W1200L';
    'VDDA':'(1)';
    'GNDA':'(2)';
    'NC'<0>:'(3)';
    '100M_133M_N':'(4)';IN;
    'HBW_BYPASS_LOBW_N':'(5)';IN;
    'PWRGD_PWRDN_N':'(6)';IN;
    'GND'<0>:'(7)';
    'VDDR':'(8)';
    'CLK_INP':'(9)';IN;
    'CLK_INN':'(10)';IN;
    'SA_0':'(11)';IN;
    'SDA':'(12)';BIDI;
    'SCL':'(13)';BIDI;
    'SA_1':'(14)';IN;
    'NC'<2>:'(15)';
    'NC'<1>:'(16)';
    'DIF_0P':'(17)';OUT;
    'DIF_0N':'(18)';OUT;
    'OE_0_N':'(19)';IN;
    'OE_1_N':'(20)';IN;
    'DIF_1P':'(21)';OUT;
    'DIF_1N':'(22)';OUT;
    'GND'<1>:'(23)';
    'VDD'<0>:'(24)';
    'VDDIO'<0>:'(25)';
    'DIF_2P':'(26)';OUT;
    'DIF_2N':'(27)';OUT;
    'OE_2_N':'(28)';IN;
    'OE_3_N':'(29)';IN;
    'DIF_3P':'(30)';OUT;
    'DIF_3N':'(31)';OUT;
    'VDDIO'<1>:'(32)';
    'GND'<2>:'(33)';
    'DIF_4P':'(34)';OUT;
    'DIF_4N':'(35)';OUT;
    'OE_4_N':'(36)';IN;
    'OE_5_N':'(37)';IN;
    'DIF_5P':'(38)';OUT;
    'DIF_5N':'(39)';OUT;
    'VDD'<1>:'(40)';
    'GND'<3>:'(41)';
    'DIF_6P':'(42)';OUT;
    'DIF_6N':'(43)';OUT;
    'OE_6_N':'(44)';IN;
    'OE_7_N':'(45)';IN;
    'DIF_7P':'(46)';OUT;
    'DIF_7N':'(47)';OUT;
    'GND'<4>:'(48)';
    'VDDIO'<2>:'(49)';
    'DIF_8P':'(50)';OUT;
    'DIF_8N':'(51)';OUT;
    'OE_8_N':'(52)';IN;
    'OE_9_N':'(53)';IN;
    'DIF_9P':'(54)';OUT;
    'DIF_9N':'(55)';OUT;
    'VDDIO'<3>:'(56)';
    'VDD'<2>:'(57)';
    'GND'<5>:'(58)';
    'DIF_10P':'(59)';OUT;
    'DIF_10N':'(60)';OUT;
    'OE_10_N':'(61)';IN;
    'OE_11_N':'(62)';IN;
    'DIF_11P':'(63)';OUT;
    'DIF_11N':'(64)';OUT;
    'THPAD':'(65)';
end_primitive;
primitive 'NC7SB3157_SMLF-IC,C99406-001';body 'NC7SB3157';
    'S':'(6)';
    'B0':'(3)';
    'B1':'(1)';
    'A':'(4)';
    'VCC':'(5)';
    'GND':'(2)';
end_primitive;
primitive 'NCP3232L_SM-IC,H86355-001';body 'NCP3232L';
    'AGND':'(5)';
    'BST':'(36)';IN;
    'COMP':'(3)';OUT;
    'EN':'(40)';IN;
    'FB':'(2)';BIDI;
    'GND':'(41)';
    'ISET':'(4)';BIDI;
    'OTS':'(6)';IN;
    'PG':'(7)';BIDI;
    'PGND'<13>:'(37)';
    'PGND'<12>:'(28)';
    'PGND'<11>:'(27)';
    'PGND'<10>:'(26)';
    'PGND'<9>:'(25)';
    'PGND'<8>:'(24)';
    'PGND'<7>:'(23)';
    'PGND'<6>:'(22)';
    'PGND'<5>:'(21)';
    'PGND'<4>:'(20)';
    'PGND'<3>:'(19)';
    'PGND'<2>:'(18)';
    'PGND'<1>:'(17)';
    'PGND'<0>:'(16)';
    'SS':'(1)';BIDI;
    'VB':'(38)';OUT;
    'VCC':'(39)';
    'VIN'<7>:'(42)';IN;
    'VIN'<6>:'(14)';IN;
    'VIN'<5>:'(13)';IN;
    'VIN'<4>:'(12)';IN;
    'VIN'<3>:'(11)';IN;
    'VIN'<2>:'(10)';IN;
    'VIN'<1>:'(9)';IN;
    'VIN'<0>:'(8)';IN;
    'VSW':'(35)';BIDI;
    'VSWH'<7>:'(43)';BIDI;
    'VSWH'<6>:'(34)';BIDI;
    'VSWH'<5>:'(33)';BIDI;
    'VSWH'<4>:'(32)';BIDI;
    'VSWH'<3>:'(31)';BIDI;
    'VSWH'<2>:'(30)';BIDI;
    'VSWH'<1>:'(29)';BIDI;
    'VSWH'<0>:'(15)';BIDI;
end_primitive;
primitive 'NPN_DUAL_SSOPLF-MBT3904,EMPTY,A';body 'NPN_DUAL';
    'B'<0>:'(5,2)';$S;
    'C'<0>:'(3,6)';$S;
    'E'<0>:'(4,1)';$S;
end_primitive;
primitive 'NPN_DUAL_SSOPLF-MBT3904,XSTR,CA';body 'NPN_DUAL';
    'B'<0>:'(5,2)';$S;
    'C'<0>:'(3,6)';$S;
    'E'<0>:'(4,1)';$S;
end_primitive;
primitive 'NPN_SM-MMBT3904,IC,C52245-001';body 'NPN';
    'B':'(1)';
    'C':'(3)';
    'E':'(2)';
end_primitive;
primitive 'OSC_C_6P10-156.25MHZ,OSC,G6383A';body 'OSC_C';
    'ENABLE_DISABLE':'(1)';BIDI;
    'NC_GND':'(2)';
    'GND':'(3)';
    'OUT':'(4)';OUT;
    'OUT_N':'(5)';OUT;
    'VCC':'(6)';
end_primitive;
primitive 'OSC_C_SM4-24MHZ,OSC,D34520-021';body 'OSC_C';
    'ENABLE_CONTROL':'(1)';IN;
    'GND':'(2)';
    'OUT':'(3)';OUT;
    'VDD':'(4)';
end_primitive;
primitive 'PCA9515ADGKR-1-GP_DISCRET-G5-PA';body 'PCA9515ADGKR-1-GP';
    'NC#1':'(1)';
    'SCL0':'(2)';BIDI;
    'SDA0':'(3)';BIDI;
    'GND':'(4)';
    'EN':'(5)';IN;
    'SDA1':'(6)';BIDI;
    'SCL1':'(7)';BIDI;
    'VCC':'(8)';
end_primitive;
primitive 'PCA9517_SM-IC,G77073-001-GND=GA';body 'PCA9517';
    'EN':'(5)';IN;
    'SCLA':'(2)';IN;
    'SCLB':'(7)';OUT;
    'SDAA':'(3)';IN;
    'SDAB':'(6)';OUT;
    'VCCA':'(1)';
    'VCCB':'(8)';
end_primitive;
primitive 'PCA9555PWRG4-GP_DISCRET-G5-PCAA';body 'PCA9555PWRG4-GP';
    'INT#':'(1)';OUT;
    'A1':'(2)';IN;
    'A2':'(3)';IN;
    'P0':'(4)';BIDI;
    'P1':'(5)';BIDI;
    'P2':'(6)';BIDI;
    'P3':'(7)';BIDI;
    'P4':'(8)';BIDI;
    'P5':'(9)';BIDI;
    'P6':'(10)';BIDI;
    'P7':'(11)';BIDI;
    'GND':'(12)';
    'P10':'(13)';BIDI;
    'P11':'(14)';BIDI;
    'P12':'(15)';BIDI;
    'P13':'(16)';BIDI;
    'P14':'(17)';BIDI;
    'P15':'(18)';BIDI;
    'P16':'(19)';BIDI;
    'P17':'(20)';BIDI;
    'A0':'(21)';IN;
    'SCL':'(22)';
    'SDA':'(23)';
    'VCC':'(24)';
end_primitive;
primitive 'PCA9617_SSOP-IC,G81764-001-GNDA';body 'PCA9617';
    'EN':'(5)';IN;
    'SCLA':'(2)';IN;
    'SCLB':'(7)';OUT;
    'SDAA':'(3)';IN;
    'SDAB':'(6)';OUT;
    'VCCA':'(1)';
    'VCCB':'(8)';
end_primitive;
primitive 'PI3B3257A_TSSOPLF-IC,E16801-001';body 'PI3B3257A';
    'VCC':'(16)';
    'GND':'(8)';
    'EN':'(15)';IN;
    'S':'(1)';BIDI;
    'YA':'(4)';BIDI;
    'YB':'(7)';BIDI;
    'YC':'(9)';BIDI;
    'YD':'(12)';BIDI;
    'IA0':'(2)';BIDI;
    'IA1':'(3)';BIDI;
    'IB0':'(5)';BIDI;
    'IB1':'(6)';BIDI;
    'IC0':'(11)';BIDI;
    'IC1':'(10)';BIDI;
    'ID0':'(14)';BIDI;
    'ID1':'(13)';BIDI;
end_primitive;
primitive 'PI7C9X1172_QFN-IC,H66899-001';body 'PI7C9X1172';
    'A0_CS_N':'(30)';IN;
    'A1_S1':'(31)';IN;
    'CTSA_N':'(25)';IN;
    'CTSB_N':'(16)';IN;
    'EN485_N':'(19)';IN;
    'ENIR_N':'(18)';IN;
    'GND':'(12)';
    'GPIO0_DSRB_N':'(13)';BIDI;
    'GPIO1_DTRB_N':'(23)';BIDI;
    'GPIO2_CDB_N':'(11)';BIDI;
    'GPIO3_RIB_N':'(14)';BIDI;
    'GPIO4_DSRA_N':'(26)';BIDI;
    'GPIO5_DTRA_N':'(22)';BIDI;
    'GPIO6_CDA_N':'(27)';BIDI;
    'GPIO7_RIA_N':'(28)';BIDI;
    'I2C_SPI_N':'(32)';IN;
    'IRQ_N':'(20)';OUT;
    'NC'<1>:'(8)';
    'NC'<0>:'(1)';
    'RESET_N':'(24)';IN;
    'RTSA_N':'(21)';OUT;
    'RTSB_N':'(15)';OUT;
    'RXA':'(5)';IN;
    'RXB':'(4)';IN;
    'SCL':'(17)';IN;
    'SDA':'(3)';BIDI;
    'SO':'(2)';OUT;
    'THPAD':'(33)';
    'TXA':'(6)';OUT;
    'TXB':'(7)';OUT;
    'VDD':'(29)';
    'XTAL1':'(9)';IN;
    'XTAL2':'(10)';OUT;
end_primitive;
primitive 'PNP_TO92-MPS2907,IC,G73554-001';body 'PNP';
    'B':'(1)';
    'C':'(3)';
    'E':'(2)';
end_primitive;
primitive 'PXE1110B_QFN-IC,H89187-001';body 'PXE1110B';
    'DNC'<0>:'(1)';
    'DNC'<1>:'(2)';
    'BPWM1':'(3)';OUT;
    'DNC'<2>:'(4)';
    'APWM1':'(5)';OUT;
    'SDA':'(6)';BIDI;
    'SCL':'(7)';BIDI;
    'RESET_N':'(8)';IN;
    'AVRRDY':'(9)';OUT;
    'AVREN':'(10)';IN;
    'VRHOT_N':'(11)';OUT;
    'PINALRT_N':'(12)';OUT;
    'MP0':'(13)';BIDI;
    'MP1':'(14)';BIDI;
    'VCLK':'(15)';IN;
    'VDIO':'(16)';BIDI;
    'VALRT_N':'(17)';OUT;
    'MP2':'(18)';OUT;
    'AVSEN':'(19)';IN;
    'AVREF':'(20)';IN;
    'AIREF1':'(21)';IN;
    'AISEN1':'(22)';IN;
    'GND'<1>:'(23)';
    'DNC'<3>:'(24)';
    'BIREF1':'(25)';IN;
    'BISEN1':'(26)';IN;
    'GND'<0>:'(27)';
    'DNC'<4>:'(28)';
    'BVSEN':'(29)';IN;
    'BVREF':'(30)';IN;
    'MP3':'(31)';BIDI;
    'MP4':'(32)';BIDI;
    'XADDR2':'(33)';IN;
    'BTSEN':'(34)';IN;
    'ATSEN':'(35)';IN;
    'XADDR1':'(36)';IN;
    'VINSEN':'(37)';IN;
    'IINSEN':'(38)';IN;
    'VDD':'(39)';
    'VD12':'(40)';
    'THPAD':'(41)';
end_primitive;
primitive 'PXE1610B_QFN-IC,H79206-001';body 'PXE1610B';
    'BPWM1':'(1)';OUT;
    'APWM6':'(2)';OUT;
    'APWM5':'(3)';OUT;
    'APWM4':'(4)';OUT;
    'APWM3':'(5)';OUT;
    'APWM2':'(6)';OUT;
    'APWM1':'(7)';OUT;
    'SDA':'(8)';BIDI;
    'SCL':'(9)';BIDI;
    'RESET_N':'(10)';IN;
    'AVRRDY':'(11)';OUT;
    'AVREN':'(12)';IN;
    'VRHOT_N':'(13)';OUT;
    'PINALRT_N':'(14)';OUT;
    'MP0':'(15)';BIDI;
    'MP1':'(16)';BIDI;
    'VCLK':'(17)';IN;
    'VDIO':'(18)';BIDI;
    'VALRT_N':'(19)';OUT;
    'MP2':'(20)';OUT;
    'AVSEN':'(21)';IN;
    'AVREF':'(22)';IN;
    'AIREF1':'(23)';IN;
    'AISEN1':'(24)';IN;
    'AIREF2':'(25)';IN;
    'AISEN2':'(26)';IN;
    'AIREF3':'(27)';IN;
    'AISEN3':'(28)';IN;
    'AIREF4':'(29)';IN;
    'AISEN4':'(30)';IN;
    'AIREF5':'(31)';IN;
    'AISEN5':'(32)';IN;
    'AIREF6':'(33)';IN;
    'AISEN6':'(34)';IN;
    'BVSEN':'(35)';IN;
    'BVREF':'(36)';IN;
    'BIREF1':'(37)';IN;
    'BISEN1':'(38)';IN;
    'MP3':'(39)';OUT;
    'MP4':'(40)';OUT;
    'XADDR2':'(41)';IN;
    'BTSEN':'(42)';IN;
    'ATSEN':'(43)';IN;
    'XADDR1':'(44)';IN;
    'VINSEN':'(45)';IN;
    'IINSEN':'(46)';IN;
    'VDD':'(47)';
    'VD12':'(48)';
    'THPAD':'(49)';
end_primitive;
primitive 'PXM1310B_QFN-IC,H89186-001';body 'PXM1310B';
    'BPWM1':'(1)';OUT;
    'DNC'<0>:'(2)';
    'APWM3':'(3)';OUT;
    'APWM2':'(4)';OUT;
    'APWM1':'(5)';OUT;
    'SDA':'(6)';BIDI;
    'SCL':'(7)';BIDI;
    'RESET_N':'(8)';IN;
    'AVRRDY':'(9)';OUT;
    'AVREN':'(10)';IN;
    'VRHOT_N':'(11)';OUT;
    'PINALRT_N':'(12)';OUT;
    'MP0':'(13)';BIDI;
    'MP1':'(14)';BIDI;
    'VCLK':'(15)';IN;
    'VDIO':'(16)';BIDI;
    'VALRT_N':'(17)';OUT;
    'MP2':'(18)';BIDI;
    'AVSEN':'(19)';IN;
    'AVREF':'(20)';IN;
    'AIREF1':'(21)';IN;
    'AISEN1':'(22)';IN;
    'AIREF2':'(23)';IN;
    'AISEN2':'(24)';IN;
    'AIREF3':'(25)';IN;
    'AISEN3':'(26)';IN;
    'GND':'(27)';
    'DNC'<1>:'(28)';
    'BVSEN':'(29)';IN;
    'BVREF':'(30)';IN;
    'BIREF1':'(31)';IN;
    'BISEN1':'(32)';IN;
    'XADDR2':'(33)';IN;
    'BTSEN':'(34)';IN;
    'ATSEN':'(35)';IN;
    'XADDR1':'(36)';IN;
    'VINSEN':'(37)';IN;
    'IINSEN':'(38)';IN;
    'VDD':'(39)';
    'VD12':'(40)';BIDI;
    'THPAD':'(41)';
end_primitive;
primitive 'RCC_DFX1940_ID4-EMPTY,N_A';body 'RCC_DFX1940';
    'GND':'(1)';
    'IO1':'(2)';
    'IO2':'(3)';
end_primitive;
primitive 'RES_0402-0.0,5%,1/16W,CHIP,G21A';body 'RES';
    'A':'(1)';
    'B':'(2)';
end_primitive;
primitive 'RES_0402-0.0,5%,1/16W,EMPTY,G2A';body 'RES';
    'A':'(1)';
    'B':'(2)';
end_primitive;
primitive 'RES_0402-1.0,1%,1/16W,CHIP,G21A';body 'RES';
    'A':'(1)';
    'B':'(2)';
end_primitive;
primitive 'RES_0402-1.00K,1%,1/16W,CHIP,GA';body 'RES';
    'A':'(1)';
    'B':'(2)';
end_primitive;
primitive 'RES_0402-1.00K,1%,1/16W,EMPTY,A';body 'RES';
    'A':'(1)';
    'B':'(2)';
end_primitive;
primitive 'RES_0402-1.0K,0.1%,1/16W,CHIP,A';body 'RES';
    'A':'(1)';
    'B':'(2)';
end_primitive;
primitive 'RES_0402-1.0M,1%,1/16W,EMPTY,GA';body 'RES';
    'A':'(1)';
    'B':'(2)';
end_primitive;
primitive 'RES_0402-1.37K,1%,1/16W,CHIP,GA';body 'RES';
    'A':'(1)';
    'B':'(2)';
end_primitive;
primitive 'RES_0402-1.5K,1%,1/16W,CHIP,G2A';body 'RES';
    'A':'(1)';
    'B':'(2)';
end_primitive;
primitive 'RES_0402-1.8K,1%,1/16W,CHIP,G2A';body 'RES';
    'A':'(1)';
    'B':'(2)';
end_primitive;
primitive 'RES_0402-10.0,1%,1/16W,CHIP,G2A';body 'RES';
    'A':'(1)';
    'B':'(2)';
end_primitive;
primitive 'RES_0402-10.0,1%,1/16W,EMPTY,GA';body 'RES';
    'A':'(1)';
    'B':'(2)';
end_primitive;
primitive 'RES_0402-10.0K,1%,1/16W,CHIP,GA';body 'RES';
    'A':'(1)';
    'B':'(2)';
end_primitive;
primitive 'RES_0402-10.0K,1%,1/16W,EMPTY,A';body 'RES';
    'A':'(1)';
    'B':'(2)';
end_primitive;
primitive 'RES_0402-100.0,1%,1/16W,CHIP,GA';body 'RES';
    'A':'(1)';
    'B':'(2)';
end_primitive;
primitive 'RES_0402-100.0,1%,1/16W,EMPTY,A';body 'RES';
    'A':'(1)';
    'B':'(2)';
end_primitive;
primitive 'RES_0402-100.0K,1%,1/16W,CHIP,A';body 'RES';
    'A':'(1)';
    'B':'(2)';
end_primitive;
primitive 'RES_0402-100.0K,1%,1/16W,CHIP,B';body 'RES';
    'A':'(1)';
    'B':'(2)';
end_primitive;
primitive 'RES_0402-100.0K,1%,1/16W,EMPTYA';body 'RES';
    'A':'(1)';
    'B':'(2)';
end_primitive;
primitive 'RES_0402-105.0K,1%,1/16W,CHIP,A';body 'RES';
    'A':'(1)';
    'B':'(2)';
end_primitive;
primitive 'RES_0402-110,1%,1/16W,EMPTY,G2A';body 'RES';
    'A':'(1)';
    'B':'(2)';
end_primitive;
primitive 'RES_0402-113,1%,1/16W,CHIP,G21A';body 'RES';
    'A':'(1)';
    'B':'(2)';
end_primitive;
primitive 'RES_0402-11K,1%,1/16W,CHIP,G21A';body 'RES';
    'A':'(1)';
    'B':'(2)';
end_primitive;
primitive 'RES_0402-12.1K,1%,1/16W,CHIP,GA';body 'RES';
    'A':'(1)';
    'B':'(2)';
end_primitive;
primitive 'RES_0402-13K,1.0%,1/16W,CHIP,GA';body 'RES';
    'A':'(1)';
    'B':'(2)';
end_primitive;
primitive 'RES_0402-15.0K,1%,1/16W,CHIP,GA';body 'RES';
    'A':'(1)';
    'B':'(2)';
end_primitive;
primitive 'RES_0402-150.0,1%,1/16W,CHIP,GA';body 'RES';
    'A':'(1)';
    'B':'(2)';
end_primitive;
primitive 'RES_0402-150.0K,1%,1/16W,CHIP,A';body 'RES';
    'A':'(1)';
    'B':'(2)';
end_primitive;
primitive 'RES_0402-169,1.0%,1/16W,CHIP,GA';body 'RES';
    'A':'(1)';
    'B':'(2)';
end_primitive;
primitive 'RES_0402-16K,1.0%,1/16W,CHIP,GA';body 'RES';
    'A':'(1)';
    'B':'(2)';
end_primitive;
primitive 'RES_0402-2,1.0%,1/16W,CHIP,G21A';body 'RES';
    'A':'(1)';
    'B':'(2)';
end_primitive;
primitive 'RES_0402-2.0K,1%,1/16W,CHIP,G2A';body 'RES';
    'A':'(1)';
    'B':'(2)';
end_primitive;
primitive 'RES_0402-2.0K,1%,1/16W,EMPTY,GA';body 'RES';
    'A':'(1)';
    'B':'(2)';
end_primitive;
primitive 'RES_0402-2.2,5%,1/16W,EMPTY,G2A';body 'RES';
    'A':'(1)';
    'B':'(2)';
end_primitive;
primitive 'RES_0402-2.21K,1%,1/16W,CHIP,GA';body 'RES';
    'A':'(1)';
    'B':'(2)';
end_primitive;
primitive 'RES_0402-2.26K,1.0%,1/16W,CHIPA';body 'RES';
    'A':'(1)';
    'B':'(2)';
end_primitive;
primitive 'RES_0402-2.26K,1.0%,1/16W,EMPTA';body 'RES';
    'A':'(1)';
    'B':'(2)';
end_primitive;
primitive 'RES_0402-2.67K,1%,1/16W,CHIP,GA';body 'RES';
    'A':'(1)';
    'B':'(2)';
end_primitive;
primitive 'RES_0402-2.7K,1%,1/16W,CHIP,G2A';body 'RES';
    'A':'(1)';
    'B':'(2)';
end_primitive;
primitive 'RES_0402-2.7K,1%,1/16W,EMPTY,GA';body 'RES';
    'A':'(1)';
    'B':'(2)';
end_primitive;
primitive 'RES_0402-20.0,1%,1/16W,CHIP,G2A';body 'RES';
    'A':'(1)';
    'B':'(2)';
end_primitive;
primitive 'RES_0402-20.0,1%,1/16W,EMPTY,GA';body 'RES';
    'A':'(1)';
    'B':'(2)';
end_primitive;
primitive 'RES_0402-20.0K,1%,1/16W,CHIP,GA';body 'RES';
    'A':'(1)';
    'B':'(2)';
end_primitive;
primitive 'RES_0402-20.0K,1%,1/16W,EMPTY,A';body 'RES';
    'A':'(1)';
    'B':'(2)';
end_primitive;
primitive 'RES_0402-200.0,1%,1/16W,CHIP,GA';body 'RES';
    'A':'(1)';
    'B':'(2)';
end_primitive;
primitive 'RES_0402-200.0K,1%,1/16W,CHIP,A';body 'RES';
    'A':'(1)';
    'B':'(2)';
end_primitive;
primitive 'RES_0402-22.1,1.0%,1/16W,CHIP,A';body 'RES';
    'A':'(1)';
    'B':'(2)';
end_primitive;
primitive 'RES_0402-221,1.0%,1/16W,CHIP,GA';body 'RES';
    'A':'(1)';
    'B':'(2)';
end_primitive;
primitive 'RES_0402-23.2K,1%,1/16W,CHIP,GA';body 'RES';
    'A':'(1)';
    'B':'(2)';
end_primitive;
primitive 'RES_0402-24.9K,1%,1/16W,CHIP,GA';body 'RES';
    'A':'(1)';
    'B':'(2)';
end_primitive;
primitive 'RES_0402-240,1.0%,1/16W,CHIP,GA';body 'RES';
    'A':'(1)';
    'B':'(2)';
end_primitive;
primitive 'RES_0402-240,1.0%,1/16W,EMPTY,A';body 'RES';
    'A':'(1)';
    'B':'(2)';
end_primitive;
primitive 'RES_0402-249,0.1%,1/16W,CHIP,GA';body 'RES';
    'A':'(1)';
    'B':'(2)';
end_primitive;
primitive 'RES_0402-249K,1.0%,1/16W,CHIP,A';body 'RES';
    'A':'(1)';
    'B':'(2)';
end_primitive;
primitive 'RES_0402-27.4,1%,1/16W,CHIP,G2A';body 'RES';
    'A':'(1)';
    'B':'(2)';
end_primitive;
primitive 'RES_0402-274K,1.0%,1/16W,CHIP,A';body 'RES';
    'A':'(1)';
    'B':'(2)';
end_primitive;
primitive 'RES_0402-3.16K,1%,1/16W,CHIP,GA';body 'RES';
    'A':'(1)';
    'B':'(2)';
end_primitive;
primitive 'RES_0402-3.32K,1%,1/16W,CHIP,GA';body 'RES';
    'A':'(1)';
    'B':'(2)';
end_primitive;
primitive 'RES_0402-3.32K,1%,1/16W,EMPTY,A';body 'RES';
    'A':'(1)';
    'B':'(2)';
end_primitive;
primitive 'RES_0402-3.3K,5%,1/16W,CHIP,G2A';body 'RES';
    'A':'(1)';
    'B':'(2)';
end_primitive;
primitive 'RES_0402-3.48K,1.0%,1/16W,CHIPA';body 'RES';
    'A':'(1)';
    'B':'(2)';
end_primitive;
primitive 'RES_0402-3.74K,1%,1/16W,CHIP,GA';body 'RES';
    'A':'(1)';
    'B':'(2)';
end_primitive;
primitive 'RES_0402-301.0,1%,1/16W,CHIP,GA';body 'RES';
    'A':'(1)';
    'B':'(2)';
end_primitive;
primitive 'RES_0402-33.0K,5%,1/16W,CHIP,GA';body 'RES';
    'A':'(1)';
    'B':'(2)';
end_primitive;
primitive 'RES_0402-33.2,1%,1/16W,CHIP,G2A';body 'RES';
    'A':'(1)';
    'B':'(2)';
end_primitive;
primitive 'RES_0402-33.2,1%,1/16W,EMPTY,GA';body 'RES';
    'A':'(1)';
    'B':'(2)';
end_primitive;
primitive 'RES_0402-330,5%,1/16W,CHIP,G21A';body 'RES';
    'A':'(1)';
    'B':'(2)';
end_primitive;
primitive 'RES_0402-348,1%,1/16W,CHIP,G21A';body 'RES';
    'A':'(1)';
    'B':'(2)';
end_primitive;
primitive 'RES_0402-348,1%,1/16W,EMPTY,G2A';body 'RES';
    'A':'(1)';
    'B':'(2)';
end_primitive;
primitive 'RES_0402-4.02K,1%,1/16W,CHIP,GA';body 'RES';
    'A':'(1)';
    'B':'(2)';
end_primitive;
primitive 'RES_0402-4.75K,1%,1/16W,CHIP,GA';body 'RES';
    'A':'(1)';
    'B':'(2)';
end_primitive;
primitive 'RES_0402-4.75K,1%,1/16W,EMPTY,A';body 'RES';
    'A':'(1)';
    'B':'(2)';
end_primitive;
primitive 'RES_0402-4.99K,1%,1/16W,CHIP,GA';body 'RES';
    'A':'(1)';
    'B':'(2)';
end_primitive;
primitive 'RES_0402-40.2K,1%,1/16W,CHIP,GA';body 'RES';
    'A':'(1)';
    'B':'(2)';
end_primitive;
primitive 'RES_0402-42.2,1.0%,1/16W,EMPTYA';body 'RES';
    'A':'(1)';
    'B':'(2)';
end_primitive;
primitive 'RES_0402-470.0,5%,1/16W,CHIP,GA';body 'RES';
    'A':'(1)';
    'B':'(2)';
end_primitive;
primitive 'RES_0402-475.0,1%,1/16W,CHIP,GA';body 'RES';
    'A':'(1)';
    'B':'(2)';
end_primitive;
primitive 'RES_0402-49.9,1%,1/16W,CHIP,G2A';body 'RES';
    'A':'(1)';
    'B':'(2)';
end_primitive;
primitive 'RES_0402-49.9,1%,1/16W,EMPTY,GA';body 'RES';
    'A':'(1)';
    'B':'(2)';
end_primitive;
primitive 'RES_0402-49.9K,1%,1/16W,CHIP,GA';body 'RES';
    'A':'(1)';
    'B':'(2)';
end_primitive;
primitive 'RES_0402-5.11K,1%,1/16W,CHIP,GA';body 'RES';
    'A':'(1)';
    'B':'(2)';
end_primitive;
primitive 'RES_0402-5.36K,1.0%,1/16W,CHIPA';body 'RES';
    'A':'(1)';
    'B':'(2)';
end_primitive;
primitive 'RES_0402-51,5.0%,1/16W,CHIP,G2A';body 'RES';
    'A':'(1)';
    'B':'(2)';
end_primitive;
primitive 'RES_0402-51.1,1.0%,1/16W,CHIP,A';body 'RES';
    'A':'(1)';
    'B':'(2)';
end_primitive;
primitive 'RES_0402-560,5%,1/16W,CHIP,G21A';body 'RES';
    'A':'(1)';
    'B':'(2)';
end_primitive;
primitive 'RES_0402-6.19K,1%,1/16W,CHIP,GA';body 'RES';
    'A':'(1)';
    'B':'(2)';
end_primitive;
primitive 'RES_0402-6.34K,1%,1/16W,CHIP,GA';body 'RES';
    'A':'(1)';
    'B':'(2)';
end_primitive;
primitive 'RES_0402-63.4K,1.0%,1/16W,CHIPA';body 'RES';
    'A':'(1)';
    'B':'(2)';
end_primitive;
primitive 'RES_0402-64.9,1.0%,1/16W,CHIP,A';body 'RES';
    'A':'(1)';
    'B':'(2)';
end_primitive;
primitive 'RES_0402-64.9K,1%,1/16W,CHIP,GA';body 'RES';
    'A':'(1)';
    'B':'(2)';
end_primitive;
primitive 'RES_0402-665,1.0%,1/16W,CHIP,GA';body 'RES';
    'A':'(1)';
    'B':'(2)';
end_primitive;
primitive 'RES_0402-68.1K,1%,1/16W,EMPTY,A';body 'RES';
    'A':'(1)';
    'B':'(2)';
end_primitive;
primitive 'RES_0402-69.8K,1%,1/16W,CHIP,GA';body 'RES';
    'A':'(1)';
    'B':'(2)';
end_primitive;
primitive 'RES_0402-7.5K,1%,1/16W,CHIP,G2A';body 'RES';
    'A':'(1)';
    'B':'(2)';
end_primitive;
primitive 'RES_0402-7.87K,1.0%,1/16W,CHIPA';body 'RES';
    'A':'(1)';
    'B':'(2)';
end_primitive;
primitive 'RES_0402-75,1.0%,1/16W,CHIP,G2A';body 'RES';
    'A':'(1)';
    'B':'(2)';
end_primitive;
primitive 'RES_0402-75K,1%,1/16W,CHIP,G21A';body 'RES';
    'A':'(1)';
    'B':'(2)';
end_primitive;
primitive 'RES_0402-8.06K,1%,1/16W,CHIP,GA';body 'RES';
    'A':'(1)';
    'B':'(2)';
end_primitive;
primitive 'RES_0402-8.2K,1%,1/16W,CHIP,G2A';body 'RES';
    'A':'(1)';
    'B':'(2)';
end_primitive;
primitive 'RES_0402-8.2K,1%,1/16W,EMPTY,GA';body 'RES';
    'A':'(1)';
    'B':'(2)';
end_primitive;
primitive 'RES_0402-90.9,1%,1/16W,CHIP,G2A';body 'RES';
    'A':'(1)';
    'B':'(2)';
end_primitive;
primitive 'RES_0402-90.9K,1%,1/16W,CHIP,GA';body 'RES';
    'A':'(1)';
    'B':'(2)';
end_primitive;
primitive 'RES_0603-0,5.0%,1/10W,CHIP,G22A';body 'RES';
    'A':'(1)';
    'B':'(2)';
end_primitive;
primitive 'RES_0603-0,5.0%,1/10W,EMPTY,G2A';body 'RES';
    'A':'(1)';
    'B':'(2)';
end_primitive;
primitive 'RES_0603-10.0,1%,1/10W,CHIP,G2A';body 'RES';
    'A':'(1)';
    'B':'(2)';
end_primitive;
primitive 'RES_0603-100.0,1%,1/10W,CHIP,GA';body 'RES';
    'A':'(1)';
    'B':'(2)';
end_primitive;
primitive 'RES_0603-100.0K,1%,1/10W,CHIP,A';body 'RES';
    'A':'(1)';
    'B':'(2)';
end_primitive;
primitive 'RES_0603-10M,1.0%,1/10W,CHIP,GA';body 'RES';
    'A':'(1)';
    'B':'(2)';
end_primitive;
primitive 'RES_0603-120.0,1%,1/10W,CHIP,GA';body 'RES';
    'A':'(1)';
    'B':'(2)';
end_primitive;
primitive 'RES_0603-2.2,1.0%,1/10W,CHIP,GA';body 'RES';
    'A':'(1)';
    'B':'(2)';
end_primitive;
primitive 'RES_0603-200K,0.1%,1/10W,CHIP,A';body 'RES';
    'A':'(1)';
    'B':'(2)';
end_primitive;
primitive 'RES_0603-475.0,1%,1/10W,CHIP,GA';body 'RES';
    'A':'(1)';
    'B':'(2)';
end_primitive;
primitive 'RES_0805-0.0,5%,1/8W,CHIP,G221A';body 'RES';
    'A':'(1)';
    'B':'(2)';
end_primitive;
primitive 'RES_1206-0.002,1%,1W,CHIP,G521A';body 'RES';
    'A':'(1)';
    'B':'(2)';
end_primitive;
primitive 'RES_2010-0.001,1%,1W,CHIP,E309A';body 'RES';
    'A':'(1)';
    'B':'(2)';
end_primitive;
primitive 'RES_PWR_6PAD-0.001,1%,3W,CHIP,A';body 'RES_PWR';
    '1':'(1)';
    '2':'(2)';
    '3':'(3)';
    '4':'(4)';
    '5':'(5)';
    '6':'(6)';
end_primitive;
primitive 'RT8240_QFN-IC,H66262-001';body 'RT8240';
    'BOOT':'(4)';IN;
    'CS':'(10)';IN;
    'EN':'(8)';IN;
    'G0':'(11)';IN;
    'GND'<1>:'(13)';
    'GND'<0>:'(12)';
    'LGATE':'(1)';OUT;
    'PGOOD':'(9)';IN;
    'PHASE':'(2)';IN;
    'RGND':'(7)';
    'UGATE':'(3)';OUT;
    'VCC':'(5)';
    'VOUT':'(6)';OUT;
end_primitive;
primitive 'RT9059_DFN-IC,H65765-001';body 'RT9059';
    'ADJ_NC':'(4)';OUT;
    'EN':'(6)';IN;
    'GND':'(11)';
    'PGOOD':'(5)';OUT;
    'VDD':'(10)';
    'VIN'<2>:'(9)';IN;
    'VIN'<1>:'(8)';IN;
    'VIN'<0>:'(7)';IN;
    'VOUT'<2>:'(3)';OUT;
    'VOUT'<1>:'(2)';OUT;
    'VOUT'<0>:'(1)';OUT;
end_primitive;
primitive 'SC1U16V3KX-2GP_SMD-BCG-SC1U16VA';body 'SC1U16V3KX-2GP';
    '1':'(1)';
    '2':'(2)';
end_primitive;
primitive 'SC22P50V2JN-4GP_SMD-BCG-SC22P5A';body 'SC22P50V2JN-4GP';
    '1':'(1)';
    '2':'(2)';
end_primitive;
primitive 'SC2K2P50V3KX-GP_SMD-BCG6-SC2K2A';body 'SC2K2P50V3KX-GP';
    '1':'(1)';
    '2':'(2)';
end_primitive;
primitive 'SC4D7U10V3KX-GP_SMD-BCG-SC4D7UA';body 'SC4D7U10V3KX-GP';
    '1':'(1)';
    '2':'(2)';
end_primitive;
primitive 'SCD1U16V2KX-3GP_SMD-BCG-SCD1U1A';body 'SCD1U16V2KX-3GP';
    '1':'(1)';
    '2':'(2)';
end_primitive;
primitive 'SCONN10_C12536004_SMLF-CONN,C1A';body 'SCONN10_C12536004';
    'IO1':'(1)';
    'IO2':'(2)';
    'IO3':'(3)';
    'IO4':'(4)';
    'IO5':'(5)';
    'IO6':'(6)';
    'IO7':'(7)';
    'IO8':'(8)';
    'IO9':'(9)';
    'IO10':'(10)';
end_primitive;
primitive 'SCONN11_H67026001_SM-CONN,H670A';body 'SCONN11_H67026001';
    'IO1':'(1)';BIDI;
    'IO2':'(2)';BIDI;
    'IO3':'(3)';BIDI;
    'IO4':'(4)';BIDI;
    'IO5':'(5)';BIDI;
    'IO6':'(6)';BIDI;
    'IO7':'(7)';BIDI;
    'IO8':'(8)';BIDI;
    'IO9':'(9)';BIDI;
    'IO10':'(10)';BIDI;
    'IO11':'(11)';BIDI;
    'MP1':'(MP1)';
    'MP2':'(MP2)';
end_primitive;
primitive 'SCONN120_A28699018_SM-SCONN,A2A';body 'SCONN120_A28699018';
    'IO1':'(1)';BIDI;
    'IO10':'(10)';BIDI;
    'IO100':'(100)';BIDI;
    'IO101':'(101)';BIDI;
    'IO102':'(102)';BIDI;
    'IO103':'(103)';BIDI;
    'IO104':'(104)';BIDI;
    'IO105':'(105)';BIDI;
    'IO106':'(106)';BIDI;
    'IO107':'(107)';BIDI;
    'IO108':'(108)';BIDI;
    'IO109':'(109)';BIDI;
    'IO11':'(11)';BIDI;
    'IO110':'(110)';BIDI;
    'IO111':'(111)';BIDI;
    'IO112':'(112)';BIDI;
    'IO113':'(113)';BIDI;
    'IO114':'(114)';BIDI;
    'IO115':'(115)';BIDI;
    'IO116':'(116)';BIDI;
    'IO117':'(117)';BIDI;
    'IO118':'(118)';BIDI;
    'IO119':'(119)';BIDI;
    'IO12':'(12)';BIDI;
    'IO120':'(120)';BIDI;
    'IO13':'(13)';BIDI;
    'IO14':'(14)';BIDI;
    'IO15':'(15)';BIDI;
    'IO16':'(16)';BIDI;
    'IO17':'(17)';BIDI;
    'IO18':'(18)';BIDI;
    'IO19':'(19)';BIDI;
    'IO2':'(2)';BIDI;
    'IO20':'(20)';BIDI;
    'IO21':'(21)';BIDI;
    'IO22':'(22)';BIDI;
    'IO23':'(23)';BIDI;
    'IO24':'(24)';BIDI;
    'IO25':'(25)';BIDI;
    'IO26':'(26)';BIDI;
    'IO27':'(27)';BIDI;
    'IO28':'(28)';BIDI;
    'IO29':'(29)';BIDI;
    'IO3':'(3)';BIDI;
    'IO30':'(30)';BIDI;
    'IO31':'(31)';BIDI;
    'IO32':'(32)';BIDI;
    'IO33':'(33)';BIDI;
    'IO34':'(34)';BIDI;
    'IO35':'(35)';BIDI;
    'IO36':'(36)';BIDI;
    'IO37':'(37)';BIDI;
    'IO38':'(38)';BIDI;
    'IO39':'(39)';BIDI;
    'IO4':'(4)';BIDI;
    'IO40':'(40)';BIDI;
    'IO41':'(41)';BIDI;
    'IO42':'(42)';BIDI;
    'IO43':'(43)';BIDI;
    'IO44':'(44)';BIDI;
    'IO45':'(45)';BIDI;
    'IO46':'(46)';BIDI;
    'IO47':'(47)';BIDI;
    'IO48':'(48)';BIDI;
    'IO49':'(49)';BIDI;
    'IO5':'(5)';BIDI;
    'IO50':'(50)';BIDI;
    'IO51':'(51)';BIDI;
    'IO52':'(52)';BIDI;
    'IO53':'(53)';BIDI;
    'IO54':'(54)';BIDI;
    'IO55':'(55)';BIDI;
    'IO56':'(56)';BIDI;
    'IO57':'(57)';BIDI;
    'IO58':'(58)';BIDI;
    'IO59':'(59)';BIDI;
    'IO6':'(6)';BIDI;
    'IO60':'(60)';BIDI;
    'IO61':'(61)';BIDI;
    'IO62':'(62)';BIDI;
    'IO63':'(63)';BIDI;
    'IO64':'(64)';BIDI;
    'IO65':'(65)';BIDI;
    'IO66':'(66)';BIDI;
    'IO67':'(67)';BIDI;
    'IO68':'(68)';BIDI;
    'IO69':'(69)';BIDI;
    'IO7':'(7)';BIDI;
    'IO70':'(70)';BIDI;
    'IO71':'(71)';BIDI;
    'IO72':'(72)';BIDI;
    'IO73':'(73)';BIDI;
    'IO74':'(74)';BIDI;
    'IO75':'(75)';BIDI;
    'IO76':'(76)';BIDI;
    'IO77':'(77)';BIDI;
    'IO78':'(78)';BIDI;
    'IO79':'(79)';BIDI;
    'IO8':'(8)';BIDI;
    'IO80':'(80)';BIDI;
    'IO81':'(81)';BIDI;
    'IO82':'(82)';BIDI;
    'IO83':'(83)';BIDI;
    'IO84':'(84)';BIDI;
    'IO85':'(85)';BIDI;
    'IO86':'(86)';BIDI;
    'IO87':'(87)';BIDI;
    'IO88':'(88)';BIDI;
    'IO89':'(89)';BIDI;
    'IO9':'(9)';BIDI;
    'IO90':'(90)';BIDI;
    'IO91':'(91)';BIDI;
    'IO92':'(92)';BIDI;
    'IO93':'(93)';BIDI;
    'IO94':'(94)';BIDI;
    'IO95':'(95)';BIDI;
    'IO96':'(96)';BIDI;
    'IO97':'(97)';BIDI;
    'IO98':'(98)';BIDI;
    'IO99':'(99)';BIDI;
end_primitive;
primitive 'SCONN120_H61426002_SM-CONN,H61A';body 'SCONN120_H61426002';
    'IOA1':'(A1)';BIDI;
    'IOA10':'(A10)';BIDI;
    'IOA11':'(A11)';BIDI;
    'IOA12':'(A12)';BIDI;
    'IOA13':'(A13)';BIDI;
    'IOA14':'(A14)';BIDI;
    'IOA15':'(A15)';BIDI;
    'IOA16':'(A16)';BIDI;
    'IOA17':'(A17)';BIDI;
    'IOA18':'(A18)';BIDI;
    'IOA19':'(A19)';BIDI;
    'IOA2':'(A2)';BIDI;
    'IOA20':'(A20)';BIDI;
    'IOA3':'(A3)';BIDI;
    'IOA4':'(A4)';BIDI;
    'IOA5':'(A5)';BIDI;
    'IOA6':'(A6)';BIDI;
    'IOA7':'(A7)';BIDI;
    'IOA8':'(A8)';BIDI;
    'IOA9':'(A9)';BIDI;
    'IOB1':'(B1)';BIDI;
    'IOB10':'(B10)';BIDI;
    'IOB11':'(B11)';BIDI;
    'IOB12':'(B12)';BIDI;
    'IOB13':'(B13)';BIDI;
    'IOB14':'(B14)';BIDI;
    'IOB15':'(B15)';BIDI;
    'IOB16':'(B16)';BIDI;
    'IOB17':'(B17)';BIDI;
    'IOB18':'(B18)';BIDI;
    'IOB19':'(B19)';BIDI;
    'IOB2':'(B2)';BIDI;
    'IOB20':'(B20)';BIDI;
    'IOB3':'(B3)';BIDI;
    'IOB4':'(B4)';BIDI;
    'IOB5':'(B5)';BIDI;
    'IOB6':'(B6)';BIDI;
    'IOB7':'(B7)';BIDI;
    'IOB8':'(B8)';BIDI;
    'IOB9':'(B9)';BIDI;
    'IOC1':'(C1)';BIDI;
    'IOC10':'(C10)';BIDI;
    'IOC11':'(C11)';BIDI;
    'IOC12':'(C12)';BIDI;
    'IOC13':'(C13)';BIDI;
    'IOC14':'(C14)';BIDI;
    'IOC15':'(C15)';BIDI;
    'IOC16':'(C16)';BIDI;
    'IOC17':'(C17)';BIDI;
    'IOC18':'(C18)';BIDI;
    'IOC19':'(C19)';BIDI;
    'IOC2':'(C2)';BIDI;
    'IOC20':'(C20)';BIDI;
    'IOC3':'(C3)';BIDI;
    'IOC4':'(C4)';BIDI;
    'IOC5':'(C5)';BIDI;
    'IOC6':'(C6)';BIDI;
    'IOC7':'(C7)';BIDI;
    'IOC8':'(C8)';BIDI;
    'IOC9':'(C9)';BIDI;
    'IOD1':'(D1)';BIDI;
    'IOD10':'(D10)';BIDI;
    'IOD11':'(D11)';BIDI;
    'IOD12':'(D12)';BIDI;
    'IOD13':'(D13)';BIDI;
    'IOD14':'(D14)';BIDI;
    'IOD15':'(D15)';BIDI;
    'IOD16':'(D16)';BIDI;
    'IOD17':'(D17)';BIDI;
    'IOD18':'(D18)';BIDI;
    'IOD19':'(D19)';BIDI;
    'IOD2':'(D2)';BIDI;
    'IOD20':'(D20)';BIDI;
    'IOD3':'(D3)';BIDI;
    'IOD4':'(D4)';BIDI;
    'IOD5':'(D5)';BIDI;
    'IOD6':'(D6)';BIDI;
    'IOD7':'(D7)';BIDI;
    'IOD8':'(D8)';BIDI;
    'IOD9':'(D9)';BIDI;
    'IOE1':'(E1)';BIDI;
    'IOE10':'(E10)';BIDI;
    'IOE11':'(E11)';BIDI;
    'IOE12':'(E12)';BIDI;
    'IOE13':'(E13)';BIDI;
    'IOE14':'(E14)';BIDI;
    'IOE15':'(E15)';BIDI;
    'IOE16':'(E16)';BIDI;
    'IOE17':'(E17)';BIDI;
    'IOE18':'(E18)';BIDI;
    'IOE19':'(E19)';BIDI;
    'IOE2':'(E2)';BIDI;
    'IOE20':'(E20)';BIDI;
    'IOE3':'(E3)';BIDI;
    'IOE4':'(E4)';BIDI;
    'IOE5':'(E5)';BIDI;
    'IOE6':'(E6)';BIDI;
    'IOE7':'(E7)';BIDI;
    'IOE8':'(E8)';BIDI;
    'IOE9':'(E9)';BIDI;
    'IOF1':'(F1)';BIDI;
    'IOF10':'(F10)';BIDI;
    'IOF11':'(F11)';BIDI;
    'IOF12':'(F12)';BIDI;
    'IOF13':'(F13)';BIDI;
    'IOF14':'(F14)';BIDI;
    'IOF15':'(F15)';BIDI;
    'IOF16':'(F16)';BIDI;
    'IOF17':'(F17)';BIDI;
    'IOF18':'(F18)';BIDI;
    'IOF19':'(F19)';BIDI;
    'IOF2':'(F2)';BIDI;
    'IOF20':'(F20)';BIDI;
    'IOF3':'(F3)';BIDI;
    'IOF4':'(F4)';BIDI;
    'IOF5':'(F5)';BIDI;
    'IOF6':'(F6)';BIDI;
    'IOF7':'(F7)';BIDI;
    'IOF8':'(F8)';BIDI;
    'IOF9':'(F9)';BIDI;
end_primitive;
primitive 'SCONN200_H68296001_SM-CONN,H68A';body 'SCONN200_H68296001';
    'IO1':'(1,0)';$S;BIDI;
    'IO2':'(2,0)';$S;BIDI;
    'IO3':'(3,0)';$S;BIDI;
    'IO4':'(4,0)';$S;BIDI;
    'IO5':'(5,0)';$S;BIDI;
    'IO6':'(6,0)';$S;BIDI;
    'IO7':'(7,0)';$S;BIDI;
    'IO8':'(8,0)';$S;BIDI;
    'IO9':'(9,0)';$S;BIDI;
    'IO10':'(10,0)';$S;BIDI;
    'IO11':'(11,0)';$S;BIDI;
    'IO12':'(12,0)';$S;BIDI;
    'IO13':'(13,0)';$S;BIDI;
    'IO14':'(14,0)';$S;BIDI;
    'IO15':'(15,0)';$S;BIDI;
    'IO16':'(16,0)';$S;BIDI;
    'IO17':'(17,0)';$S;BIDI;
    'IO18':'(18,0)';$S;BIDI;
    'IO19':'(19,0)';$S;BIDI;
    'IO20':'(20,0)';$S;BIDI;
    'IO21':'(21,0)';$S;BIDI;
    'IO22':'(22,0)';$S;BIDI;
    'IO23':'(23,0)';$S;BIDI;
    'IO24':'(24,0)';$S;BIDI;
    'IO25':'(25,0)';$S;BIDI;
    'IO26':'(26,0)';$S;BIDI;
    'IO27':'(27,0)';$S;BIDI;
    'IO28':'(28,0)';$S;BIDI;
    'IO29':'(29,0)';$S;BIDI;
    'IO30':'(30,0)';$S;BIDI;
    'IO31':'(31,0)';$S;BIDI;
    'IO32':'(32,0)';$S;BIDI;
    'IO33':'(33,0)';$S;BIDI;
    'IO34':'(34,0)';$S;BIDI;
    'IO35':'(35,0)';$S;BIDI;
    'IO36':'(36,0)';$S;BIDI;
    'IO37':'(37,0)';$S;BIDI;
    'IO38':'(38,0)';$S;BIDI;
    'IO39':'(39,0)';$S;BIDI;
    'IO40':'(40,0)';$S;BIDI;
    'IO41':'(41,0)';$S;BIDI;
    'IO42':'(42,0)';$S;BIDI;
    'IO43':'(43,0)';$S;BIDI;
    'IO44':'(44,0)';$S;BIDI;
    'IO45':'(45,0)';$S;BIDI;
    'IO46':'(46,0)';$S;BIDI;
    'IO47':'(47,0)';$S;BIDI;
    'IO48':'(48,0)';$S;BIDI;
    'IO49':'(49,0)';$S;BIDI;
    'IO50':'(50,0)';$S;BIDI;
    'IO51':'(51,0)';$S;BIDI;
    'IO52':'(52,0)';$S;BIDI;
    'IO53':'(53,0)';$S;BIDI;
    'IO54':'(54,0)';$S;BIDI;
    'IO55':'(55,0)';$S;BIDI;
    'IO56':'(56,0)';$S;BIDI;
    'IO57':'(57,0)';$S;BIDI;
    'IO58':'(58,0)';$S;BIDI;
    'IO59':'(59,0)';$S;BIDI;
    'IO60':'(60,0)';$S;BIDI;
    'IO61':'(61,0)';$S;BIDI;
    'IO62':'(62,0)';$S;BIDI;
    'IO63':'(63,0)';$S;BIDI;
    'IO64':'(64,0)';$S;BIDI;
    'IO65':'(65,0)';$S;BIDI;
    'IO66':'(66,0)';$S;BIDI;
    'IO67':'(67,0)';$S;BIDI;
    'IO68':'(68,0)';$S;BIDI;
    'IO69':'(69,0)';$S;BIDI;
    'IO70':'(70,0)';$S;BIDI;
    'IO71':'(71,0)';$S;BIDI;
    'IO72':'(72,0)';$S;BIDI;
    'IO73':'(73,0)';$S;BIDI;
    'IO74':'(74,0)';$S;BIDI;
    'IO75':'(75,0)';$S;BIDI;
    'IO76':'(76,0)';$S;BIDI;
    'IO77':'(77,0)';$S;BIDI;
    'IO78':'(78,0)';$S;BIDI;
    'IO79':'(79,0)';$S;BIDI;
    'IO80':'(80,0)';$S;BIDI;
    'IO81':'(81,0)';$S;BIDI;
    'IO82':'(82,0)';$S;BIDI;
    'IO83':'(83,0)';$S;BIDI;
    'IO84':'(84,0)';$S;BIDI;
    'IO85':'(85,0)';$S;BIDI;
    'IO86':'(86,0)';$S;BIDI;
    'IO87':'(87,0)';$S;BIDI;
    'IO88':'(88,0)';$S;BIDI;
    'IO89':'(89,0)';$S;BIDI;
    'IO90':'(90,0)';$S;BIDI;
    'IO91':'(91,0)';$S;BIDI;
    'IO92':'(92,0)';$S;BIDI;
    'IO93':'(93,0)';$S;BIDI;
    'IO94':'(94,0)';$S;BIDI;
    'IO95':'(95,0)';$S;BIDI;
    'IO96':'(96,0)';$S;BIDI;
    'IO97':'(97,0)';$S;BIDI;
    'IO98':'(98,0)';$S;BIDI;
    'IO99':'(99,0)';$S;BIDI;
    'IO100':'(100,0)';$S;BIDI;
    'IO101':'(0,101)';$S;BIDI;
    'IO102':'(0,102)';$S;BIDI;
    'IO103':'(0,103)';$S;BIDI;
    'IO104':'(0,104)';$S;BIDI;
    'IO105':'(0,105)';$S;BIDI;
    'IO106':'(0,106)';$S;BIDI;
    'IO107':'(0,107)';$S;BIDI;
    'IO108':'(0,108)';$S;BIDI;
    'IO109':'(0,109)';$S;BIDI;
    'IO110':'(0,110)';$S;BIDI;
    'IO111':'(0,111)';$S;BIDI;
    'IO112':'(0,112)';$S;BIDI;
    'IO113':'(0,113)';$S;BIDI;
    'IO114':'(0,114)';$S;BIDI;
    'IO115':'(0,115)';$S;BIDI;
    'IO116':'(0,116)';$S;BIDI;
    'IO117':'(0,117)';$S;BIDI;
    'IO118':'(0,118)';$S;BIDI;
    'IO119':'(0,119)';$S;BIDI;
    'IO120':'(0,120)';$S;BIDI;
    'IO121':'(0,121)';$S;BIDI;
    'IO122':'(0,122)';$S;BIDI;
    'IO123':'(0,123)';$S;BIDI;
    'IO124':'(0,124)';$S;BIDI;
    'IO125':'(0,125)';$S;BIDI;
    'IO126':'(0,126)';$S;BIDI;
    'IO127':'(0,127)';$S;BIDI;
    'IO128':'(0,128)';$S;BIDI;
    'IO129':'(0,129)';$S;BIDI;
    'IO130':'(0,130)';$S;BIDI;
    'IO131':'(0,131)';$S;BIDI;
    'IO132':'(0,132)';$S;BIDI;
    'IO133':'(0,133)';$S;BIDI;
    'IO134':'(0,134)';$S;BIDI;
    'IO135':'(0,135)';$S;BIDI;
    'IO136':'(0,136)';$S;BIDI;
    'IO137':'(0,137)';$S;BIDI;
    'IO138':'(0,138)';$S;BIDI;
    'IO139':'(0,139)';$S;BIDI;
    'IO140':'(0,140)';$S;BIDI;
    'IO141':'(0,141)';$S;BIDI;
    'IO142':'(0,142)';$S;BIDI;
    'IO143':'(0,143)';$S;BIDI;
    'IO144':'(0,144)';$S;BIDI;
    'IO145':'(0,145)';$S;BIDI;
    'IO146':'(0,146)';$S;BIDI;
    'IO147':'(0,147)';$S;BIDI;
    'IO148':'(0,148)';$S;BIDI;
    'IO149':'(0,149)';$S;BIDI;
    'IO150':'(0,150)';$S;BIDI;
    'IO151':'(0,151)';$S;BIDI;
    'IO152':'(0,152)';$S;BIDI;
    'IO153':'(0,153)';$S;BIDI;
    'IO154':'(0,154)';$S;BIDI;
    'IO155':'(0,155)';$S;BIDI;
    'IO156':'(0,156)';$S;BIDI;
    'IO157':'(0,157)';$S;BIDI;
    'IO158':'(0,158)';$S;BIDI;
    'IO159':'(0,159)';$S;BIDI;
    'IO160':'(0,160)';$S;BIDI;
    'IO161':'(0,161)';$S;BIDI;
    'IO162':'(0,162)';$S;BIDI;
    'IO163':'(0,163)';$S;BIDI;
    'IO164':'(0,164)';$S;BIDI;
    'IO165':'(0,165)';$S;BIDI;
    'IO166':'(0,166)';$S;BIDI;
    'IO167':'(0,167)';$S;BIDI;
    'IO168':'(0,168)';$S;BIDI;
    'IO169':'(0,169)';$S;BIDI;
    'IO170':'(0,170)';$S;BIDI;
    'IO171':'(0,171)';$S;BIDI;
    'IO172':'(0,172)';$S;BIDI;
    'IO173':'(0,173)';$S;BIDI;
    'IO174':'(0,174)';$S;BIDI;
    'IO175':'(0,175)';$S;BIDI;
    'IO176':'(0,176)';$S;BIDI;
    'IO177':'(0,177)';$S;BIDI;
    'IO178':'(0,178)';$S;BIDI;
    'IO179':'(0,179)';$S;BIDI;
    'IO180':'(0,180)';$S;BIDI;
    'IO181':'(0,181)';$S;BIDI;
    'IO182':'(0,182)';$S;BIDI;
    'IO183':'(0,183)';$S;BIDI;
    'IO184':'(0,184)';$S;BIDI;
    'IO185':'(0,185)';$S;BIDI;
    'IO186':'(0,186)';$S;BIDI;
    'IO187':'(0,187)';$S;BIDI;
    'IO188':'(0,188)';$S;BIDI;
    'IO189':'(0,189)';$S;BIDI;
    'IO190':'(0,190)';$S;BIDI;
    'IO191':'(0,191)';$S;BIDI;
    'IO192':'(0,192)';$S;BIDI;
    'IO193':'(0,193)';$S;BIDI;
    'IO194':'(0,194)';$S;BIDI;
    'IO195':'(0,195)';$S;BIDI;
    'IO196':'(0,196)';$S;BIDI;
    'IO197':'(0,197)';$S;BIDI;
    'IO198':'(0,198)';$S;BIDI;
    'IO199':'(0,199)';$S;BIDI;
    'IO200':'(0,200)';$S;BIDI;
    'MH1':'(MH1,0)';$S;
    'MH2':'(MH2,0)';$S;
end_primitive;
primitive 'SCONN24_H46321001_SM-SCONN,H46A';body 'SCONN24_H46321001';
    'IO1':'(1)';BIDI;
    'IO10':'(10)';BIDI;
    'IO11':'(11)';BIDI;
    'IO12':'(12)';BIDI;
    'IO13':'(13)';BIDI;
    'IO14':'(14)';BIDI;
    'IO15':'(15)';BIDI;
    'IO16':'(16)';BIDI;
    'IO17':'(17)';BIDI;
    'IO18':'(18)';BIDI;
    'IO19':'(19)';BIDI;
    'IO2':'(2)';BIDI;
    'IO20':'(20)';BIDI;
    'IO21':'(21)';BIDI;
    'IO22':'(22)';BIDI;
    'IO23':'(23)';BIDI;
    'IO24':'(24)';BIDI;
    'IO3':'(3)';BIDI;
    'IO4':'(4)';BIDI;
    'IO5':'(5)';BIDI;
    'IO6':'(6)';BIDI;
    'IO7':'(7)';BIDI;
    'IO8':'(8)';BIDI;
    'IO9':'(9)';BIDI;
    'MP1':'(MP1)';
    'MP2':'(MP2)';
end_primitive;
primitive 'SCONN288_H44441003_PIP-SCONN,HA';body 'SCONN288_H44441003';
    '12V'<1>:'(0,0,0,1)';
    '12V'<0>:'(0,0,0,145)';
    'A0':'(79,0,0,0)';$S;BIDI;
    'A1':'(72,0,0,0)';$S;BIDI;
    'A10':'(225,0,0,0)';$S;BIDI;
    'A11':'(210,0,0,0)';$S;BIDI;
    'A12':'(65,0,0,0)';$S;BIDI;
    'A13':'(232,0,0,0)';$S;BIDI;
    'A14_WE_N':'(228,0,0,0)';$S;BIDI;
    'A15_CAS_N':'(86,0,0,0)';$S;BIDI;
    'A16_RAS_N':'(82,0,0,0)';$S;BIDI;
    'A17':'(234,0,0,0)';$S;BIDI;
    'A2':'(216,0,0,0)';$S;BIDI;
    'A3':'(71,0,0,0)';$S;BIDI;
    'A4':'(214,0,0,0)';$S;BIDI;
    'A5':'(213,0,0,0)';$S;BIDI;
    'A6':'(69,0,0,0)';$S;BIDI;
    'A7':'(211,0,0,0)';$S;BIDI;
    'A8':'(68,0,0,0)';$S;BIDI;
    'A9':'(66,0,0,0)';$S;BIDI;
    'ACT_N':'(62,0,0,0)';$S;BIDI;
    'ALERT_N':'(208,0,0,0)';$S;BIDI;
    'BA'<1>:'(224,0,0,0)';BIDI;
    'BA'<0>:'(81,0,0,0)';BIDI;
    'BG'<1>:'(207,0,0,0)';BIDI;
    'BG'<0>:'(63,0,0,0)';BIDI;
    'C'<2>:'(235,0,0,0)';$S;BIDI;
    'CB'<7>:'(199,0,0,0)';BIDI;
    'CB'<6>:'(54,0,0,0)';BIDI;
    'CB'<5>:'(192,0,0,0)';BIDI;
    'CB'<4>:'(47,0,0,0)';BIDI;
    'CB'<3>:'(201,0,0,0)';BIDI;
    'CB'<2>:'(56,0,0,0)';BIDI;
    'CB'<1>:'(194,0,0,0)';BIDI;
    'CB'<0>:'(49,0,0,0)';BIDI;
    'CK0N':'(75,0,0,0)';$S;BIDI;
    'CK0P':'(74,0,0,0)';$S;BIDI;
    'CK1N':'(219,0,0,0)';$S;BIDI;
    'CK1P':'(218,0,0,0)';$S;BIDI;
    'CKE'<1>:'(203,0,0,0)';BIDI;
    'CKE'<0>:'(60,0,0,0)';BIDI;
    'DQ'<63>:'(280,0,0,0)';BIDI;
    'DQ'<62>:'(135,0,0,0)';BIDI;
    'DQ'<61>:'(273,0,0,0)';BIDI;
    'DQ'<60>:'(128,0,0,0)';BIDI;
    'DQ'<59>:'(282,0,0,0)';BIDI;
    'DQ'<58>:'(137,0,0,0)';BIDI;
    'DQ'<57>:'(275,0,0,0)';BIDI;
    'DQ'<56>:'(130,0,0,0)';BIDI;
    'DQ'<55>:'(269,0,0,0)';BIDI;
    'DQ'<54>:'(124,0,0,0)';BIDI;
    'DQ'<53>:'(262,0,0,0)';BIDI;
    'DQ'<52>:'(117,0,0,0)';BIDI;
    'DQ'<51>:'(271,0,0,0)';BIDI;
    'DQ'<50>:'(126,0,0,0)';BIDI;
    'DQ'<49>:'(264,0,0,0)';BIDI;
    'DQ'<48>:'(119,0,0,0)';BIDI;
    'DQ'<47>:'(258,0,0,0)';BIDI;
    'DQ'<46>:'(113,0,0,0)';BIDI;
    'DQ'<45>:'(251,0,0,0)';BIDI;
    'DQ'<44>:'(106,0,0,0)';BIDI;
    'DQ'<43>:'(260,0,0,0)';BIDI;
    'DQ'<42>:'(115,0,0,0)';BIDI;
    'DQ'<41>:'(253,0,0,0)';BIDI;
    'DQ'<40>:'(108,0,0,0)';BIDI;
    'DQ'<39>:'(247,0,0,0)';BIDI;
    'DQ'<38>:'(102,0,0,0)';BIDI;
    'DQ'<37>:'(240,0,0,0)';BIDI;
    'DQ'<36>:'(95,0,0,0)';BIDI;
    'DQ'<35>:'(249,0,0,0)';BIDI;
    'DQ'<34>:'(104,0,0,0)';BIDI;
    'DQ'<33>:'(242,0,0,0)';BIDI;
    'DQ'<32>:'(97,0,0,0)';BIDI;
    'DQ'<31>:'(188,0,0,0)';BIDI;
    'DQ'<30>:'(43,0,0,0)';BIDI;
    'DQ'<29>:'(181,0,0,0)';BIDI;
    'DQ'<28>:'(36,0,0,0)';BIDI;
    'DQ'<27>:'(190,0,0,0)';BIDI;
    'DQ'<26>:'(45,0,0,0)';BIDI;
    'DQ'<25>:'(183,0,0,0)';BIDI;
    'DQ'<24>:'(38,0,0,0)';BIDI;
    'DQ'<23>:'(177,0,0,0)';BIDI;
    'DQ'<22>:'(32,0,0,0)';BIDI;
    'DQ'<21>:'(170,0,0,0)';BIDI;
    'DQ'<20>:'(25,0,0,0)';BIDI;
    'DQ'<19>:'(179,0,0,0)';BIDI;
    'DQ'<18>:'(34,0,0,0)';BIDI;
    'DQ'<17>:'(172,0,0,0)';BIDI;
    'DQ'<16>:'(27,0,0,0)';BIDI;
    'DQ'<15>:'(166,0,0,0)';BIDI;
    'DQ'<14>:'(21,0,0,0)';BIDI;
    'DQ'<13>:'(159,0,0,0)';BIDI;
    'DQ'<12>:'(14,0,0,0)';BIDI;
    'DQ'<11>:'(168,0,0,0)';BIDI;
    'DQ'<10>:'(23,0,0,0)';BIDI;
    'DQ'<9>:'(161,0,0,0)';BIDI;
    'DQ'<8>:'(16,0,0,0)';BIDI;
    'DQ'<7>:'(155,0,0,0)';BIDI;
    'DQ'<6>:'(10,0,0,0)';BIDI;
    'DQ'<5>:'(148,0,0,0)';BIDI;
    'DQ'<4>:'(3,0,0,0)';BIDI;
    'DQ'<3>:'(157,0,0,0)';BIDI;
    'DQ'<2>:'(12,0,0,0)';BIDI;
    'DQ'<1>:'(150,0,0,0)';BIDI;
    'DQ'<0>:'(5,0,0,0)';BIDI;
    'DQS0N':'(0,152,0,0)';$S;BIDI;
    'DQS0P':'(0,153,0,0)';$S;BIDI;
    'DQS10N':'(0,19,0,0)';$S;BIDI;
    'DQS10P':'(0,18,0,0)';$S;BIDI;
    'DQS11N':'(0,30,0,0)';$S;BIDI;
    'DQS11P':'(0,29,0,0)';$S;BIDI;
    'DQS12N':'(0,41,0,0)';$S;BIDI;
    'DQS12P':'(0,40,0,0)';$S;BIDI;
    'DQS13N':'(0,100,0,0)';$S;BIDI;
    'DQS13P':'(0,99,0,0)';$S;BIDI;
    'DQS14N':'(0,111,0,0)';$S;BIDI;
    'DQS14P':'(0,110,0,0)';$S;BIDI;
    'DQS15N':'(0,122,0,0)';$S;BIDI;
    'DQS15P':'(0,121,0,0)';$S;BIDI;
    'DQS16N':'(0,133,0,0)';$S;BIDI;
    'DQS16P':'(0,132,0,0)';$S;BIDI;
    'DQS17N':'(0,52,0,0)';$S;BIDI;
    'DQS17P':'(0,51,0,0)';$S;BIDI;
    'DQS1N':'(0,163,0,0)';$S;BIDI;
    'DQS1P':'(0,164,0,0)';$S;BIDI;
    'DQS2N':'(0,174,0,0)';$S;BIDI;
    'DQS2P':'(0,175,0,0)';$S;BIDI;
    'DQS3N':'(0,185,0,0)';$S;BIDI;
    'DQS3P':'(0,186,0,0)';$S;BIDI;
    'DQS4N':'(0,244,0,0)';$S;BIDI;
    'DQS4P':'(0,245,0,0)';$S;BIDI;
    'DQS5N':'(0,255,0,0)';$S;BIDI;
    'DQS5P':'(0,256,0,0)';$S;BIDI;
    'DQS6N':'(0,266,0,0)';$S;BIDI;
    'DQS6P':'(0,267,0,0)';$S;BIDI;
    'DQS7N':'(0,277,0,0)';$S;BIDI;
    'DQS7P':'(0,278,0,0)';$S;BIDI;
    'DQS8N':'(0,196,0,0)';$S;BIDI;
    'DQS8P':'(0,197,0,0)';$S;BIDI;
    'DQS9N':'(0,8,0,0)';$S;BIDI;
    'DQS9P':'(0,7,0,0)';$S;BIDI;
    'EVENT_N':'(78,0,0,0)';$S;BIDI;
    'ODT'<1>:'(91,0,0,0)';BIDI;
    'ODT'<0>:'(87,0,0,0)';BIDI;
    'PAR':'(222,0,0,0)';$S;BIDI;
    'RESET_N':'(58,0,0,0)';$S;BIDI;
    'RFU'<2>:'(144,0,0,0)';BIDI;
    'RFU'<1>:'(227,0,0,0)';BIDI;
    'RFU'<0>:'(205,0,0,0)';BIDI;
    'S0_N':'(84,0,0,0)';$S;BIDI;
    'S1_N':'(89,0,0,0)';$S;BIDI;
    'S2_N_C'<0>:'(93,0,0,0)';$S;BIDI;
    'S3_N_C'<1>:'(237,0,0,0)';$S;BIDI;
    'SA'<2>:'(238,0,0,0)';BIDI;
    'SA'<1>:'(140,0,0,0)';BIDI;
    'SA'<0>:'(139,0,0,0)';BIDI;
    'SAVE_N_NC':'(230,0,0,0)';$S;BIDI;
    'SCL':'(141,0,0,0)';$S;BIDI;
    'SDA':'(285,0,0,0)';$S;BIDI;
    'VDD'<25>:'(0,0,0,59)';
    'VDD'<24>:'(0,0,0,61)';
    'VDD'<23>:'(0,0,0,64)';
    'VDD'<22>:'(0,0,0,67)';
    'VDD'<21>:'(0,0,0,70)';
    'VDD'<20>:'(0,0,0,73)';
    'VDD'<19>:'(0,0,0,76)';
    'VDD'<18>:'(0,0,0,80)';
    'VDD'<17>:'(0,0,0,83)';
    'VDD'<16>:'(0,0,0,85)';
    'VDD'<15>:'(0,0,0,88)';
    'VDD'<14>:'(0,0,0,90)';
    'VDD'<13>:'(0,0,0,92)';
    'VDD'<12>:'(0,0,0,204)';
    'VDD'<11>:'(0,0,0,206)';
    'VDD'<10>:'(0,0,0,209)';
    'VDD'<9>:'(0,0,0,212)';
    'VDD'<8>:'(0,0,0,215)';
    'VDD'<7>:'(0,0,0,217)';
    'VDD'<6>:'(0,0,0,220)';
    'VDD'<5>:'(0,0,0,223)';
    'VDD'<4>:'(0,0,0,226)';
    'VDD'<3>:'(0,0,0,229)';
    'VDD'<2>:'(0,0,0,231)';
    'VDD'<1>:'(0,0,0,233)';
    'VDD'<0>:'(0,0,0,236)';
    'VDDSPD':'(284,0,0,0)';$S;BIDI;
    'VPP'<4>:'(0,0,0,142)';
    'VPP'<3>:'(0,0,0,143)';
    'VPP'<2>:'(0,0,0,288)';
    'VPP'<1>:'(0,0,0,286)';
    'VPP'<0>:'(0,0,0,287)';
    'VREFCA':'(146,0,0,0)';$S;BIDI;
    'VSS'<93>:'(0,0,2,0)';
    'VSS'<92>:'(0,0,4,0)';
    'VSS'<91>:'(0,0,6,0)';
    'VSS'<90>:'(0,0,9,0)';
    'VSS'<89>:'(0,0,11,0)';
    'VSS'<88>:'(0,0,13,0)';
    'VSS'<87>:'(0,0,15,0)';
    'VSS'<86>:'(0,0,17,0)';
    'VSS'<85>:'(0,0,20,0)';
    'VSS'<84>:'(0,0,22,0)';
    'VSS'<83>:'(0,0,24,0)';
    'VSS'<82>:'(0,0,26,0)';
    'VSS'<81>:'(0,0,28,0)';
    'VSS'<80>:'(0,0,31,0)';
    'VSS'<79>:'(0,0,33,0)';
    'VSS'<78>:'(0,0,35,0)';
    'VSS'<77>:'(0,0,37,0)';
    'VSS'<76>:'(0,0,39,0)';
    'VSS'<75>:'(0,0,42,0)';
    'VSS'<74>:'(0,0,44,0)';
    'VSS'<73>:'(0,0,46,0)';
    'VSS'<72>:'(0,0,48,0)';
    'VSS'<71>:'(0,0,50,0)';
    'VSS'<70>:'(0,0,53,0)';
    'VSS'<69>:'(0,0,55,0)';
    'VSS'<68>:'(0,0,57,0)';
    'VSS'<67>:'(0,0,94,0)';
    'VSS'<66>:'(0,0,96,0)';
    'VSS'<65>:'(0,0,98,0)';
    'VSS'<64>:'(0,0,101,0)';
    'VSS'<63>:'(0,0,103,0)';
    'VSS'<62>:'(0,0,105,0)';
    'VSS'<61>:'(0,0,107,0)';
    'VSS'<60>:'(0,0,109,0)';
    'VSS'<59>:'(0,0,112,0)';
    'VSS'<58>:'(0,0,114,0)';
    'VSS'<57>:'(0,0,116,0)';
    'VSS'<56>:'(0,0,118,0)';
    'VSS'<55>:'(0,0,120,0)';
    'VSS'<54>:'(0,0,123,0)';
    'VSS'<53>:'(0,0,125,0)';
    'VSS'<52>:'(0,0,127,0)';
    'VSS'<51>:'(0,0,129,0)';
    'VSS'<50>:'(0,0,131,0)';
    'VSS'<49>:'(0,0,134,0)';
    'VSS'<48>:'(0,0,136,0)';
    'VSS'<47>:'(0,0,138,0)';
    'VSS'<46>:'(0,0,147,0)';
    'VSS'<45>:'(0,0,149,0)';
    'VSS'<44>:'(0,0,151,0)';
    'VSS'<43>:'(0,0,154,0)';
    'VSS'<42>:'(0,0,156,0)';
    'VSS'<41>:'(0,0,158,0)';
    'VSS'<40>:'(0,0,160,0)';
    'VSS'<39>:'(0,0,162,0)';
    'VSS'<38>:'(0,0,165,0)';
    'VSS'<37>:'(0,0,167,0)';
    'VSS'<36>:'(0,0,169,0)';
    'VSS'<35>:'(0,0,171,0)';
    'VSS'<34>:'(0,0,173,0)';
    'VSS'<33>:'(0,0,176,0)';
    'VSS'<32>:'(0,0,178,0)';
    'VSS'<31>:'(0,0,180,0)';
    'VSS'<30>:'(0,0,182,0)';
    'VSS'<29>:'(0,0,184,0)';
    'VSS'<28>:'(0,0,187,0)';
    'VSS'<27>:'(0,0,189,0)';
    'VSS'<26>:'(0,0,191,0)';
    'VSS'<25>:'(0,0,193,0)';
    'VSS'<24>:'(0,0,195,0)';
    'VSS'<23>:'(0,0,198,0)';
    'VSS'<22>:'(0,0,200,0)';
    'VSS'<21>:'(0,0,202,0)';
    'VSS'<20>:'(0,0,239,0)';
    'VSS'<19>:'(0,0,241,0)';
    'VSS'<18>:'(0,0,243,0)';
    'VSS'<17>:'(0,0,246,0)';
    'VSS'<16>:'(0,0,248,0)';
    'VSS'<15>:'(0,0,250,0)';
    'VSS'<14>:'(0,0,252,0)';
    'VSS'<13>:'(0,0,254,0)';
    'VSS'<12>:'(0,0,257,0)';
    'VSS'<11>:'(0,0,259,0)';
    'VSS'<10>:'(0,0,261,0)';
    'VSS'<9>:'(0,0,263,0)';
    'VSS'<8>:'(0,0,265,0)';
    'VSS'<7>:'(0,0,268,0)';
    'VSS'<6>:'(0,0,270,0)';
    'VSS'<5>:'(0,0,272,0)';
    'VSS'<4>:'(0,0,274,0)';
    'VSS'<3>:'(0,0,276,0)';
    'VSS'<2>:'(0,0,279,0)';
    'VSS'<1>:'(0,0,281,0)';
    'VSS'<0>:'(0,0,283,0)';
    'VTT'<1>:'(0,0,0,77)';
    'VTT'<0>:'(0,0,0,221)';
end_primitive;
primitive 'SCONN288_H44441004_PIP-SCONN,HA';body 'SCONN288_H44441004';
    '12V'<1>:'(0,0,0,1)';
    '12V'<0>:'(0,0,0,145)';
    'A0':'(79,0,0,0)';$S;BIDI;
    'A1':'(72,0,0,0)';$S;BIDI;
    'A10':'(225,0,0,0)';$S;BIDI;
    'A11':'(210,0,0,0)';$S;BIDI;
    'A12':'(65,0,0,0)';$S;BIDI;
    'A13':'(232,0,0,0)';$S;BIDI;
    'A14_WE_N':'(228,0,0,0)';$S;BIDI;
    'A15_CAS_N':'(86,0,0,0)';$S;BIDI;
    'A16_RAS_N':'(82,0,0,0)';$S;BIDI;
    'A17':'(234,0,0,0)';$S;BIDI;
    'A2':'(216,0,0,0)';$S;BIDI;
    'A3':'(71,0,0,0)';$S;BIDI;
    'A4':'(214,0,0,0)';$S;BIDI;
    'A5':'(213,0,0,0)';$S;BIDI;
    'A6':'(69,0,0,0)';$S;BIDI;
    'A7':'(211,0,0,0)';$S;BIDI;
    'A8':'(68,0,0,0)';$S;BIDI;
    'A9':'(66,0,0,0)';$S;BIDI;
    'ACT_N':'(62,0,0,0)';$S;BIDI;
    'ALERT_N':'(208,0,0,0)';$S;BIDI;
    'BA'<1>:'(224,0,0,0)';BIDI;
    'BA'<0>:'(81,0,0,0)';BIDI;
    'BG'<1>:'(207,0,0,0)';BIDI;
    'BG'<0>:'(63,0,0,0)';BIDI;
    'C'<2>:'(235,0,0,0)';$S;BIDI;
    'CB'<7>:'(199,0,0,0)';BIDI;
    'CB'<6>:'(54,0,0,0)';BIDI;
    'CB'<5>:'(192,0,0,0)';BIDI;
    'CB'<4>:'(47,0,0,0)';BIDI;
    'CB'<3>:'(201,0,0,0)';BIDI;
    'CB'<2>:'(56,0,0,0)';BIDI;
    'CB'<1>:'(194,0,0,0)';BIDI;
    'CB'<0>:'(49,0,0,0)';BIDI;
    'CK0N':'(75,0,0,0)';$S;BIDI;
    'CK0P':'(74,0,0,0)';$S;BIDI;
    'CK1N':'(219,0,0,0)';$S;BIDI;
    'CK1P':'(218,0,0,0)';$S;BIDI;
    'CKE'<1>:'(203,0,0,0)';BIDI;
    'CKE'<0>:'(60,0,0,0)';BIDI;
    'DQ'<63>:'(280,0,0,0)';BIDI;
    'DQ'<62>:'(135,0,0,0)';BIDI;
    'DQ'<61>:'(273,0,0,0)';BIDI;
    'DQ'<60>:'(128,0,0,0)';BIDI;
    'DQ'<59>:'(282,0,0,0)';BIDI;
    'DQ'<58>:'(137,0,0,0)';BIDI;
    'DQ'<57>:'(275,0,0,0)';BIDI;
    'DQ'<56>:'(130,0,0,0)';BIDI;
    'DQ'<55>:'(269,0,0,0)';BIDI;
    'DQ'<54>:'(124,0,0,0)';BIDI;
    'DQ'<53>:'(262,0,0,0)';BIDI;
    'DQ'<52>:'(117,0,0,0)';BIDI;
    'DQ'<51>:'(271,0,0,0)';BIDI;
    'DQ'<50>:'(126,0,0,0)';BIDI;
    'DQ'<49>:'(264,0,0,0)';BIDI;
    'DQ'<48>:'(119,0,0,0)';BIDI;
    'DQ'<47>:'(258,0,0,0)';BIDI;
    'DQ'<46>:'(113,0,0,0)';BIDI;
    'DQ'<45>:'(251,0,0,0)';BIDI;
    'DQ'<44>:'(106,0,0,0)';BIDI;
    'DQ'<43>:'(260,0,0,0)';BIDI;
    'DQ'<42>:'(115,0,0,0)';BIDI;
    'DQ'<41>:'(253,0,0,0)';BIDI;
    'DQ'<40>:'(108,0,0,0)';BIDI;
    'DQ'<39>:'(247,0,0,0)';BIDI;
    'DQ'<38>:'(102,0,0,0)';BIDI;
    'DQ'<37>:'(240,0,0,0)';BIDI;
    'DQ'<36>:'(95,0,0,0)';BIDI;
    'DQ'<35>:'(249,0,0,0)';BIDI;
    'DQ'<34>:'(104,0,0,0)';BIDI;
    'DQ'<33>:'(242,0,0,0)';BIDI;
    'DQ'<32>:'(97,0,0,0)';BIDI;
    'DQ'<31>:'(188,0,0,0)';BIDI;
    'DQ'<30>:'(43,0,0,0)';BIDI;
    'DQ'<29>:'(181,0,0,0)';BIDI;
    'DQ'<28>:'(36,0,0,0)';BIDI;
    'DQ'<27>:'(190,0,0,0)';BIDI;
    'DQ'<26>:'(45,0,0,0)';BIDI;
    'DQ'<25>:'(183,0,0,0)';BIDI;
    'DQ'<24>:'(38,0,0,0)';BIDI;
    'DQ'<23>:'(177,0,0,0)';BIDI;
    'DQ'<22>:'(32,0,0,0)';BIDI;
    'DQ'<21>:'(170,0,0,0)';BIDI;
    'DQ'<20>:'(25,0,0,0)';BIDI;
    'DQ'<19>:'(179,0,0,0)';BIDI;
    'DQ'<18>:'(34,0,0,0)';BIDI;
    'DQ'<17>:'(172,0,0,0)';BIDI;
    'DQ'<16>:'(27,0,0,0)';BIDI;
    'DQ'<15>:'(166,0,0,0)';BIDI;
    'DQ'<14>:'(21,0,0,0)';BIDI;
    'DQ'<13>:'(159,0,0,0)';BIDI;
    'DQ'<12>:'(14,0,0,0)';BIDI;
    'DQ'<11>:'(168,0,0,0)';BIDI;
    'DQ'<10>:'(23,0,0,0)';BIDI;
    'DQ'<9>:'(161,0,0,0)';BIDI;
    'DQ'<8>:'(16,0,0,0)';BIDI;
    'DQ'<7>:'(155,0,0,0)';BIDI;
    'DQ'<6>:'(10,0,0,0)';BIDI;
    'DQ'<5>:'(148,0,0,0)';BIDI;
    'DQ'<4>:'(3,0,0,0)';BIDI;
    'DQ'<3>:'(157,0,0,0)';BIDI;
    'DQ'<2>:'(12,0,0,0)';BIDI;
    'DQ'<1>:'(150,0,0,0)';BIDI;
    'DQ'<0>:'(5,0,0,0)';BIDI;
    'DQS0N':'(0,152,0,0)';$S;BIDI;
    'DQS0P':'(0,153,0,0)';$S;BIDI;
    'DQS10N':'(0,19,0,0)';$S;BIDI;
    'DQS10P':'(0,18,0,0)';$S;BIDI;
    'DQS11N':'(0,30,0,0)';$S;BIDI;
    'DQS11P':'(0,29,0,0)';$S;BIDI;
    'DQS12N':'(0,41,0,0)';$S;BIDI;
    'DQS12P':'(0,40,0,0)';$S;BIDI;
    'DQS13N':'(0,100,0,0)';$S;BIDI;
    'DQS13P':'(0,99,0,0)';$S;BIDI;
    'DQS14N':'(0,111,0,0)';$S;BIDI;
    'DQS14P':'(0,110,0,0)';$S;BIDI;
    'DQS15N':'(0,122,0,0)';$S;BIDI;
    'DQS15P':'(0,121,0,0)';$S;BIDI;
    'DQS16N':'(0,133,0,0)';$S;BIDI;
    'DQS16P':'(0,132,0,0)';$S;BIDI;
    'DQS17N':'(0,52,0,0)';$S;BIDI;
    'DQS17P':'(0,51,0,0)';$S;BIDI;
    'DQS1N':'(0,163,0,0)';$S;BIDI;
    'DQS1P':'(0,164,0,0)';$S;BIDI;
    'DQS2N':'(0,174,0,0)';$S;BIDI;
    'DQS2P':'(0,175,0,0)';$S;BIDI;
    'DQS3N':'(0,185,0,0)';$S;BIDI;
    'DQS3P':'(0,186,0,0)';$S;BIDI;
    'DQS4N':'(0,244,0,0)';$S;BIDI;
    'DQS4P':'(0,245,0,0)';$S;BIDI;
    'DQS5N':'(0,255,0,0)';$S;BIDI;
    'DQS5P':'(0,256,0,0)';$S;BIDI;
    'DQS6N':'(0,266,0,0)';$S;BIDI;
    'DQS6P':'(0,267,0,0)';$S;BIDI;
    'DQS7N':'(0,277,0,0)';$S;BIDI;
    'DQS7P':'(0,278,0,0)';$S;BIDI;
    'DQS8N':'(0,196,0,0)';$S;BIDI;
    'DQS8P':'(0,197,0,0)';$S;BIDI;
    'DQS9N':'(0,8,0,0)';$S;BIDI;
    'DQS9P':'(0,7,0,0)';$S;BIDI;
    'EVENT_N':'(78,0,0,0)';$S;BIDI;
    'ODT'<1>:'(91,0,0,0)';BIDI;
    'ODT'<0>:'(87,0,0,0)';BIDI;
    'PAR':'(222,0,0,0)';$S;BIDI;
    'RESET_N':'(58,0,0,0)';$S;BIDI;
    'RFU'<2>:'(144,0,0,0)';BIDI;
    'RFU'<1>:'(227,0,0,0)';BIDI;
    'RFU'<0>:'(205,0,0,0)';BIDI;
    'S0_N':'(84,0,0,0)';$S;BIDI;
    'S1_N':'(89,0,0,0)';$S;BIDI;
    'S2_N_C'<0>:'(93,0,0,0)';$S;BIDI;
    'S3_N_C'<1>:'(237,0,0,0)';$S;BIDI;
    'SA'<2>:'(238,0,0,0)';BIDI;
    'SA'<1>:'(140,0,0,0)';BIDI;
    'SA'<0>:'(139,0,0,0)';BIDI;
    'SAVE_N_NC':'(230,0,0,0)';$S;BIDI;
    'SCL':'(141,0,0,0)';$S;BIDI;
    'SDA':'(285,0,0,0)';$S;BIDI;
    'VDD'<25>:'(0,0,0,59)';
    'VDD'<24>:'(0,0,0,61)';
    'VDD'<23>:'(0,0,0,64)';
    'VDD'<22>:'(0,0,0,67)';
    'VDD'<21>:'(0,0,0,70)';
    'VDD'<20>:'(0,0,0,73)';
    'VDD'<19>:'(0,0,0,76)';
    'VDD'<18>:'(0,0,0,80)';
    'VDD'<17>:'(0,0,0,83)';
    'VDD'<16>:'(0,0,0,85)';
    'VDD'<15>:'(0,0,0,88)';
    'VDD'<14>:'(0,0,0,90)';
    'VDD'<13>:'(0,0,0,92)';
    'VDD'<12>:'(0,0,0,204)';
    'VDD'<11>:'(0,0,0,206)';
    'VDD'<10>:'(0,0,0,209)';
    'VDD'<9>:'(0,0,0,212)';
    'VDD'<8>:'(0,0,0,215)';
    'VDD'<7>:'(0,0,0,217)';
    'VDD'<6>:'(0,0,0,220)';
    'VDD'<5>:'(0,0,0,223)';
    'VDD'<4>:'(0,0,0,226)';
    'VDD'<3>:'(0,0,0,229)';
    'VDD'<2>:'(0,0,0,231)';
    'VDD'<1>:'(0,0,0,233)';
    'VDD'<0>:'(0,0,0,236)';
    'VDDSPD':'(284,0,0,0)';$S;BIDI;
    'VPP'<4>:'(0,0,0,142)';
    'VPP'<3>:'(0,0,0,143)';
    'VPP'<2>:'(0,0,0,288)';
    'VPP'<1>:'(0,0,0,286)';
    'VPP'<0>:'(0,0,0,287)';
    'VREFCA':'(146,0,0,0)';$S;BIDI;
    'VSS'<93>:'(0,0,2,0)';
    'VSS'<92>:'(0,0,4,0)';
    'VSS'<91>:'(0,0,6,0)';
    'VSS'<90>:'(0,0,9,0)';
    'VSS'<89>:'(0,0,11,0)';
    'VSS'<88>:'(0,0,13,0)';
    'VSS'<87>:'(0,0,15,0)';
    'VSS'<86>:'(0,0,17,0)';
    'VSS'<85>:'(0,0,20,0)';
    'VSS'<84>:'(0,0,22,0)';
    'VSS'<83>:'(0,0,24,0)';
    'VSS'<82>:'(0,0,26,0)';
    'VSS'<81>:'(0,0,28,0)';
    'VSS'<80>:'(0,0,31,0)';
    'VSS'<79>:'(0,0,33,0)';
    'VSS'<78>:'(0,0,35,0)';
    'VSS'<77>:'(0,0,37,0)';
    'VSS'<76>:'(0,0,39,0)';
    'VSS'<75>:'(0,0,42,0)';
    'VSS'<74>:'(0,0,44,0)';
    'VSS'<73>:'(0,0,46,0)';
    'VSS'<72>:'(0,0,48,0)';
    'VSS'<71>:'(0,0,50,0)';
    'VSS'<70>:'(0,0,53,0)';
    'VSS'<69>:'(0,0,55,0)';
    'VSS'<68>:'(0,0,57,0)';
    'VSS'<67>:'(0,0,94,0)';
    'VSS'<66>:'(0,0,96,0)';
    'VSS'<65>:'(0,0,98,0)';
    'VSS'<64>:'(0,0,101,0)';
    'VSS'<63>:'(0,0,103,0)';
    'VSS'<62>:'(0,0,105,0)';
    'VSS'<61>:'(0,0,107,0)';
    'VSS'<60>:'(0,0,109,0)';
    'VSS'<59>:'(0,0,112,0)';
    'VSS'<58>:'(0,0,114,0)';
    'VSS'<57>:'(0,0,116,0)';
    'VSS'<56>:'(0,0,118,0)';
    'VSS'<55>:'(0,0,120,0)';
    'VSS'<54>:'(0,0,123,0)';
    'VSS'<53>:'(0,0,125,0)';
    'VSS'<52>:'(0,0,127,0)';
    'VSS'<51>:'(0,0,129,0)';
    'VSS'<50>:'(0,0,131,0)';
    'VSS'<49>:'(0,0,134,0)';
    'VSS'<48>:'(0,0,136,0)';
    'VSS'<47>:'(0,0,138,0)';
    'VSS'<46>:'(0,0,147,0)';
    'VSS'<45>:'(0,0,149,0)';
    'VSS'<44>:'(0,0,151,0)';
    'VSS'<43>:'(0,0,154,0)';
    'VSS'<42>:'(0,0,156,0)';
    'VSS'<41>:'(0,0,158,0)';
    'VSS'<40>:'(0,0,160,0)';
    'VSS'<39>:'(0,0,162,0)';
    'VSS'<38>:'(0,0,165,0)';
    'VSS'<37>:'(0,0,167,0)';
    'VSS'<36>:'(0,0,169,0)';
    'VSS'<35>:'(0,0,171,0)';
    'VSS'<34>:'(0,0,173,0)';
    'VSS'<33>:'(0,0,176,0)';
    'VSS'<32>:'(0,0,178,0)';
    'VSS'<31>:'(0,0,180,0)';
    'VSS'<30>:'(0,0,182,0)';
    'VSS'<29>:'(0,0,184,0)';
    'VSS'<28>:'(0,0,187,0)';
    'VSS'<27>:'(0,0,189,0)';
    'VSS'<26>:'(0,0,191,0)';
    'VSS'<25>:'(0,0,193,0)';
    'VSS'<24>:'(0,0,195,0)';
    'VSS'<23>:'(0,0,198,0)';
    'VSS'<22>:'(0,0,200,0)';
    'VSS'<21>:'(0,0,202,0)';
    'VSS'<20>:'(0,0,239,0)';
    'VSS'<19>:'(0,0,241,0)';
    'VSS'<18>:'(0,0,243,0)';
    'VSS'<17>:'(0,0,246,0)';
    'VSS'<16>:'(0,0,248,0)';
    'VSS'<15>:'(0,0,250,0)';
    'VSS'<14>:'(0,0,252,0)';
    'VSS'<13>:'(0,0,254,0)';
    'VSS'<12>:'(0,0,257,0)';
    'VSS'<11>:'(0,0,259,0)';
    'VSS'<10>:'(0,0,261,0)';
    'VSS'<9>:'(0,0,263,0)';
    'VSS'<8>:'(0,0,265,0)';
    'VSS'<7>:'(0,0,268,0)';
    'VSS'<6>:'(0,0,270,0)';
    'VSS'<5>:'(0,0,272,0)';
    'VSS'<4>:'(0,0,274,0)';
    'VSS'<3>:'(0,0,276,0)';
    'VSS'<2>:'(0,0,279,0)';
    'VSS'<1>:'(0,0,281,0)';
    'VSS'<0>:'(0,0,283,0)';
    'VTT'<1>:'(0,0,0,77)';
    'VTT'<0>:'(0,0,0,221)';
end_primitive;
primitive 'SCONN3_D53458001_SM-EMPTY,D534A';body 'SCONN3_D53458001';
    'IO1':'(1)';BIDI;
    'IO2':'(2)';BIDI;
    'IO3':'(3)';BIDI;
end_primitive;
primitive 'SCONN60_C21100002_SMLF-CONN,C2A';body 'SCONN60_C21100002';
    'IO1':'(1)';
    'IO3':'(3)';
    'IO5':'(5)';
    'IO7':'(7)';
    'IO9':'(9)';
    'IO11':'(11)';
    'IO13':'(13)';
    'IO15':'(15)';
    'IO17':'(17)';
    'IO19':'(19)';
    'IO21':'(21)';
    'IO23':'(23)';
    'IO25':'(25)';
    'IO27':'(27)';
    'IO29':'(29)';
    'IO31':'(31)';
    'IO33':'(33)';
    'IO35':'(35)';
    'IO37':'(37)';
    'IO39':'(39)';
    'IO41':'(41)';
    'IO43':'(43)';
    'IO45':'(45)';
    'IO47':'(47)';
    'IO49':'(49)';
    'IO2':'(2)';
    'IO4':'(4)';
    'IO6':'(6)';
    'IO8':'(8)';
    'IO10':'(10)';
    'IO12':'(12)';
    'IO14':'(14)';
    'IO16':'(16)';
    'IO18':'(18)';
    'IO20':'(20)';
    'IO22':'(22)';
    'IO24':'(24)';
    'IO26':'(26)';
    'IO28':'(28)';
    'IO30':'(30)';
    'IO32':'(32)';
    'IO34':'(34)';
    'IO36':'(36)';
    'IO38':'(38)';
    'IO40':'(40)';
    'IO42':'(42)';
    'IO44':'(44)';
    'IO46':'(46)';
    'IO48':'(48)';
    'IO50':'(50)';
    'IO51':'(51)';
    'IO52':'(52)';
    'IO53':'(53)';
    'IO54':'(54)';
    'IO55':'(55)';
    'IO56':'(56)';
    'IO57':'(57)';
    'IO58':'(58)';
    'IO59':'(59)';
    'IO60':'(60)';
end_primitive;
primitive 'SCONN64_H87568002_A_SMT-CONN,HA';body 'SCONN64_H87568002_A';
    'IO1':'(1)';BIDI;
    'IO10':'(10)';BIDI;
    'IO11':'(11)';BIDI;
    'IO12':'(12)';BIDI;
    'IO13':'(13)';BIDI;
    'IO14':'(14)';BIDI;
    'IO15':'(15)';BIDI;
    'IO16':'(16)';BIDI;
    'IO17':'(17)';BIDI;
    'IO18':'(18)';BIDI;
    'IO19':'(19)';BIDI;
    'IO2':'(2)';BIDI;
    'IO20':'(20)';BIDI;
    'IO21':'(21)';BIDI;
    'IO22':'(22)';BIDI;
    'IO23':'(23)';BIDI;
    'IO24':'(24)';BIDI;
    'IO25':'(25)';BIDI;
    'IO26':'(26)';BIDI;
    'IO27':'(27)';BIDI;
    'IO28':'(28)';BIDI;
    'IO29':'(29)';BIDI;
    'IO3':'(3)';BIDI;
    'IO30':'(30)';BIDI;
    'IO31':'(31)';BIDI;
    'IO32':'(32)';BIDI;
    'IO33':'(33)';BIDI;
    'IO34':'(34)';BIDI;
    'IO35':'(35)';BIDI;
    'IO36':'(36)';BIDI;
    'IO37':'(37)';BIDI;
    'IO38':'(38)';BIDI;
    'IO39':'(39)';BIDI;
    'IO4':'(4)';BIDI;
    'IO40':'(40)';BIDI;
    'IO41':'(41)';BIDI;
    'IO42':'(42)';BIDI;
    'IO43':'(43)';BIDI;
    'IO44':'(44)';BIDI;
    'IO45':'(45)';BIDI;
    'IO46':'(46)';BIDI;
    'IO47':'(47)';BIDI;
    'IO48':'(48)';BIDI;
    'IO49':'(49)';BIDI;
    'IO5':'(5)';BIDI;
    'IO50':'(50)';BIDI;
    'IO51':'(51)';BIDI;
    'IO52':'(52)';BIDI;
    'IO53':'(53)';BIDI;
    'IO54':'(54)';BIDI;
    'IO55':'(55)';BIDI;
    'IO56':'(56)';BIDI;
    'IO57':'(57)';BIDI;
    'IO58':'(58)';BIDI;
    'IO59':'(59)';BIDI;
    'IO6':'(6)';BIDI;
    'IO60':'(60)';BIDI;
    'IO61':'(61)';BIDI;
    'IO62':'(62)';BIDI;
    'IO63':'(63)';BIDI;
    'IO64':'(64)';BIDI;
    'IO7':'(7)';BIDI;
    'IO8':'(8)';BIDI;
    'IO9':'(9)';BIDI;
end_primitive;
primitive 'SCONN75K_H17033002_SMT1-SCONN,A';body 'SCONN75K_H17033002';
    'GND'<0>:'(1)';
    '3_3V'<0>:'(2)';
    'GND'<1>:'(3)';
    '3_3V'<1>:'(4)';
    'PERN3':'(5)';BIDI;
    'NC'<0>:'(6)';
    'PERP3':'(7)';BIDI;
    'NC'<1>:'(8)';
    'GND'<2>:'(9)';
    'DAS_DSS_N':'(10)';IN;
    'PETN3':'(11)';BIDI;
    '3_3V'<2>:'(12)';
    'PETP3':'(13)';BIDI;
    '3_3V'<3>:'(14)';
    'GND'<3>:'(15)';
    '3_3V'<4>:'(16)';
    'PERN2':'(17)';BIDI;
    '3_3V'<5>:'(18)';
    'PERP2':'(19)';BIDI;
    'NC'<2>:'(20)';
    'GND'<4>:'(21)';
    'NC'<3>:'(22)';
    'PETN2':'(23)';BIDI;
    'NC'<4>:'(24)';
    'PETP2':'(25)';BIDI;
    'NC'<5>:'(26)';
    'GND'<5>:'(27)';
    'NC'<6>:'(28)';
    'PERN1':'(29)';BIDI;
    'NC'<7>:'(30)';
    'PERP1':'(31)';BIDI;
    'NC'<8>:'(32)';
    'GND'<6>:'(33)';
    'NC'<9>:'(34)';
    'PETN1':'(35)';BIDI;
    'NC'<10>:'(36)';
    'PETP1':'(37)';BIDI;
    'DEVSLP':'(38)';OUT;
    'GND'<7>:'(39)';
    'NC'<11>:'(40)';
    'PERN0_SATA_BP':'(41)';BIDI;
    'NC'<12>:'(42)';
    'PERP0_SATA_BN':'(43)';BIDI;
    'NC'<13>:'(44)';
    'GND'<8>:'(45)';
    'NC'<14>:'(46)';
    'PETN0_SATA_AN':'(47)';BIDI;
    'NC'<15>:'(48)';
    'PETP0_SATA_AP':'(49)';BIDI;
    'PERST_N_NC':'(50)';OUT;
    'GND'<9>:'(51)';
    'CLKREQ_N_NC':'(52)';BIDI;
    'REFCLKN':'(53)';BIDI;
    'PEWAKE_N_NC':'(54)';BIDI;
    'REFCLKP':'(55)';BIDI;
    'NC'<16>:'(56)';
    'GND'<10>:'(57)';
    'NC'<17>:'(58)';
    'NC'<18>:'(67)';
    'SUSCLK':'(68)';OUT;
    'PEDET':'(69)';BIDI;
    '3_3V'<6>:'(70)';
    'GND'<11>:'(71)';
    '3_3V'<7>:'(72)';
    'GND'<12>:'(73)';
    '3_3V'<8>:'(74)';
    'GND'<13>:'(75)';
    'MP1':'(MP1)';
    'MP2':'(MP2)';
end_primitive;
primitive 'SCONN80_E67482007_SM-CONN,E674A';body 'SCONN80_E67482007';
    'IO1':'(1)';BIDI;
    'IO10':'(10)';BIDI;
    'IO11':'(11)';BIDI;
    'IO12':'(12)';BIDI;
    'IO13':'(13)';BIDI;
    'IO14':'(14)';BIDI;
    'IO15':'(15)';BIDI;
    'IO16':'(16)';BIDI;
    'IO17':'(17)';BIDI;
    'IO18':'(18)';BIDI;
    'IO19':'(19)';BIDI;
    'IO2':'(2)';BIDI;
    'IO20':'(20)';BIDI;
    'IO21':'(21)';BIDI;
    'IO22':'(22)';BIDI;
    'IO23':'(23)';BIDI;
    'IO24':'(24)';BIDI;
    'IO25':'(25)';BIDI;
    'IO26':'(26)';BIDI;
    'IO27':'(27)';BIDI;
    'IO28':'(28)';BIDI;
    'IO29':'(29)';BIDI;
    'IO3':'(3)';BIDI;
    'IO30':'(30)';BIDI;
    'IO31':'(31)';BIDI;
    'IO32':'(32)';BIDI;
    'IO33':'(33)';BIDI;
    'IO34':'(34)';BIDI;
    'IO35':'(35)';BIDI;
    'IO36':'(36)';BIDI;
    'IO37':'(37)';BIDI;
    'IO38':'(38)';BIDI;
    'IO39':'(39)';BIDI;
    'IO4':'(4)';BIDI;
    'IO40':'(40)';BIDI;
    'IO41':'(41)';BIDI;
    'IO42':'(42)';BIDI;
    'IO43':'(43)';BIDI;
    'IO44':'(44)';BIDI;
    'IO45':'(45)';BIDI;
    'IO46':'(46)';BIDI;
    'IO47':'(47)';BIDI;
    'IO48':'(48)';BIDI;
    'IO49':'(49)';BIDI;
    'IO5':'(5)';BIDI;
    'IO50':'(50)';BIDI;
    'IO51':'(51)';BIDI;
    'IO52':'(52)';BIDI;
    'IO53':'(53)';BIDI;
    'IO54':'(54)';BIDI;
    'IO55':'(55)';BIDI;
    'IO56':'(56)';BIDI;
    'IO57':'(57)';BIDI;
    'IO58':'(58)';BIDI;
    'IO59':'(59)';BIDI;
    'IO6':'(6)';BIDI;
    'IO60':'(60)';BIDI;
    'IO61':'(61)';BIDI;
    'IO62':'(62)';BIDI;
    'IO63':'(63)';BIDI;
    'IO64':'(64)';BIDI;
    'IO65':'(65)';BIDI;
    'IO66':'(66)';BIDI;
    'IO67':'(67)';BIDI;
    'IO68':'(68)';BIDI;
    'IO69':'(69)';BIDI;
    'IO7':'(7)';BIDI;
    'IO70':'(70)';BIDI;
    'IO71':'(71)';BIDI;
    'IO72':'(72)';BIDI;
    'IO73':'(73)';BIDI;
    'IO74':'(74)';BIDI;
    'IO75':'(75)';BIDI;
    'IO76':'(76)';BIDI;
    'IO77':'(77)';BIDI;
    'IO78':'(78)';BIDI;
    'IO79':'(79)';BIDI;
    'IO8':'(8)';BIDI;
    'IO80':'(80)';BIDI;
    'IO9':'(9)';BIDI;
end_primitive;
primitive 'SHUNT_SH0201-EMPTY,N_A';body 'SHUNT';
    'A':'(1)';
    'B':'(2)';
end_primitive;
primitive 'SKX_EXT_B_BGA1-IC,TBD';body 'SKX_EXT_B';
    'BCLK0_DN':'(AU24,0,0,0,0,0,0,0,0,0,0,0,0,0,0,0,0,0,0,0,0,0,0,0,0,0,0,0,0,0)~
';$S;IN;
    'BCLK0_DP':'(AW24,0,0,0,0,0,0,0,0,0,0,0,0,0,0,0,0,0,0,0,0,0,0,0,0,0,0,0,0,0)~
';$S;IN;
    'BCLK1_DN':'(CR26,0,0,0,0,0,0,0,0,0,0,0,0,0,0,0,0,0,0,0,0,0,0,0,0,0,0,0,0,0)~
';$S;IN;
    'BCLK1_DP':'(CP27,0,0,0,0,0,0,0,0,0,0,0,0,0,0,0,0,0,0,0,0,0,0,0,0,0,0,0,0,0)~
';$S;IN;
    'BCLK2_DN':'(CT25,0,0,0,0,0,0,0,0,0,0,0,0,0,0,0,0,0,0,0,0,0,0,0,0,0,0,0,0,0)~
';$S;IN;
    'BCLK2_DP':'(CU26,0,0,0,0,0,0,0,0,0,0,0,0,0,0,0,0,0,0,0,0,0,0,0,0,0,0,0,0,0)~
';$S;IN;
    'BIST_ENABLE':'(BA20,0,0,0,0,0,0,0,0,0,0,0,0,0,0,0,0,0,0,0,0,0,0,0,0,0,0,0,0~
,0)';$S;IN;
    'BMCINIT':'(BD23,0,0,0,0,0,0,0,0,0,0,0,0,0,0,0,0,0,0,0,0,0,0,0,0,0,0,0,0,0)';$S;IN;
    'BPM_N'<7>:'(AC12,0,0,0,0,0,0,0,0,0,0,0,0,0,0,0,0,0,0,0,0,0,0,0,0,0,0,0,0,0)~
';BIDI;
    'BPM_N'<6>:'(AE12,0,0,0,0,0,0,0,0,0,0,0,0,0,0,0,0,0,0,0,0,0,0,0,0,0,0,0,0,0)~
';BIDI;
    'BPM_N'<5>:'(Y11,0,0,0,0,0,0,0,0,0,0,0,0,0,0,0,0,0,0,0,0,0,0,0,0,0,0,0,0,0)';BIDI;
    'BPM_N'<4>:'(AA12,0,0,0,0,0,0,0,0,0,0,0,0,0,0,0,0,0,0,0,0,0,0,0,0,0,0,0,0,0)~
';BIDI;
    'BPM_N'<3>:'(AF11,0,0,0,0,0,0,0,0,0,0,0,0,0,0,0,0,0,0,0,0,0,0,0,0,0,0,0,0,0)~
';BIDI;
    'BPM_N'<2>:'(AG10,0,0,0,0,0,0,0,0,0,0,0,0,0,0,0,0,0,0,0,0,0,0,0,0,0,0,0,0,0)~
';BIDI;
    'BPM_N'<1>:'(AH11,0,0,0,0,0,0,0,0,0,0,0,0,0,0,0,0,0,0,0,0,0,0,0,0,0,0,0,0,0)~
';BIDI;
    'BPM_N'<0>:'(AJ10,0,0,0,0,0,0,0,0,0,0,0,0,0,0,0,0,0,0,0,0,0,0,0,0,0,0,0,0,0)~
';BIDI;
    'CATERR_N':'(AL14,0,0,0,0,0,0,0,0,0,0,0,0,0,0,0,0,0,0,0,0,0,0,0,0,0,0,0,0,0)~
';$S;BIDI;
    'CD_HFI0_I2CCLK':'(0,0,0,0,0,0,0,0,BN22,0,0,0,0,0,0,0,0,0,0,0,0,0,0,0,0,0,0,~
0,0,0)';$S;BIDI;
    'CD_HFI0_I2CDAT':'(0,0,0,0,0,0,0,0,BP23,0,0,0,0,0,0,0,0,0,0,0,0,0,0,0,0,0,0,~
0,0,0)';$S;BIDI;
    'CD_HFI0_INT_N':'(0,0,0,0,0,0,0,0,BP19,0,0,0,0,0,0,0,0,0,0,0,0,0,0,0,0,0,0,0~
,0,0)';$S;IN;
    'CD_HFI0_LED_N':'(0,0,0,0,0,0,0,0,BK21,0,0,0,0,0,0,0,0,0,0,0,0,0,0,0,0,0,0,0~
,0,0)';$S;OUT;
    'CD_HFI0_MODPRST_N':'(0,0,0,0,0,0,0,0,BR20,0,0,0,0,0,0,0,0,0,0,0,0,0,0,0,0,0~
,0,0,0,0)';$S;IN;
    'CD_HFI0_RESET_N':'(0,0,0,0,0,0,0,0,BN24,0,0,0,0,0,0,0,0,0,0,0,0,0,0,0,0,0,0~
,0,0,0)';$S;OUT;
    'CD_HFI1_I2CCLK':'(0,0,0,0,0,0,0,0,BJ22,0,0,0,0,0,0,0,0,0,0,0,0,0,0,0,0,0,0,~
0,0,0)';$S;BIDI;
    'CD_HFI1_I2CDAT':'(0,0,0,0,0,0,0,0,BH23,0,0,0,0,0,0,0,0,0,0,0,0,0,0,0,0,0,0,~
0,0,0)';$S;BIDI;
    'CD_HFI1_INT_N':'(0,0,0,0,0,0,0,0,BM21,0,0,0,0,0,0,0,0,0,0,0,0,0,0,0,0,0,0,0~
,0,0)';$S;IN;
    'CD_HFI1_LED_N':'(0,0,0,0,0,0,0,0,BM23,0,0,0,0,0,0,0,0,0,0,0,0,0,0,0,0,0,0,0~
,0,0)';$S;OUT;
    'CD_HFI1_MODPRST_N':'(0,0,0,0,0,0,0,0,BT19,0,0,0,0,0,0,0,0,0,0,0,0,0,0,0,0,0~
,0,0,0,0)';$S;IN;
    'CD_HFI1_RESET_N':'(0,0,0,0,0,0,0,0,BK23,0,0,0,0,0,0,0,0,0,0,0,0,0,0,0,0,0,0~
,0,0,0)';$S;OUT;
    'CD_HFI_REFCLK_DN':'(0,0,0,0,0,0,0,0,BE16,0,0,0,0,0,0,0,0,0,0,0,0,0,0,0,0,0,~
0,0,0,0)';$S;IN;
    'CD_HFI_REFCLK_DP':'(0,0,0,0,0,0,0,0,BG16,0,0,0,0,0,0,0,0,0,0,0,0,0,0,0,0,0,~
0,0,0,0)';$S;IN;
    'CD_PE_REFCLK_DN':'(0,0,0,0,0,0,0,0,BU24,0,0,0,0,0,0,0,0,0,0,0,0,0,0,0,0,0,0~
,0,0,0)';$S;IN;
    'CD_PE_REFCLK_DP':'(0,0,0,0,0,0,0,0,BW24,0,0,0,0,0,0,0,0,0,0,0,0,0,0,0,0,0,0~
,0,0,0)';$S;IN;
    'CD_POR_N':'(0,0,0,0,0,0,0,0,CF25,0,0,0,0,0,0,0,0,0,0,0,0,0,0,0,0,0,0,0,0,0)~
';$S;BIDI;
    'CD_TCLK':'(0,0,0,0,0,0,0,0,CB23,0,0,0,0,0,0,0,0,0,0,0,0,0,0,0,0,0,0,0,0,0)';$S;IN;
    'CD_TDI':'(0,0,0,0,0,0,0,0,BY21,0,0,0,0,0,0,0,0,0,0,0,0,0,0,0,0,0,0,0,0,0)';~
$S;IN;
    'CD_TDO':'(0,0,0,0,0,0,0,0,CC22,0,0,0,0,0,0,0,0,0,0,0,0,0,0,0,0,0,0,0,0,0)';~
$S;OUT;
    'CD_TMS':'(0,0,0,0,0,0,0,0,CE24,0,0,0,0,0,0,0,0,0,0,0,0,0,0,0,0,0,0,0,0,0)';~
$S;IN;
    'CD_TRST_N':'(0,0,0,0,0,0,0,0,CD23,0,0,0,0,0,0,0,0,0,0,0,0,0,0,0,0,0,0,0,0,0~
)';$S;IN;
    'CD_VCCIN'<3>:'(0,0,0,0,0,0,0,0,0,0,0,0,0,0,0,0,0,0,0,0,BY27,0,0,0,0,0,0,0,0~
,0)';
    'CD_VCCIN'<2>:'(0,0,0,0,0,0,0,0,0,0,0,0,0,0,0,0,0,0,0,0,BV27,0,0,0,0,0,0,0,0~
,0)';
    'CD_VCCIN'<1>:'(0,0,0,0,0,0,0,0,0,0,0,0,0,0,0,0,0,0,0,0,BU26,0,0,0,0,0,0,0,0~
,0)';
    'CD_VCCIN'<0>:'(0,0,0,0,0,0,0,0,0,0,0,0,0,0,0,0,0,0,0,0,BT27,0,0,0,0,0,0,0,0~
,0)';
    'CD_VCCP'<15>:'(0,0,0,0,0,0,0,0,0,0,0,0,0,0,0,0,0,0,0,0,BM11,0,0,0,0,0,0,0,0~
,0)';
    'CD_VCCP'<14>:'(0,0,0,0,0,0,0,0,0,0,0,0,0,0,0,0,0,0,0,0,BN12,0,0,0,0,0,0,0,0~
,0)';
    'CD_VCCP'<13>:'(0,0,0,0,0,0,0,0,0,0,0,0,0,0,0,0,0,0,0,0,BN14,0,0,0,0,0,0,0,0~
,0)';
    'CD_VCCP'<12>:'(0,0,0,0,0,0,0,0,0,0,0,0,0,0,0,0,0,0,0,0,BP11,0,0,0,0,0,0,0,0~
,0)';
    'CD_VCCP'<11>:'(0,0,0,0,0,0,0,0,0,0,0,0,0,0,0,0,0,0,0,0,BP13,0,0,0,0,0,0,0,0~
,0)';
    'CD_VCCP'<10>:'(0,0,0,0,0,0,0,0,0,0,0,0,0,0,0,0,0,0,0,0,BP15,0,0,0,0,0,0,0,0~
,0)';
    'CD_VCCP'<9>:'(0,0,0,0,0,0,0,0,0,0,0,0,0,0,0,0,0,0,0,0,BR12,0,0,0,0,0,0,0,0,~
0)';
    'CD_VCCP'<8>:'(0,0,0,0,0,0,0,0,0,0,0,0,0,0,0,0,0,0,0,0,BR14,0,0,0,0,0,0,0,0,~
0)';
    'CD_VCCP'<7>:'(0,0,0,0,0,0,0,0,0,0,0,0,0,0,0,0,0,0,0,0,BT11,0,0,0,0,0,0,0,0,~
0)';
    'CD_VCCP'<6>:'(0,0,0,0,0,0,0,0,0,0,0,0,0,0,0,0,0,0,0,0,BT13,0,0,0,0,0,0,0,0,~
0)';
    'CD_VCCP'<5>:'(0,0,0,0,0,0,0,0,0,0,0,0,0,0,0,0,0,0,0,0,BT15,0,0,0,0,0,0,0,0,~
0)';
    'CD_VCCP'<4>:'(0,0,0,0,0,0,0,0,0,0,0,0,0,0,0,0,0,0,0,0,BU12,0,0,0,0,0,0,0,0,~
0)';
    'CD_VCCP'<3>:'(0,0,0,0,0,0,0,0,0,0,0,0,0,0,0,0,0,0,0,0,BU14,0,0,0,0,0,0,0,0,~
0)';
    'CD_VCCP'<2>:'(0,0,0,0,0,0,0,0,0,0,0,0,0,0,0,0,0,0,0,0,BV11,0,0,0,0,0,0,0,0,~
0)';
    'CD_VCCP'<1>:'(0,0,0,0,0,0,0,0,0,0,0,0,0,0,0,0,0,0,0,0,BV13,0,0,0,0,0,0,0,0,~
0)';
    'CD_VCCP'<0>:'(0,0,0,0,0,0,0,0,0,0,0,0,0,0,0,0,0,0,0,0,BV15,0,0,0,0,0,0,0,0,~
0)';
    'CD_VCCP_SENSE'<1>:'(0,0,0,0,0,0,0,0,0,0,0,0,0,0,0,0,0,0,0,0,0,BT17,0,0,0,0,~
0,0,0,0)';
    'CD_VCCP_SENSE'<0>:'(0,0,0,0,0,0,0,0,0,0,0,0,0,0,0,0,0,0,0,0,0,BU16,0,0,0,0,~
0,0,0,0)';
    'CD_VCC_CORE'<12>:'(0,0,0,0,0,0,0,0,0,0,0,0,0,0,0,0,0,0,0,0,BD13,0,0,0,0,0,0~
,0,0,0)';
    'CD_VCC_CORE'<11>:'(0,0,0,0,0,0,0,0,0,0,0,0,0,0,0,0,0,0,0,0,BE12,0,0,0,0,0,0~
,0,0,0)';
    'CD_VCC_CORE'<10>:'(0,0,0,0,0,0,0,0,0,0,0,0,0,0,0,0,0,0,0,0,BE14,0,0,0,0,0,0~
,0,0,0)';
    'CD_VCC_CORE'<9>:'(0,0,0,0,0,0,0,0,0,0,0,0,0,0,0,0,0,0,0,0,BF11,0,0,0,0,0,0,~
0,0,0)';
    'CD_VCC_CORE'<8>:'(0,0,0,0,0,0,0,0,0,0,0,0,0,0,0,0,0,0,0,0,BF13,0,0,0,0,0,0,~
0,0,0)';
    'CD_VCC_CORE'<7>:'(0,0,0,0,0,0,0,0,0,0,0,0,0,0,0,0,0,0,0,0,BG12,0,0,0,0,0,0,~
0,0,0)';
    'CD_VCC_CORE'<6>:'(0,0,0,0,0,0,0,0,0,0,0,0,0,0,0,0,0,0,0,0,BG14,0,0,0,0,0,0,~
0,0,0)';
    'CD_VCC_CORE'<5>:'(0,0,0,0,0,0,0,0,0,0,0,0,0,0,0,0,0,0,0,0,BH13,0,0,0,0,0,0,~
0,0,0)';
    'CD_VCC_CORE'<4>:'(0,0,0,0,0,0,0,0,0,0,0,0,0,0,0,0,0,0,0,0,BJ12,0,0,0,0,0,0,~
0,0,0)';
    'CD_VCC_CORE'<3>:'(0,0,0,0,0,0,0,0,0,0,0,0,0,0,0,0,0,0,0,0,BJ14,0,0,0,0,0,0,~
0,0,0)';
    'CD_VCC_CORE'<2>:'(0,0,0,0,0,0,0,0,0,0,0,0,0,0,0,0,0,0,0,0,BK13,0,0,0,0,0,0,~
0,0,0)';
    'CD_VCC_CORE'<1>:'(0,0,0,0,0,0,0,0,0,0,0,0,0,0,0,0,0,0,0,0,BK15,0,0,0,0,0,0,~
0,0,0)';
    'CD_VCC_CORE'<0>:'(0,0,0,0,0,0,0,0,0,0,0,0,0,0,0,0,0,0,0,0,BL14,0,0,0,0,0,0,~
0,0,0)';
    'CD_VCC_CORE_SENSE':'(0,0,0,0,0,0,0,0,0,0,0,0,0,0,0,0,0,0,0,0,0,BN16,0,0,0,0~
,0,0,0,0)';$S;
    'CD_VPP'<3>:'(0,0,0,0,0,0,0,0,0,0,0,0,0,0,0,0,0,0,0,0,A8,0,0,0,0,0,0,0,0,0)';
    'CD_VPP'<2>:'(0,0,0,0,0,0,0,0,0,0,0,0,0,0,0,0,0,0,0,0,A10,0,0,0,0,0,0,0,0,0)~
';
    'CD_VPP'<1>:'(0,0,0,0,0,0,0,0,0,0,0,0,0,0,0,0,0,0,0,0,A12,0,0,0,0,0,0,0,0,0)~
';
    'CD_VPP'<0>:'(0,0,0,0,0,0,0,0,0,0,0,0,0,0,0,0,0,0,0,0,B11,0,0,0,0,0,0,0,0,0)~
';
    'CD_VSS_VCC_CORE_SENSE':'(0,0,0,0,0,0,0,0,0,0,0,0,0,0,0,0,0,0,0,0,0,BL16,0,0~
,0,0,0,0,0,0)';$S;
    'DDR012_DRAM_PWR_OK':'(AN30,0,0,0,0,0,0,0,0,0,0,0,0,0,0,0,0,0,0,0,0,0,0,0,0,~
0,0,0,0,0)';$S;IN;
    'DDR012_RCOMP'<2>:'(AC42,0,0,0,0,0,0,0,0,0,0,0,0,0,0,0,0,0,0,0,0,0,0,0,0,0,0~
,0,0,0)';BIDI;
    'DDR012_RCOMP'<1>:'(AB43,0,0,0,0,0,0,0,0,0,0,0,0,0,0,0,0,0,0,0,0,0,0,0,0,0,0~
,0,0,0)';BIDI;
    'DDR012_RCOMP'<0>:'(Y43,0,0,0,0,0,0,0,0,0,0,0,0,0,0,0,0,0,0,0,0,0,0,0,0,0,0,~
0,0,0)';BIDI;
    'DDR012_RESET_N':'(U64,0,0,0,0,0,0,0,0,0,0,0,0,0,0,0,0,0,0,0,0,0,0,0,0,0,0,0~
,0,0)';$S;OUT;
    'DDR012_SPDSCL':'(AJ18,0,0,0,0,0,0,0,0,0,0,0,0,0,0,0,0,0,0,0,0,0,0,0,0,0,0,0~
,0,0)';$S;BIDI;
    'DDR012_SPDSDA':'(AF17,0,0,0,0,0,0,0,0,0,0,0,0,0,0,0,0,0,0,0,0,0,0,0,0,0,0,0~
,0,0)';$S;BIDI;
    'DDR0_ACT_N':'(0,0,J60,0,0,0,0,0,0,0,0,0,0,0,0,0,0,0,0,0,0,0,0,0,0,0,0,0,0,0~
)';$S;OUT;
    'DDR0_ALERT_N':'(0,0,B61,0,0,0,0,0,0,0,0,0,0,0,0,0,0,0,0,0,0,0,0,0,0,0,0,0,0~
,0)';$S;IN;
    'DDR0_BA'<1>:'(0,0,G54,0,0,0,0,0,0,0,0,0,0,0,0,0,0,0,0,0,0,0,0,0,0,0,0,0,0,0~
)';OUT;
    'DDR0_BA'<0>:'(0,0,C52,0,0,0,0,0,0,0,0,0,0,0,0,0,0,0,0,0,0,0,0,0,0,0,0,0,0,0~
)';OUT;
    'DDR0_BG'<1>:'(0,0,F63,0,0,0,0,0,0,0,0,0,0,0,0,0,0,0,0,0,0,0,0,0,0,0,0,0,0,0~
)';OUT;
    'DDR0_BG'<0>:'(0,0,D61,0,0,0,0,0,0,0,0,0,0,0,0,0,0,0,0,0,0,0,0,0,0,0,0,0,0,0~
)';OUT;
    'DDR0_CAVREF':'(AJ64,0,0,0,0,0,0,0,0,0,0,0,0,0,0,0,0,0,0,0,0,0,0,0,0,0,0,0,0~
,0)';$S;OUT;
    'DDR0_CID'<2>:'(0,0,G46,0,0,0,0,0,0,0,0,0,0,0,0,0,0,0,0,0,0,0,0,0,0,0,0,0,0,~
0)';$S;OUT;
    'DDR0_CKE'<3>:'(0,0,D63,0,0,0,0,0,0,0,0,0,0,0,0,0,0,0,0,0,0,0,0,0,0,0,0,0,0,~
0)';OUT;
    'DDR0_CKE'<2>:'(0,0,B63,0,0,0,0,0,0,0,0,0,0,0,0,0,0,0,0,0,0,0,0,0,0,0,0,0,0,~
0)';OUT;
    'DDR0_CKE'<1>:'(0,0,C64,0,0,0,0,0,0,0,0,0,0,0,0,0,0,0,0,0,0,0,0,0,0,0,0,0,0,~
0)';OUT;
    'DDR0_CKE'<0>:'(0,0,C62,0,0,0,0,0,0,0,0,0,0,0,0,0,0,0,0,0,0,0,0,0,0,0,0,0,0,~
0)';OUT;
    'DDR0_CLK_DN'<3>:'(0,0,C56,0,0,0,0,0,0,0,0,0,0,0,0,0,0,0,0,0,0,0,0,0,0,0,0,0~
,0,0)';OUT;
    'DDR0_CLK_DN'<2>:'(0,0,J56,0,0,0,0,0,0,0,0,0,0,0,0,0,0,0,0,0,0,0,0,0,0,0,0,0~
,0,0)';OUT;
    'DDR0_CLK_DN'<1>:'(0,0,C54,0,0,0,0,0,0,0,0,0,0,0,0,0,0,0,0,0,0,0,0,0,0,0,0,0~
,0,0)';OUT;
    'DDR0_CLK_DN'<0>:'(0,0,F55,0,0,0,0,0,0,0,0,0,0,0,0,0,0,0,0,0,0,0,0,0,0,0,0,0~
,0,0)';OUT;
    'DDR0_CLK_DP'<3>:'(0,0,B57,0,0,0,0,0,0,0,0,0,0,0,0,0,0,0,0,0,0,0,0,0,0,0,0,0~
,0,0)';OUT;
    'DDR0_CLK_DP'<2>:'(0,0,G56,0,0,0,0,0,0,0,0,0,0,0,0,0,0,0,0,0,0,0,0,0,0,0,0,0~
,0,0)';OUT;
    'DDR0_CLK_DP'<1>:'(0,0,B55,0,0,0,0,0,0,0,0,0,0,0,0,0,0,0,0,0,0,0,0,0,0,0,0,0~
,0,0)';OUT;
    'DDR0_CLK_DP'<0>:'(0,0,D55,0,0,0,0,0,0,0,0,0,0,0,0,0,0,0,0,0,0,0,0,0,0,0,0,0~
,0,0)';OUT;
    'DDR0_CS_N'<7>:'(0,0,K45,0,0,0,0,0,0,0,0,0,0,0,0,0,0,0,0,0,0,0,0,0,0,0,0,0,0~
,0)';OUT;
    'DDR0_CS_N'<6>:'(0,0,F45,0,0,0,0,0,0,0,0,0,0,0,0,0,0,0,0,0,0,0,0,0,0,0,0,0,0~
,0)';OUT;
    'DDR0_CS_N'<5>:'(0,0,D49,0,0,0,0,0,0,0,0,0,0,0,0,0,0,0,0,0,0,0,0,0,0,0,0,0,0~
,0)';OUT;
    'DDR0_CS_N'<4>:'(0,0,B51,0,0,0,0,0,0,0,0,0,0,0,0,0,0,0,0,0,0,0,0,0,0,0,0,0,0~
,0)';OUT;
    'DDR0_CS_N'<3>:'(0,0,F47,0,0,0,0,0,0,0,0,0,0,0,0,0,0,0,0,0,0,0,0,0,0,0,0,0,0~
,0)';OUT;
    'DDR0_CS_N'<2>:'(0,0,D47,0,0,0,0,0,0,0,0,0,0,0,0,0,0,0,0,0,0,0,0,0,0,0,0,0,0~
,0)';OUT;
    'DDR0_CS_N'<1>:'(0,0,F49,0,0,0,0,0,0,0,0,0,0,0,0,0,0,0,0,0,0,0,0,0,0,0,0,0,0~
,0)';OUT;
    'DDR0_CS_N'<0>:'(0,0,G52,0,0,0,0,0,0,0,0,0,0,0,0,0,0,0,0,0,0,0,0,0,0,0,0,0,0~
,0)';OUT;
    'DDR0_DQ'<63>:'(0,0,K23,0,0,0,0,0,0,0,0,0,0,0,0,0,0,0,0,0,0,0,0,0,0,0,0,0,0,~
0)';BIDI;
    'DDR0_DQ'<62>:'(0,0,H23,0,0,0,0,0,0,0,0,0,0,0,0,0,0,0,0,0,0,0,0,0,0,0,0,0,0,~
0)';BIDI;
    'DDR0_DQ'<61>:'(0,0,N26,0,0,0,0,0,0,0,0,0,0,0,0,0,0,0,0,0,0,0,0,0,0,0,0,0,0,~
0)';BIDI;
    'DDR0_DQ'<60>:'(0,0,L26,0,0,0,0,0,0,0,0,0,0,0,0,0,0,0,0,0,0,0,0,0,0,0,0,0,0,~
0)';BIDI;
    'DDR0_DQ'<59>:'(0,0,T23,0,0,0,0,0,0,0,0,0,0,0,0,0,0,0,0,0,0,0,0,0,0,0,0,0,0,~
0)';BIDI;
    'DDR0_DQ'<58>:'(0,0,P23,0,0,0,0,0,0,0,0,0,0,0,0,0,0,0,0,0,0,0,0,0,0,0,0,0,0,~
0)';BIDI;
    'DDR0_DQ'<57>:'(0,0,P25,0,0,0,0,0,0,0,0,0,0,0,0,0,0,0,0,0,0,0,0,0,0,0,0,0,0,~
0)';BIDI;
    'DDR0_DQ'<56>:'(0,0,K25,0,0,0,0,0,0,0,0,0,0,0,0,0,0,0,0,0,0,0,0,0,0,0,0,0,0,~
0)';BIDI;
    'DDR0_DQ'<55>:'(0,0,P29,0,0,0,0,0,0,0,0,0,0,0,0,0,0,0,0,0,0,0,0,0,0,0,0,0,0,~
0)';BIDI;
    'DDR0_DQ'<54>:'(0,0,K29,0,0,0,0,0,0,0,0,0,0,0,0,0,0,0,0,0,0,0,0,0,0,0,0,0,0,~
0)';BIDI;
    'DDR0_DQ'<53>:'(0,0,N32,0,0,0,0,0,0,0,0,0,0,0,0,0,0,0,0,0,0,0,0,0,0,0,0,0,0,~
0)';BIDI;
    'DDR0_DQ'<52>:'(0,0,L32,0,0,0,0,0,0,0,0,0,0,0,0,0,0,0,0,0,0,0,0,0,0,0,0,0,0,~
0)';BIDI;
    'DDR0_DQ'<51>:'(0,0,N28,0,0,0,0,0,0,0,0,0,0,0,0,0,0,0,0,0,0,0,0,0,0,0,0,0,0,~
0)';BIDI;
    'DDR0_DQ'<50>:'(0,0,L28,0,0,0,0,0,0,0,0,0,0,0,0,0,0,0,0,0,0,0,0,0,0,0,0,0,0,~
0)';BIDI;
    'DDR0_DQ'<49>:'(0,0,P31,0,0,0,0,0,0,0,0,0,0,0,0,0,0,0,0,0,0,0,0,0,0,0,0,0,0,~
0)';BIDI;
    'DDR0_DQ'<48>:'(0,0,K31,0,0,0,0,0,0,0,0,0,0,0,0,0,0,0,0,0,0,0,0,0,0,0,0,0,0,~
0)';BIDI;
    'DDR0_DQ'<47>:'(0,0,P35,0,0,0,0,0,0,0,0,0,0,0,0,0,0,0,0,0,0,0,0,0,0,0,0,0,0,~
0)';BIDI;
    'DDR0_DQ'<46>:'(0,0,K35,0,0,0,0,0,0,0,0,0,0,0,0,0,0,0,0,0,0,0,0,0,0,0,0,0,0,~
0)';BIDI;
    'DDR0_DQ'<45>:'(0,0,N38,0,0,0,0,0,0,0,0,0,0,0,0,0,0,0,0,0,0,0,0,0,0,0,0,0,0,~
0)';BIDI;
    'DDR0_DQ'<44>:'(0,0,L38,0,0,0,0,0,0,0,0,0,0,0,0,0,0,0,0,0,0,0,0,0,0,0,0,0,0,~
0)';BIDI;
    'DDR0_DQ'<43>:'(0,0,N34,0,0,0,0,0,0,0,0,0,0,0,0,0,0,0,0,0,0,0,0,0,0,0,0,0,0,~
0)';BIDI;
    'DDR0_DQ'<42>:'(0,0,L34,0,0,0,0,0,0,0,0,0,0,0,0,0,0,0,0,0,0,0,0,0,0,0,0,0,0,~
0)';BIDI;
    'DDR0_DQ'<41>:'(0,0,P37,0,0,0,0,0,0,0,0,0,0,0,0,0,0,0,0,0,0,0,0,0,0,0,0,0,0,~
0)';BIDI;
    'DDR0_DQ'<40>:'(0,0,K37,0,0,0,0,0,0,0,0,0,0,0,0,0,0,0,0,0,0,0,0,0,0,0,0,0,0,~
0)';BIDI;
    'DDR0_DQ'<39>:'(0,0,F39,0,0,0,0,0,0,0,0,0,0,0,0,0,0,0,0,0,0,0,0,0,0,0,0,0,0,~
0)';BIDI;
    'DDR0_DQ'<38>:'(0,0,B39,0,0,0,0,0,0,0,0,0,0,0,0,0,0,0,0,0,0,0,0,0,0,0,0,0,0,~
0)';BIDI;
    'DDR0_DQ'<37>:'(0,0,F41,0,0,0,0,0,0,0,0,0,0,0,0,0,0,0,0,0,0,0,0,0,0,0,0,0,0,~
0)';BIDI;
    'DDR0_DQ'<36>:'(0,0,E42,0,0,0,0,0,0,0,0,0,0,0,0,0,0,0,0,0,0,0,0,0,0,0,0,0,0,~
0)';BIDI;
    'DDR0_DQ'<35>:'(0,0,E38,0,0,0,0,0,0,0,0,0,0,0,0,0,0,0,0,0,0,0,0,0,0,0,0,0,0,~
0)';BIDI;
    'DDR0_DQ'<34>:'(0,0,C38,0,0,0,0,0,0,0,0,0,0,0,0,0,0,0,0,0,0,0,0,0,0,0,0,0,0,~
0)';BIDI;
    'DDR0_DQ'<33>:'(0,0,B41,0,0,0,0,0,0,0,0,0,0,0,0,0,0,0,0,0,0,0,0,0,0,0,0,0,0,~
0)';BIDI;
    'DDR0_DQ'<32>:'(0,0,C42,0,0,0,0,0,0,0,0,0,0,0,0,0,0,0,0,0,0,0,0,0,0,0,0,0,0,~
0)';BIDI;
    'DDR0_DQ'<31>:'(0,0,R74,0,0,0,0,0,0,0,0,0,0,0,0,0,0,0,0,0,0,0,0,0,0,0,0,0,0,~
0)';BIDI;
    'DDR0_DQ'<30>:'(0,0,L74,0,0,0,0,0,0,0,0,0,0,0,0,0,0,0,0,0,0,0,0,0,0,0,0,0,0,~
0)';BIDI;
    'DDR0_DQ'<29>:'(0,0,P77,0,0,0,0,0,0,0,0,0,0,0,0,0,0,0,0,0,0,0,0,0,0,0,0,0,0,~
0)';BIDI;
    'DDR0_DQ'<28>:'(0,0,M77,0,0,0,0,0,0,0,0,0,0,0,0,0,0,0,0,0,0,0,0,0,0,0,0,0,0,~
0)';BIDI;
    'DDR0_DQ'<27>:'(0,0,P73,0,0,0,0,0,0,0,0,0,0,0,0,0,0,0,0,0,0,0,0,0,0,0,0,0,0,~
0)';BIDI;
    'DDR0_DQ'<26>:'(0,0,M73,0,0,0,0,0,0,0,0,0,0,0,0,0,0,0,0,0,0,0,0,0,0,0,0,0,0,~
0)';BIDI;
    'DDR0_DQ'<25>:'(0,0,R76,0,0,0,0,0,0,0,0,0,0,0,0,0,0,0,0,0,0,0,0,0,0,0,0,0,0,~
0)';BIDI;
    'DDR0_DQ'<24>:'(0,0,L76,0,0,0,0,0,0,0,0,0,0,0,0,0,0,0,0,0,0,0,0,0,0,0,0,0,0,~
0)';BIDI;
    'DDR0_DQ'<23>:'(0,0,N80,0,0,0,0,0,0,0,0,0,0,0,0,0,0,0,0,0,0,0,0,0,0,0,0,0,0,~
0)';BIDI;
    'DDR0_DQ'<22>:'(0,0,R82,0,0,0,0,0,0,0,0,0,0,0,0,0,0,0,0,0,0,0,0,0,0,0,0,0,0,~
0)';BIDI;
    'DDR0_DQ'<21>:'(0,0,V79,0,0,0,0,0,0,0,0,0,0,0,0,0,0,0,0,0,0,0,0,0,0,0,0,0,0,~
0)';BIDI;
    'DDR0_DQ'<20>:'(0,0,W80,0,0,0,0,0,0,0,0,0,0,0,0,0,0,0,0,0,0,0,0,0,0,0,0,0,0,~
0)';BIDI;
    'DDR0_DQ'<19>:'(0,0,M81,0,0,0,0,0,0,0,0,0,0,0,0,0,0,0,0,0,0,0,0,0,0,0,0,0,0,~
0)';BIDI;
    'DDR0_DQ'<18>:'(0,0,N82,0,0,0,0,0,0,0,0,0,0,0,0,0,0,0,0,0,0,0,0,0,0,0,0,0,0,~
0)';BIDI;
    'DDR0_DQ'<17>:'(0,0,T79,0,0,0,0,0,0,0,0,0,0,0,0,0,0,0,0,0,0,0,0,0,0,0,0,0,0,~
0)';BIDI;
    'DDR0_DQ'<16>:'(0,0,V81,0,0,0,0,0,0,0,0,0,0,0,0,0,0,0,0,0,0,0,0,0,0,0,0,0,0,~
0)';BIDI;
    'DDR0_DQ'<15>:'(0,0,N84,0,0,0,0,0,0,0,0,0,0,0,0,0,0,0,0,0,0,0,0,0,0,0,0,0,0,~
0)';BIDI;
    'DDR0_DQ'<14>:'(0,0,N86,0,0,0,0,0,0,0,0,0,0,0,0,0,0,0,0,0,0,0,0,0,0,0,0,0,0,~
0)';BIDI;
    'DDR0_DQ'<13>:'(0,0,AA84,0,0,0,0,0,0,0,0,0,0,0,0,0,0,0,0,0,0,0,0,0,0,0,0,0,0~
,0)';BIDI;
    'DDR0_DQ'<12>:'(0,0,AA86,0,0,0,0,0,0,0,0,0,0,0,0,0,0,0,0,0,0,0,0,0,0,0,0,0,0~
,0)';BIDI;
    'DDR0_DQ'<11>:'(0,0,L84,0,0,0,0,0,0,0,0,0,0,0,0,0,0,0,0,0,0,0,0,0,0,0,0,0,0,~
0)';BIDI;
    'DDR0_DQ'<10>:'(0,0,L86,0,0,0,0,0,0,0,0,0,0,0,0,0,0,0,0,0,0,0,0,0,0,0,0,0,0,~
0)';BIDI;
    'DDR0_DQ'<9>:'(0,0,W84,0,0,0,0,0,0,0,0,0,0,0,0,0,0,0,0,0,0,0,0,0,0,0,0,0,0,0~
)';BIDI;
    'DDR0_DQ'<8>:'(0,0,W86,0,0,0,0,0,0,0,0,0,0,0,0,0,0,0,0,0,0,0,0,0,0,0,0,0,0,0~
)';BIDI;
    'DDR0_DQ'<7>:'(0,0,AG84,0,0,0,0,0,0,0,0,0,0,0,0,0,0,0,0,0,0,0,0,0,0,0,0,0,0,~
0)';BIDI;
    'DDR0_DQ'<6>:'(0,0,AG86,0,0,0,0,0,0,0,0,0,0,0,0,0,0,0,0,0,0,0,0,0,0,0,0,0,0,~
0)';BIDI;
    'DDR0_DQ'<5>:'(0,0,AR84,0,0,0,0,0,0,0,0,0,0,0,0,0,0,0,0,0,0,0,0,0,0,0,0,0,0,~
0)';BIDI;
    'DDR0_DQ'<4>:'(0,0,AR86,0,0,0,0,0,0,0,0,0,0,0,0,0,0,0,0,0,0,0,0,0,0,0,0,0,0,~
0)';BIDI;
    'DDR0_DQ'<3>:'(0,0,AE84,0,0,0,0,0,0,0,0,0,0,0,0,0,0,0,0,0,0,0,0,0,0,0,0,0,0,~
0)';BIDI;
    'DDR0_DQ'<2>:'(0,0,AE86,0,0,0,0,0,0,0,0,0,0,0,0,0,0,0,0,0,0,0,0,0,0,0,0,0,0,~
0)';BIDI;
    'DDR0_DQ'<1>:'(0,0,AN84,0,0,0,0,0,0,0,0,0,0,0,0,0,0,0,0,0,0,0,0,0,0,0,0,0,0,~
0)';BIDI;
    'DDR0_DQ'<0>:'(0,0,AN86,0,0,0,0,0,0,0,0,0,0,0,0,0,0,0,0,0,0,0,0,0,0,0,0,0,0,~
0)';BIDI;
    'DDR0_DQS_DN'<17>:'(0,0,AB67,0,0,0,0,0,0,0,0,0,0,0,0,0,0,0,0,0,0,0,0,0,0,0,0~
,0,0,0)';BIDI;
    'DDR0_DQS_DN'<16>:'(0,0,J24,0,0,0,0,0,0,0,0,0,0,0,0,0,0,0,0,0,0,0,0,0,0,0,0,~
0,0,0)';BIDI;
    'DDR0_DQS_DN'<15>:'(0,0,J30,0,0,0,0,0,0,0,0,0,0,0,0,0,0,0,0,0,0,0,0,0,0,0,0,~
0,0,0)';BIDI;
    'DDR0_DQS_DN'<14>:'(0,0,J36,0,0,0,0,0,0,0,0,0,0,0,0,0,0,0,0,0,0,0,0,0,0,0,0,~
0,0,0)';BIDI;
    'DDR0_DQS_DN'<13>:'(0,0,A40,0,0,0,0,0,0,0,0,0,0,0,0,0,0,0,0,0,0,0,0,0,0,0,0,~
0,0,0)';BIDI;
    'DDR0_DQS_DN'<12>:'(0,0,K75,0,0,0,0,0,0,0,0,0,0,0,0,0,0,0,0,0,0,0,0,0,0,0,0,~
0,0,0)';BIDI;
    'DDR0_DQS_DN'<11>:'(0,0,U82,0,0,0,0,0,0,0,0,0,0,0,0,0,0,0,0,0,0,0,0,0,0,0,0,~
0,0,0)';BIDI;
    'DDR0_DQS_DN'<10>:'(0,0,U84,0,0,0,0,0,0,0,0,0,0,0,0,0,0,0,0,0,0,0,0,0,0,0,0,~
0,0,0)';BIDI;
    'DDR0_DQS_DN'<9>:'(0,0,AL84,0,0,0,0,0,0,0,0,0,0,0,0,0,0,0,0,0,0,0,0,0,0,0,0,~
0,0,0)';BIDI;
    'DDR0_DQS_DN'<8>:'(0,0,AH67,0,0,0,0,0,0,0,0,0,0,0,0,0,0,0,0,0,0,0,0,0,0,0,0,~
0,0,0)';BIDI;
    'DDR0_DQS_DN'<7>:'(0,0,N24,0,0,0,0,0,0,0,0,0,0,0,0,0,0,0,0,0,0,0,0,0,0,0,0,0~
,0,0)';BIDI;
    'DDR0_DQS_DN'<6>:'(0,0,R30,0,0,0,0,0,0,0,0,0,0,0,0,0,0,0,0,0,0,0,0,0,0,0,0,0~
,0,0)';BIDI;
    'DDR0_DQS_DN'<5>:'(0,0,R36,0,0,0,0,0,0,0,0,0,0,0,0,0,0,0,0,0,0,0,0,0,0,0,0,0~
,0,0)';BIDI;
    'DDR0_DQS_DN'<4>:'(0,0,G40,0,0,0,0,0,0,0,0,0,0,0,0,0,0,0,0,0,0,0,0,0,0,0,0,0~
,0,0)';BIDI;
    'DDR0_DQS_DN'<3>:'(0,0,T75,0,0,0,0,0,0,0,0,0,0,0,0,0,0,0,0,0,0,0,0,0,0,0,0,0~
,0,0)';BIDI;
    'DDR0_DQS_DN'<2>:'(0,0,P79,0,0,0,0,0,0,0,0,0,0,0,0,0,0,0,0,0,0,0,0,0,0,0,0,0~
,0,0)';BIDI;
    'DDR0_DQS_DN'<1>:'(0,0,R84,0,0,0,0,0,0,0,0,0,0,0,0,0,0,0,0,0,0,0,0,0,0,0,0,0~
,0,0)';BIDI;
    'DDR0_DQS_DN'<0>:'(0,0,AJ84,0,0,0,0,0,0,0,0,0,0,0,0,0,0,0,0,0,0,0,0,0,0,0,0,~
0,0,0)';BIDI;
    'DDR0_DQS_DP'<17>:'(0,0,AD67,0,0,0,0,0,0,0,0,0,0,0,0,0,0,0,0,0,0,0,0,0,0,0,0~
,0,0,0)';BIDI;
    'DDR0_DQS_DP'<16>:'(0,0,L24,0,0,0,0,0,0,0,0,0,0,0,0,0,0,0,0,0,0,0,0,0,0,0,0,~
0,0,0)';BIDI;
    'DDR0_DQS_DP'<15>:'(0,0,L30,0,0,0,0,0,0,0,0,0,0,0,0,0,0,0,0,0,0,0,0,0,0,0,0,~
0,0,0)';BIDI;
    'DDR0_DQS_DP'<14>:'(0,0,L36,0,0,0,0,0,0,0,0,0,0,0,0,0,0,0,0,0,0,0,0,0,0,0,0,~
0,0,0)';BIDI;
    'DDR0_DQS_DP'<13>:'(0,0,C40,0,0,0,0,0,0,0,0,0,0,0,0,0,0,0,0,0,0,0,0,0,0,0,0,~
0,0,0)';BIDI;
    'DDR0_DQS_DP'<12>:'(0,0,M75,0,0,0,0,0,0,0,0,0,0,0,0,0,0,0,0,0,0,0,0,0,0,0,0,~
0,0,0)';BIDI;
    'DDR0_DQS_DP'<11>:'(0,0,T81,0,0,0,0,0,0,0,0,0,0,0,0,0,0,0,0,0,0,0,0,0,0,0,0,~
0,0,0)';BIDI;
    'DDR0_DQS_DP'<10>:'(0,0,V85,0,0,0,0,0,0,0,0,0,0,0,0,0,0,0,0,0,0,0,0,0,0,0,0,~
0,0,0)';BIDI;
    'DDR0_DQS_DP'<9>:'(0,0,AM85,0,0,0,0,0,0,0,0,0,0,0,0,0,0,0,0,0,0,0,0,0,0,0,0,~
0,0,0)';BIDI;
    'DDR0_DQS_DP'<8>:'(0,0,AF67,0,0,0,0,0,0,0,0,0,0,0,0,0,0,0,0,0,0,0,0,0,0,0,0,~
0,0,0)';BIDI;
    'DDR0_DQS_DP'<7>:'(0,0,R24,0,0,0,0,0,0,0,0,0,0,0,0,0,0,0,0,0,0,0,0,0,0,0,0,0~
,0,0)';BIDI;
    'DDR0_DQS_DP'<6>:'(0,0,N30,0,0,0,0,0,0,0,0,0,0,0,0,0,0,0,0,0,0,0,0,0,0,0,0,0~
,0,0)';BIDI;
    'DDR0_DQS_DP'<5>:'(0,0,N36,0,0,0,0,0,0,0,0,0,0,0,0,0,0,0,0,0,0,0,0,0,0,0,0,0~
,0,0)';BIDI;
    'DDR0_DQS_DP'<4>:'(0,0,E40,0,0,0,0,0,0,0,0,0,0,0,0,0,0,0,0,0,0,0,0,0,0,0,0,0~
,0,0)';BIDI;
    'DDR0_DQS_DP'<3>:'(0,0,P75,0,0,0,0,0,0,0,0,0,0,0,0,0,0,0,0,0,0,0,0,0,0,0,0,0~
,0,0)';BIDI;
    'DDR0_DQS_DP'<2>:'(0,0,R80,0,0,0,0,0,0,0,0,0,0,0,0,0,0,0,0,0,0,0,0,0,0,0,0,0~
,0,0)';BIDI;
    'DDR0_DQS_DP'<1>:'(0,0,P85,0,0,0,0,0,0,0,0,0,0,0,0,0,0,0,0,0,0,0,0,0,0,0,0,0~
,0,0)';BIDI;
    'DDR0_DQS_DP'<0>:'(0,0,AH85,0,0,0,0,0,0,0,0,0,0,0,0,0,0,0,0,0,0,0,0,0,0,0,0,~
0,0,0)';BIDI;
    'DDR0_ECC'<7>:'(0,0,AG66,0,0,0,0,0,0,0,0,0,0,0,0,0,0,0,0,0,0,0,0,0,0,0,0,0,0~
,0)';BIDI;
    'DDR0_ECC'<6>:'(0,0,AC66,0,0,0,0,0,0,0,0,0,0,0,0,0,0,0,0,0,0,0,0,0,0,0,0,0,0~
,0)';BIDI;
    'DDR0_ECC'<5>:'(0,0,AF69,0,0,0,0,0,0,0,0,0,0,0,0,0,0,0,0,0,0,0,0,0,0,0,0,0,0~
,0)';BIDI;
    'DDR0_ECC'<4>:'(0,0,AD69,0,0,0,0,0,0,0,0,0,0,0,0,0,0,0,0,0,0,0,0,0,0,0,0,0,0~
,0)';BIDI;
    'DDR0_ECC'<3>:'(0,0,AF65,0,0,0,0,0,0,0,0,0,0,0,0,0,0,0,0,0,0,0,0,0,0,0,0,0,0~
,0)';BIDI;
    'DDR0_ECC'<2>:'(0,0,AD65,0,0,0,0,0,0,0,0,0,0,0,0,0,0,0,0,0,0,0,0,0,0,0,0,0,0~
,0)';BIDI;
    'DDR0_ECC'<1>:'(0,0,AG68,0,0,0,0,0,0,0,0,0,0,0,0,0,0,0,0,0,0,0,0,0,0,0,0,0,0~
,0)';BIDI;
    'DDR0_ECC'<0>:'(0,0,AC68,0,0,0,0,0,0,0,0,0,0,0,0,0,0,0,0,0,0,0,0,0,0,0,0,0,0~
,0)';BIDI;
    'DDR0_MA'<17>:'(0,0,K47,0,0,0,0,0,0,0,0,0,0,0,0,0,0,0,0,0,0,0,0,0,0,0,0,0,0,~
0)';OUT;
    'DDR0_MA'<16>:'(0,0,D51,0,0,0,0,0,0,0,0,0,0,0,0,0,0,0,0,0,0,0,0,0,0,0,0,0,0,~
0)';OUT;
    'DDR0_MA'<15>:'(0,0,K49,0,0,0,0,0,0,0,0,0,0,0,0,0,0,0,0,0,0,0,0,0,0,0,0,0,0,~
0)';OUT;
    'DDR0_MA'<14>:'(0,0,F51,0,0,0,0,0,0,0,0,0,0,0,0,0,0,0,0,0,0,0,0,0,0,0,0,0,0,~
0)';OUT;
    'DDR0_MA'<13>:'(0,0,J48,0,0,0,0,0,0,0,0,0,0,0,0,0,0,0,0,0,0,0,0,0,0,0,0,0,0,~
0)';OUT;
    'DDR0_MA'<12>:'(0,0,J64,0,0,0,0,0,0,0,0,0,0,0,0,0,0,0,0,0,0,0,0,0,0,0,0,0,0,~
0)';OUT;
    'DDR0_MA'<11>:'(0,0,G62,0,0,0,0,0,0,0,0,0,0,0,0,0,0,0,0,0,0,0,0,0,0,0,0,0,0,~
0)';OUT;
    'DDR0_MA'<10>:'(0,0,J54,0,0,0,0,0,0,0,0,0,0,0,0,0,0,0,0,0,0,0,0,0,0,0,0,0,0,~
0)';OUT;
    'DDR0_MA'<9>:'(0,0,F61,0,0,0,0,0,0,0,0,0,0,0,0,0,0,0,0,0,0,0,0,0,0,0,0,0,0,0~
)';OUT;
    'DDR0_MA'<8>:'(0,0,C60,0,0,0,0,0,0,0,0,0,0,0,0,0,0,0,0,0,0,0,0,0,0,0,0,0,0,0~
)';OUT;
    'DDR0_MA'<7>:'(0,0,G60,0,0,0,0,0,0,0,0,0,0,0,0,0,0,0,0,0,0,0,0,0,0,0,0,0,0,0~
)';OUT;
    'DDR0_MA'<6>:'(0,0,D59,0,0,0,0,0,0,0,0,0,0,0,0,0,0,0,0,0,0,0,0,0,0,0,0,0,0,0~
)';OUT;
    'DDR0_MA'<5>:'(0,0,F59,0,0,0,0,0,0,0,0,0,0,0,0,0,0,0,0,0,0,0,0,0,0,0,0,0,0,0~
)';OUT;
    'DDR0_MA'<4>:'(0,0,G58,0,0,0,0,0,0,0,0,0,0,0,0,0,0,0,0,0,0,0,0,0,0,0,0,0,0,0~
)';OUT;
    'DDR0_MA'<3>:'(0,0,C58,0,0,0,0,0,0,0,0,0,0,0,0,0,0,0,0,0,0,0,0,0,0,0,0,0,0,0~
)';OUT;
    'DDR0_MA'<2>:'(0,0,D57,0,0,0,0,0,0,0,0,0,0,0,0,0,0,0,0,0,0,0,0,0,0,0,0,0,0,0~
)';OUT;
    'DDR0_MA'<1>:'(0,0,F57,0,0,0,0,0,0,0,0,0,0,0,0,0,0,0,0,0,0,0,0,0,0,0,0,0,0,0~
)';OUT;
    'DDR0_MA'<0>:'(0,0,F53,0,0,0,0,0,0,0,0,0,0,0,0,0,0,0,0,0,0,0,0,0,0,0,0,0,0,0~
)';OUT;
    'DDR0_ODT'<3>:'(0,0,G48,0,0,0,0,0,0,0,0,0,0,0,0,0,0,0,0,0,0,0,0,0,0,0,0,0,0,~
0)';OUT;
    'DDR0_ODT'<2>:'(0,0,G50,0,0,0,0,0,0,0,0,0,0,0,0,0,0,0,0,0,0,0,0,0,0,0,0,0,0,~
0)';OUT;
    'DDR0_ODT'<1>:'(0,0,C48,0,0,0,0,0,0,0,0,0,0,0,0,0,0,0,0,0,0,0,0,0,0,0,0,0,0,~
0)';OUT;
    'DDR0_ODT'<0>:'(0,0,C50,0,0,0,0,0,0,0,0,0,0,0,0,0,0,0,0,0,0,0,0,0,0,0,0,0,0,~
0)';OUT;
    'DDR0_PAR':'(0,0,D53,0,0,0,0,0,0,0,0,0,0,0,0,0,0,0,0,0,0,0,0,0,0,0,0,0,0,0)';$S;OUT;
    'DDR1_ACT_N':'(0,0,0,T63,0,0,0,0,0,0,0,0,0,0,0,0,0,0,0,0,0,0,0,0,0,0,0,0,0,0~
)';$S;OUT;
    'DDR1_ALERT_N':'(0,0,0,W62,0,0,0,0,0,0,0,0,0,0,0,0,0,0,0,0,0,0,0,0,0,0,0,0,0~
,0)';$S;IN;
    'DDR1_BA'<1>:'(0,0,0,K55,0,0,0,0,0,0,0,0,0,0,0,0,0,0,0,0,0,0,0,0,0,0,0,0,0,0~
)';OUT;
    'DDR1_BA'<0>:'(0,0,0,T53,0,0,0,0,0,0,0,0,0,0,0,0,0,0,0,0,0,0,0,0,0,0,0,0,0,0~
)';OUT;
    'DDR1_BG'<1>:'(0,0,0,N60,0,0,0,0,0,0,0,0,0,0,0,0,0,0,0,0,0,0,0,0,0,0,0,0,0,0~
)';OUT;
    'DDR1_BG'<0>:'(0,0,0,M61,0,0,0,0,0,0,0,0,0,0,0,0,0,0,0,0,0,0,0,0,0,0,0,0,0,0~
)';OUT;
    'DDR1_CAVREF':'(AK63,0,0,0,0,0,0,0,0,0,0,0,0,0,0,0,0,0,0,0,0,0,0,0,0,0,0,0,0~
,0)';$S;OUT;
    'DDR1_CID'<2>:'(0,0,0,M47,0,0,0,0,0,0,0,0,0,0,0,0,0,0,0,0,0,0,0,0,0,0,0,0,0,~
0)';$S;OUT;
    'DDR1_CKE'<3>:'(0,0,0,L64,0,0,0,0,0,0,0,0,0,0,0,0,0,0,0,0,0,0,0,0,0,0,0,0,0,~
0)';OUT;
    'DDR1_CKE'<2>:'(0,0,0,K63,0,0,0,0,0,0,0,0,0,0,0,0,0,0,0,0,0,0,0,0,0,0,0,0,0,~
0)';OUT;
    'DDR1_CKE'<1>:'(0,0,0,R64,0,0,0,0,0,0,0,0,0,0,0,0,0,0,0,0,0,0,0,0,0,0,0,0,0,~
0)';OUT;
    'DDR1_CKE'<0>:'(0,0,0,N62,0,0,0,0,0,0,0,0,0,0,0,0,0,0,0,0,0,0,0,0,0,0,0,0,0,~
0)';OUT;
    'DDR1_CLK_DN'<3>:'(0,0,0,R56,0,0,0,0,0,0,0,0,0,0,0,0,0,0,0,0,0,0,0,0,0,0,0,0~
,0,0)';OUT;
    'DDR1_CLK_DN'<2>:'(0,0,0,N56,0,0,0,0,0,0,0,0,0,0,0,0,0,0,0,0,0,0,0,0,0,0,0,0~
,0,0)';OUT;
    'DDR1_CLK_DN'<1>:'(0,0,0,R54,0,0,0,0,0,0,0,0,0,0,0,0,0,0,0,0,0,0,0,0,0,0,0,0~
,0,0)';OUT;
    'DDR1_CLK_DN'<0>:'(0,0,0,M53,0,0,0,0,0,0,0,0,0,0,0,0,0,0,0,0,0,0,0,0,0,0,0,0~
,0,0)';OUT;
    'DDR1_CLK_DP'<3>:'(0,0,0,T57,0,0,0,0,0,0,0,0,0,0,0,0,0,0,0,0,0,0,0,0,0,0,0,0~
,0,0)';OUT;
    'DDR1_CLK_DP'<2>:'(0,0,0,M57,0,0,0,0,0,0,0,0,0,0,0,0,0,0,0,0,0,0,0,0,0,0,0,0~
,0,0)';OUT;
    'DDR1_CLK_DP'<1>:'(0,0,0,T55,0,0,0,0,0,0,0,0,0,0,0,0,0,0,0,0,0,0,0,0,0,0,0,0~
,0,0)';OUT;
    'DDR1_CLK_DP'<0>:'(0,0,0,N54,0,0,0,0,0,0,0,0,0,0,0,0,0,0,0,0,0,0,0,0,0,0,0,0~
,0,0)';OUT;
    'DDR1_CS_N'<7>:'(0,0,0,R46,0,0,0,0,0,0,0,0,0,0,0,0,0,0,0,0,0,0,0,0,0,0,0,0,0~
,0)';OUT;
    'DDR1_CS_N'<6>:'(0,0,0,M45,0,0,0,0,0,0,0,0,0,0,0,0,0,0,0,0,0,0,0,0,0,0,0,0,0~
,0)';OUT;
    'DDR1_CS_N'<5>:'(0,0,0,T49,0,0,0,0,0,0,0,0,0,0,0,0,0,0,0,0,0,0,0,0,0,0,0,0,0~
,0)';OUT;
    'DDR1_CS_N'<4>:'(0,0,0,J50,0,0,0,0,0,0,0,0,0,0,0,0,0,0,0,0,0,0,0,0,0,0,0,0,0~
,0)';OUT;
    'DDR1_CS_N'<3>:'(0,0,0,V47,0,0,0,0,0,0,0,0,0,0,0,0,0,0,0,0,0,0,0,0,0,0,0,0,0~
,0)';OUT;
    'DDR1_CS_N'<2>:'(0,0,0,N46,0,0,0,0,0,0,0,0,0,0,0,0,0,0,0,0,0,0,0,0,0,0,0,0,0~
,0)';OUT;
    'DDR1_CS_N'<1>:'(0,0,0,R50,0,0,0,0,0,0,0,0,0,0,0,0,0,0,0,0,0,0,0,0,0,0,0,0,0~
,0)';OUT;
    'DDR1_CS_N'<0>:'(0,0,0,K51,0,0,0,0,0,0,0,0,0,0,0,0,0,0,0,0,0,0,0,0,0,0,0,0,0~
,0)';OUT;
    'DDR1_DQ'<63>:'(0,0,0,AA26,0,0,0,0,0,0,0,0,0,0,0,0,0,0,0,0,0,0,0,0,0,0,0,0,0~
,0)';BIDI;
    'DDR1_DQ'<62>:'(0,0,0,U26,0,0,0,0,0,0,0,0,0,0,0,0,0,0,0,0,0,0,0,0,0,0,0,0,0,~
0)';BIDI;
    'DDR1_DQ'<61>:'(0,0,0,Y29,0,0,0,0,0,0,0,0,0,0,0,0,0,0,0,0,0,0,0,0,0,0,0,0,0,~
0)';BIDI;
    'DDR1_DQ'<60>:'(0,0,0,V29,0,0,0,0,0,0,0,0,0,0,0,0,0,0,0,0,0,0,0,0,0,0,0,0,0,~
0)';BIDI;
    'DDR1_DQ'<59>:'(0,0,0,Y25,0,0,0,0,0,0,0,0,0,0,0,0,0,0,0,0,0,0,0,0,0,0,0,0,0,~
0)';BIDI;
    'DDR1_DQ'<58>:'(0,0,0,V25,0,0,0,0,0,0,0,0,0,0,0,0,0,0,0,0,0,0,0,0,0,0,0,0,0,~
0)';BIDI;
    'DDR1_DQ'<57>:'(0,0,0,AA28,0,0,0,0,0,0,0,0,0,0,0,0,0,0,0,0,0,0,0,0,0,0,0,0,0~
,0)';BIDI;
    'DDR1_DQ'<56>:'(0,0,0,U28,0,0,0,0,0,0,0,0,0,0,0,0,0,0,0,0,0,0,0,0,0,0,0,0,0,~
0)';BIDI;
    'DDR1_DQ'<55>:'(0,0,0,F27,0,0,0,0,0,0,0,0,0,0,0,0,0,0,0,0,0,0,0,0,0,0,0,0,0,~
0)';BIDI;
    'DDR1_DQ'<54>:'(0,0,0,B27,0,0,0,0,0,0,0,0,0,0,0,0,0,0,0,0,0,0,0,0,0,0,0,0,0,~
0)';BIDI;
    'DDR1_DQ'<53>:'(0,0,0,F29,0,0,0,0,0,0,0,0,0,0,0,0,0,0,0,0,0,0,0,0,0,0,0,0,0,~
0)';BIDI;
    'DDR1_DQ'<52>:'(0,0,0,E30,0,0,0,0,0,0,0,0,0,0,0,0,0,0,0,0,0,0,0,0,0,0,0,0,0,~
0)';BIDI;
    'DDR1_DQ'<51>:'(0,0,0,E26,0,0,0,0,0,0,0,0,0,0,0,0,0,0,0,0,0,0,0,0,0,0,0,0,0,~
0)';BIDI;
    'DDR1_DQ'<50>:'(0,0,0,C26,0,0,0,0,0,0,0,0,0,0,0,0,0,0,0,0,0,0,0,0,0,0,0,0,0,~
0)';BIDI;
    'DDR1_DQ'<49>:'(0,0,0,B29,0,0,0,0,0,0,0,0,0,0,0,0,0,0,0,0,0,0,0,0,0,0,0,0,0,~
0)';BIDI;
    'DDR1_DQ'<48>:'(0,0,0,C30,0,0,0,0,0,0,0,0,0,0,0,0,0,0,0,0,0,0,0,0,0,0,0,0,0,~
0)';BIDI;
    'DDR1_DQ'<47>:'(0,0,0,F33,0,0,0,0,0,0,0,0,0,0,0,0,0,0,0,0,0,0,0,0,0,0,0,0,0,~
0)';BIDI;
    'DDR1_DQ'<46>:'(0,0,0,B33,0,0,0,0,0,0,0,0,0,0,0,0,0,0,0,0,0,0,0,0,0,0,0,0,0,~
0)';BIDI;
    'DDR1_DQ'<45>:'(0,0,0,F35,0,0,0,0,0,0,0,0,0,0,0,0,0,0,0,0,0,0,0,0,0,0,0,0,0,~
0)';BIDI;
    'DDR1_DQ'<44>:'(0,0,0,E36,0,0,0,0,0,0,0,0,0,0,0,0,0,0,0,0,0,0,0,0,0,0,0,0,0,~
0)';BIDI;
    'DDR1_DQ'<43>:'(0,0,0,E32,0,0,0,0,0,0,0,0,0,0,0,0,0,0,0,0,0,0,0,0,0,0,0,0,0,~
0)';BIDI;
    'DDR1_DQ'<42>:'(0,0,0,C32,0,0,0,0,0,0,0,0,0,0,0,0,0,0,0,0,0,0,0,0,0,0,0,0,0,~
0)';BIDI;
    'DDR1_DQ'<41>:'(0,0,0,B35,0,0,0,0,0,0,0,0,0,0,0,0,0,0,0,0,0,0,0,0,0,0,0,0,0,~
0)';BIDI;
    'DDR1_DQ'<40>:'(0,0,0,C36,0,0,0,0,0,0,0,0,0,0,0,0,0,0,0,0,0,0,0,0,0,0,0,0,0,~
0)';BIDI;
    'DDR1_DQ'<39>:'(0,0,0,P41,0,0,0,0,0,0,0,0,0,0,0,0,0,0,0,0,0,0,0,0,0,0,0,0,0,~
0)';BIDI;
    'DDR1_DQ'<38>:'(0,0,0,K41,0,0,0,0,0,0,0,0,0,0,0,0,0,0,0,0,0,0,0,0,0,0,0,0,0,~
0)';BIDI;
    'DDR1_DQ'<37>:'(0,0,0,T43,0,0,0,0,0,0,0,0,0,0,0,0,0,0,0,0,0,0,0,0,0,0,0,0,0,~
0)';BIDI;
    'DDR1_DQ'<36>:'(0,0,0,P43,0,0,0,0,0,0,0,0,0,0,0,0,0,0,0,0,0,0,0,0,0,0,0,0,0,~
0)';BIDI;
    'DDR1_DQ'<35>:'(0,0,0,N40,0,0,0,0,0,0,0,0,0,0,0,0,0,0,0,0,0,0,0,0,0,0,0,0,0,~
0)';BIDI;
    'DDR1_DQ'<34>:'(0,0,0,L40,0,0,0,0,0,0,0,0,0,0,0,0,0,0,0,0,0,0,0,0,0,0,0,0,0,~
0)';BIDI;
    'DDR1_DQ'<33>:'(0,0,0,H43,0,0,0,0,0,0,0,0,0,0,0,0,0,0,0,0,0,0,0,0,0,0,0,0,0,~
0)';BIDI;
    'DDR1_DQ'<32>:'(0,0,0,K43,0,0,0,0,0,0,0,0,0,0,0,0,0,0,0,0,0,0,0,0,0,0,0,0,0,~
0)';BIDI;
    'DDR1_DQ'<31>:'(0,0,0,G72,0,0,0,0,0,0,0,0,0,0,0,0,0,0,0,0,0,0,0,0,0,0,0,0,0,~
0)';BIDI;
    'DDR1_DQ'<30>:'(0,0,0,C72,0,0,0,0,0,0,0,0,0,0,0,0,0,0,0,0,0,0,0,0,0,0,0,0,0,~
0)';BIDI;
    'DDR1_DQ'<29>:'(0,0,0,G74,0,0,0,0,0,0,0,0,0,0,0,0,0,0,0,0,0,0,0,0,0,0,0,0,0,~
0)';BIDI;
    'DDR1_DQ'<28>:'(0,0,0,F75,0,0,0,0,0,0,0,0,0,0,0,0,0,0,0,0,0,0,0,0,0,0,0,0,0,~
0)';BIDI;
    'DDR1_DQ'<27>:'(0,0,0,F71,0,0,0,0,0,0,0,0,0,0,0,0,0,0,0,0,0,0,0,0,0,0,0,0,0,~
0)';BIDI;
    'DDR1_DQ'<26>:'(0,0,0,D71,0,0,0,0,0,0,0,0,0,0,0,0,0,0,0,0,0,0,0,0,0,0,0,0,0,~
0)';BIDI;
    'DDR1_DQ'<25>:'(0,0,0,C74,0,0,0,0,0,0,0,0,0,0,0,0,0,0,0,0,0,0,0,0,0,0,0,0,0,~
0)';BIDI;
    'DDR1_DQ'<24>:'(0,0,0,D75,0,0,0,0,0,0,0,0,0,0,0,0,0,0,0,0,0,0,0,0,0,0,0,0,0,~
0)';BIDI;
    'DDR1_DQ'<23>:'(0,0,0,J78,0,0,0,0,0,0,0,0,0,0,0,0,0,0,0,0,0,0,0,0,0,0,0,0,0,~
0)';BIDI;
    'DDR1_DQ'<22>:'(0,0,0,E78,0,0,0,0,0,0,0,0,0,0,0,0,0,0,0,0,0,0,0,0,0,0,0,0,0,~
0)';BIDI;
    'DDR1_DQ'<21>:'(0,0,0,H81,0,0,0,0,0,0,0,0,0,0,0,0,0,0,0,0,0,0,0,0,0,0,0,0,0,~
0)';BIDI;
    'DDR1_DQ'<20>:'(0,0,0,F81,0,0,0,0,0,0,0,0,0,0,0,0,0,0,0,0,0,0,0,0,0,0,0,0,0,~
0)';BIDI;
    'DDR1_DQ'<19>:'(0,0,0,H77,0,0,0,0,0,0,0,0,0,0,0,0,0,0,0,0,0,0,0,0,0,0,0,0,0,~
0)';BIDI;
    'DDR1_DQ'<18>:'(0,0,0,F77,0,0,0,0,0,0,0,0,0,0,0,0,0,0,0,0,0,0,0,0,0,0,0,0,0,~
0)';BIDI;
    'DDR1_DQ'<17>:'(0,0,0,J80,0,0,0,0,0,0,0,0,0,0,0,0,0,0,0,0,0,0,0,0,0,0,0,0,0,~
0)';BIDI;
    'DDR1_DQ'<16>:'(0,0,0,E80,0,0,0,0,0,0,0,0,0,0,0,0,0,0,0,0,0,0,0,0,0,0,0,0,0,~
0)';BIDI;
    'DDR1_DQ'<15>:'(0,0,0,AC80,0,0,0,0,0,0,0,0,0,0,0,0,0,0,0,0,0,0,0,0,0,0,0,0,0~
,0)';BIDI;
    'DDR1_DQ'<14>:'(0,0,0,AE82,0,0,0,0,0,0,0,0,0,0,0,0,0,0,0,0,0,0,0,0,0,0,0,0,0~
,0)';BIDI;
    'DDR1_DQ'<13>:'(0,0,0,AH79,0,0,0,0,0,0,0,0,0,0,0,0,0,0,0,0,0,0,0,0,0,0,0,0,0~
,0)';BIDI;
    'DDR1_DQ'<12>:'(0,0,0,AJ80,0,0,0,0,0,0,0,0,0,0,0,0,0,0,0,0,0,0,0,0,0,0,0,0,0~
,0)';BIDI;
    'DDR1_DQ'<11>:'(0,0,0,AB81,0,0,0,0,0,0,0,0,0,0,0,0,0,0,0,0,0,0,0,0,0,0,0,0,0~
,0)';BIDI;
    'DDR1_DQ'<10>:'(0,0,0,AC82,0,0,0,0,0,0,0,0,0,0,0,0,0,0,0,0,0,0,0,0,0,0,0,0,0~
,0)';BIDI;
    'DDR1_DQ'<9>:'(0,0,0,AF79,0,0,0,0,0,0,0,0,0,0,0,0,0,0,0,0,0,0,0,0,0,0,0,0,0,~
0)';BIDI;
    'DDR1_DQ'<8>:'(0,0,0,AH81,0,0,0,0,0,0,0,0,0,0,0,0,0,0,0,0,0,0,0,0,0,0,0,0,0,~
0)';BIDI;
    'DDR1_DQ'<7>:'(0,0,0,AN80,0,0,0,0,0,0,0,0,0,0,0,0,0,0,0,0,0,0,0,0,0,0,0,0,0,~
0)';BIDI;
    'DDR1_DQ'<6>:'(0,0,0,AR82,0,0,0,0,0,0,0,0,0,0,0,0,0,0,0,0,0,0,0,0,0,0,0,0,0,~
0)';BIDI;
    'DDR1_DQ'<5>:'(0,0,0,AV79,0,0,0,0,0,0,0,0,0,0,0,0,0,0,0,0,0,0,0,0,0,0,0,0,0,~
0)';BIDI;
    'DDR1_DQ'<4>:'(0,0,0,AW80,0,0,0,0,0,0,0,0,0,0,0,0,0,0,0,0,0,0,0,0,0,0,0,0,0,~
0)';BIDI;
    'DDR1_DQ'<3>:'(0,0,0,AM81,0,0,0,0,0,0,0,0,0,0,0,0,0,0,0,0,0,0,0,0,0,0,0,0,0,~
0)';BIDI;
    'DDR1_DQ'<2>:'(0,0,0,AN82,0,0,0,0,0,0,0,0,0,0,0,0,0,0,0,0,0,0,0,0,0,0,0,0,0,~
0)';BIDI;
    'DDR1_DQ'<1>:'(0,0,0,AT79,0,0,0,0,0,0,0,0,0,0,0,0,0,0,0,0,0,0,0,0,0,0,0,0,0,~
0)';BIDI;
    'DDR1_DQ'<0>:'(0,0,0,AV81,0,0,0,0,0,0,0,0,0,0,0,0,0,0,0,0,0,0,0,0,0,0,0,0,0,~
0)';BIDI;
    'DDR1_DQS_DN'<17>:'(0,0,0,G68,0,0,0,0,0,0,0,0,0,0,0,0,0,0,0,0,0,0,0,0,0,0,0,~
0,0,0)';BIDI;
    'DDR1_DQS_DN'<16>:'(0,0,0,T27,0,0,0,0,0,0,0,0,0,0,0,0,0,0,0,0,0,0,0,0,0,0,0,~
0,0,0)';BIDI;
    'DDR1_DQS_DN'<15>:'(0,0,0,A28,0,0,0,0,0,0,0,0,0,0,0,0,0,0,0,0,0,0,0,0,0,0,0,~
0,0,0)';BIDI;
    'DDR1_DQS_DN'<14>:'(0,0,0,A34,0,0,0,0,0,0,0,0,0,0,0,0,0,0,0,0,0,0,0,0,0,0,0,~
0,0,0)';BIDI;
    'DDR1_DQS_DN'<13>:'(0,0,0,J42,0,0,0,0,0,0,0,0,0,0,0,0,0,0,0,0,0,0,0,0,0,0,0,~
0,0,0)';BIDI;
    'DDR1_DQS_DN'<12>:'(0,0,0,B73,0,0,0,0,0,0,0,0,0,0,0,0,0,0,0,0,0,0,0,0,0,0,0,~
0,0,0)';BIDI;
    'DDR1_DQS_DN'<11>:'(0,0,0,D79,0,0,0,0,0,0,0,0,0,0,0,0,0,0,0,0,0,0,0,0,0,0,0,~
0,0,0)';BIDI;
    'DDR1_DQS_DN'<10>:'(0,0,0,AG82,0,0,0,0,0,0,0,0,0,0,0,0,0,0,0,0,0,0,0,0,0,0,0~
,0,0,0)';BIDI;
    'DDR1_DQS_DN'<9>:'(0,0,0,AU82,0,0,0,0,0,0,0,0,0,0,0,0,0,0,0,0,0,0,0,0,0,0,0,~
0,0,0)';BIDI;
    'DDR1_DQS_DN'<8>:'(0,0,0,N68,0,0,0,0,0,0,0,0,0,0,0,0,0,0,0,0,0,0,0,0,0,0,0,0~
,0,0)';BIDI;
    'DDR1_DQS_DN'<7>:'(0,0,0,AB27,0,0,0,0,0,0,0,0,0,0,0,0,0,0,0,0,0,0,0,0,0,0,0,~
0,0,0)';BIDI;
    'DDR1_DQS_DN'<6>:'(0,0,0,G28,0,0,0,0,0,0,0,0,0,0,0,0,0,0,0,0,0,0,0,0,0,0,0,0~
,0,0)';BIDI;
    'DDR1_DQS_DN'<5>:'(0,0,0,G34,0,0,0,0,0,0,0,0,0,0,0,0,0,0,0,0,0,0,0,0,0,0,0,0~
,0,0)';BIDI;
    'DDR1_DQS_DN'<4>:'(0,0,0,N42,0,0,0,0,0,0,0,0,0,0,0,0,0,0,0,0,0,0,0,0,0,0,0,0~
,0,0)';BIDI;
    'DDR1_DQS_DN'<3>:'(0,0,0,H73,0,0,0,0,0,0,0,0,0,0,0,0,0,0,0,0,0,0,0,0,0,0,0,0~
,0,0)';BIDI;
    'DDR1_DQS_DN'<2>:'(0,0,0,K79,0,0,0,0,0,0,0,0,0,0,0,0,0,0,0,0,0,0,0,0,0,0,0,0~
,0,0)';BIDI;
    'DDR1_DQS_DN'<1>:'(0,0,0,AD79,0,0,0,0,0,0,0,0,0,0,0,0,0,0,0,0,0,0,0,0,0,0,0,~
0,0,0)';BIDI;
    'DDR1_DQS_DN'<0>:'(0,0,0,AP79,0,0,0,0,0,0,0,0,0,0,0,0,0,0,0,0,0,0,0,0,0,0,0,~
0,0,0)';BIDI;
    'DDR1_DQS_DP'<17>:'(0,0,0,J68,0,0,0,0,0,0,0,0,0,0,0,0,0,0,0,0,0,0,0,0,0,0,0,~
0,0,0)';BIDI;
    'DDR1_DQS_DP'<16>:'(0,0,0,V27,0,0,0,0,0,0,0,0,0,0,0,0,0,0,0,0,0,0,0,0,0,0,0,~
0,0,0)';BIDI;
    'DDR1_DQS_DP'<15>:'(0,0,0,C28,0,0,0,0,0,0,0,0,0,0,0,0,0,0,0,0,0,0,0,0,0,0,0,~
0,0,0)';BIDI;
    'DDR1_DQS_DP'<14>:'(0,0,0,C34,0,0,0,0,0,0,0,0,0,0,0,0,0,0,0,0,0,0,0,0,0,0,0,~
0,0,0)';BIDI;
    'DDR1_DQS_DP'<13>:'(0,0,0,L42,0,0,0,0,0,0,0,0,0,0,0,0,0,0,0,0,0,0,0,0,0,0,0,~
0,0,0)';BIDI;
    'DDR1_DQS_DP'<12>:'(0,0,0,D73,0,0,0,0,0,0,0,0,0,0,0,0,0,0,0,0,0,0,0,0,0,0,0,~
0,0,0)';BIDI;
    'DDR1_DQS_DP'<11>:'(0,0,0,F79,0,0,0,0,0,0,0,0,0,0,0,0,0,0,0,0,0,0,0,0,0,0,0,~
0,0,0)';BIDI;
    'DDR1_DQS_DP'<10>:'(0,0,0,AF81,0,0,0,0,0,0,0,0,0,0,0,0,0,0,0,0,0,0,0,0,0,0,0~
,0,0,0)';BIDI;
    'DDR1_DQS_DP'<9>:'(0,0,0,AT81,0,0,0,0,0,0,0,0,0,0,0,0,0,0,0,0,0,0,0,0,0,0,0,~
0,0,0)';BIDI;
    'DDR1_DQS_DP'<8>:'(0,0,0,L68,0,0,0,0,0,0,0,0,0,0,0,0,0,0,0,0,0,0,0,0,0,0,0,0~
,0,0)';BIDI;
    'DDR1_DQS_DP'<7>:'(0,0,0,Y27,0,0,0,0,0,0,0,0,0,0,0,0,0,0,0,0,0,0,0,0,0,0,0,0~
,0,0)';BIDI;
    'DDR1_DQS_DP'<6>:'(0,0,0,E28,0,0,0,0,0,0,0,0,0,0,0,0,0,0,0,0,0,0,0,0,0,0,0,0~
,0,0)';BIDI;
    'DDR1_DQS_DP'<5>:'(0,0,0,E34,0,0,0,0,0,0,0,0,0,0,0,0,0,0,0,0,0,0,0,0,0,0,0,0~
,0,0)';BIDI;
    'DDR1_DQS_DP'<4>:'(0,0,0,R42,0,0,0,0,0,0,0,0,0,0,0,0,0,0,0,0,0,0,0,0,0,0,0,0~
,0,0)';BIDI;
    'DDR1_DQS_DP'<3>:'(0,0,0,F73,0,0,0,0,0,0,0,0,0,0,0,0,0,0,0,0,0,0,0,0,0,0,0,0~
,0,0)';BIDI;
    'DDR1_DQS_DP'<2>:'(0,0,0,H79,0,0,0,0,0,0,0,0,0,0,0,0,0,0,0,0,0,0,0,0,0,0,0,0~
,0,0)';BIDI;
    'DDR1_DQS_DP'<1>:'(0,0,0,AE80,0,0,0,0,0,0,0,0,0,0,0,0,0,0,0,0,0,0,0,0,0,0,0,~
0,0,0)';BIDI;
    'DDR1_DQS_DP'<0>:'(0,0,0,AR80,0,0,0,0,0,0,0,0,0,0,0,0,0,0,0,0,0,0,0,0,0,0,0,~
0,0,0)';BIDI;
    'DDR1_ECC'<7>:'(0,0,0,M67,0,0,0,0,0,0,0,0,0,0,0,0,0,0,0,0,0,0,0,0,0,0,0,0,0,~
0)';BIDI;
    'DDR1_ECC'<6>:'(0,0,0,H67,0,0,0,0,0,0,0,0,0,0,0,0,0,0,0,0,0,0,0,0,0,0,0,0,0,~
0)';BIDI;
    'DDR1_ECC'<5>:'(0,0,0,M69,0,0,0,0,0,0,0,0,0,0,0,0,0,0,0,0,0,0,0,0,0,0,0,0,0,~
0)';BIDI;
    'DDR1_ECC'<4>:'(0,0,0,L70,0,0,0,0,0,0,0,0,0,0,0,0,0,0,0,0,0,0,0,0,0,0,0,0,0,~
0)';BIDI;
    'DDR1_ECC'<3>:'(0,0,0,L66,0,0,0,0,0,0,0,0,0,0,0,0,0,0,0,0,0,0,0,0,0,0,0,0,0,~
0)';BIDI;
    'DDR1_ECC'<2>:'(0,0,0,J66,0,0,0,0,0,0,0,0,0,0,0,0,0,0,0,0,0,0,0,0,0,0,0,0,0,~
0)';BIDI;
    'DDR1_ECC'<1>:'(0,0,0,H69,0,0,0,0,0,0,0,0,0,0,0,0,0,0,0,0,0,0,0,0,0,0,0,0,0,~
0)';BIDI;
    'DDR1_ECC'<0>:'(0,0,0,J70,0,0,0,0,0,0,0,0,0,0,0,0,0,0,0,0,0,0,0,0,0,0,0,0,0,~
0)';BIDI;
    'DDR1_MA'<17>:'(0,0,0,N48,0,0,0,0,0,0,0,0,0,0,0,0,0,0,0,0,0,0,0,0,0,0,0,0,0,~
0)';OUT;
    'DDR1_MA'<16>:'(0,0,0,R52,0,0,0,0,0,0,0,0,0,0,0,0,0,0,0,0,0,0,0,0,0,0,0,0,0,~
0)';OUT;
    'DDR1_MA'<15>:'(0,0,0,N52,0,0,0,0,0,0,0,0,0,0,0,0,0,0,0,0,0,0,0,0,0,0,0,0,0,~
0)';OUT;
    'DDR1_MA'<14>:'(0,0,0,T51,0,0,0,0,0,0,0,0,0,0,0,0,0,0,0,0,0,0,0,0,0,0,0,0,0,~
0)';OUT;
    'DDR1_MA'<13>:'(0,0,0,M51,0,0,0,0,0,0,0,0,0,0,0,0,0,0,0,0,0,0,0,0,0,0,0,0,0,~
0)';OUT;
    'DDR1_MA'<12>:'(0,0,0,T61,0,0,0,0,0,0,0,0,0,0,0,0,0,0,0,0,0,0,0,0,0,0,0,0,0,~
0)';OUT;
    'DDR1_MA'<11>:'(0,0,0,R60,0,0,0,0,0,0,0,0,0,0,0,0,0,0,0,0,0,0,0,0,0,0,0,0,0,~
0)';OUT;
    'DDR1_MA'<10>:'(0,0,0,M55,0,0,0,0,0,0,0,0,0,0,0,0,0,0,0,0,0,0,0,0,0,0,0,0,0,~
0)';OUT;
    'DDR1_MA'<9>:'(0,0,0,K59,0,0,0,0,0,0,0,0,0,0,0,0,0,0,0,0,0,0,0,0,0,0,0,0,0,0~
)';OUT;
    'DDR1_MA'<8>:'(0,0,0,W60,0,0,0,0,0,0,0,0,0,0,0,0,0,0,0,0,0,0,0,0,0,0,0,0,0,0~
)';OUT;
    'DDR1_MA'<7>:'(0,0,0,V61,0,0,0,0,0,0,0,0,0,0,0,0,0,0,0,0,0,0,0,0,0,0,0,0,0,0~
)';OUT;
    'DDR1_MA'<6>:'(0,0,0,T59,0,0,0,0,0,0,0,0,0,0,0,0,0,0,0,0,0,0,0,0,0,0,0,0,0,0~
)';OUT;
    'DDR1_MA'<5>:'(0,0,0,R58,0,0,0,0,0,0,0,0,0,0,0,0,0,0,0,0,0,0,0,0,0,0,0,0,0,0~
)';OUT;
    'DDR1_MA'<4>:'(0,0,0,M59,0,0,0,0,0,0,0,0,0,0,0,0,0,0,0,0,0,0,0,0,0,0,0,0,0,0~
)';OUT;
    'DDR1_MA'<3>:'(0,0,0,N58,0,0,0,0,0,0,0,0,0,0,0,0,0,0,0,0,0,0,0,0,0,0,0,0,0,0~
)';OUT;
    'DDR1_MA'<2>:'(0,0,0,K57,0,0,0,0,0,0,0,0,0,0,0,0,0,0,0,0,0,0,0,0,0,0,0,0,0,0~
)';OUT;
    'DDR1_MA'<1>:'(0,0,0,J58,0,0,0,0,0,0,0,0,0,0,0,0,0,0,0,0,0,0,0,0,0,0,0,0,0,0~
)';OUT;
    'DDR1_MA'<0>:'(0,0,0,J52,0,0,0,0,0,0,0,0,0,0,0,0,0,0,0,0,0,0,0,0,0,0,0,0,0,0~
)';OUT;
    'DDR1_ODT'<3>:'(0,0,0,T47,0,0,0,0,0,0,0,0,0,0,0,0,0,0,0,0,0,0,0,0,0,0,0,0,0,~
0)';OUT;
    'DDR1_ODT'<2>:'(0,0,0,M49,0,0,0,0,0,0,0,0,0,0,0,0,0,0,0,0,0,0,0,0,0,0,0,0,0,~
0)';OUT;
    'DDR1_ODT'<1>:'(0,0,0,R48,0,0,0,0,0,0,0,0,0,0,0,0,0,0,0,0,0,0,0,0,0,0,0,0,0,~
0)';OUT;
    'DDR1_ODT'<0>:'(0,0,0,N50,0,0,0,0,0,0,0,0,0,0,0,0,0,0,0,0,0,0,0,0,0,0,0,0,0,~
0)';OUT;
    'DDR1_PAR':'(0,0,0,K53,0,0,0,0,0,0,0,0,0,0,0,0,0,0,0,0,0,0,0,0,0,0,0,0,0,0)';$S;OUT;
    'DDR2_ACT_N':'(0,0,0,0,AB61,0,0,0,0,0,0,0,0,0,0,0,0,0,0,0,0,0,0,0,0,0,0,0,0,~
0)';$S;OUT;
    'DDR2_ALERT_N':'(0,0,0,0,AD61,0,0,0,0,0,0,0,0,0,0,0,0,0,0,0,0,0,0,0,0,0,0,0,~
0,0)';$S;IN;
    'DDR2_BA'<1>:'(0,0,0,0,AE56,0,0,0,0,0,0,0,0,0,0,0,0,0,0,0,0,0,0,0,0,0,0,0,0,~
0)';OUT;
    'DDR2_BA'<0>:'(0,0,0,0,W52,0,0,0,0,0,0,0,0,0,0,0,0,0,0,0,0,0,0,0,0,0,0,0,0,0~
)';OUT;
    'DDR2_BG'<1>:'(0,0,0,0,AE62,0,0,0,0,0,0,0,0,0,0,0,0,0,0,0,0,0,0,0,0,0,0,0,0,~
0)';OUT;
    'DDR2_BG'<0>:'(0,0,0,0,AA60,0,0,0,0,0,0,0,0,0,0,0,0,0,0,0,0,0,0,0,0,0,0,0,0,~
0)';OUT;
    'DDR2_CAVREF':'(AH63,0,0,0,0,0,0,0,0,0,0,0,0,0,0,0,0,0,0,0,0,0,0,0,0,0,0,0,0~
,0)';$S;OUT;
    'DDR2_CID'<2>:'(0,0,0,0,AB45,0,0,0,0,0,0,0,0,0,0,0,0,0,0,0,0,0,0,0,0,0,0,0,0~
,0)';$S;OUT;
    'DDR2_CKE'<3>:'(0,0,0,0,AB63,0,0,0,0,0,0,0,0,0,0,0,0,0,0,0,0,0,0,0,0,0,0,0,0~
,0)';OUT;
    'DDR2_CKE'<2>:'(0,0,0,0,V63,0,0,0,0,0,0,0,0,0,0,0,0,0,0,0,0,0,0,0,0,0,0,0,0,~
0)';OUT;
    'DDR2_CKE'<1>:'(0,0,0,0,AD63,0,0,0,0,0,0,0,0,0,0,0,0,0,0,0,0,0,0,0,0,0,0,0,0~
,0)';OUT;
    'DDR2_CKE'<0>:'(0,0,0,0,AA62,0,0,0,0,0,0,0,0,0,0,0,0,0,0,0,0,0,0,0,0,0,0,0,0~
,0)';OUT;
    'DDR2_CLK_DN'<3>:'(0,0,0,0,W56,0,0,0,0,0,0,0,0,0,0,0,0,0,0,0,0,0,0,0,0,0,0,0~
,0,0)';OUT;
    'DDR2_CLK_DN'<2>:'(0,0,0,0,AA56,0,0,0,0,0,0,0,0,0,0,0,0,0,0,0,0,0,0,0,0,0,0,~
0,0,0)';OUT;
    'DDR2_CLK_DN'<1>:'(0,0,0,0,W54,0,0,0,0,0,0,0,0,0,0,0,0,0,0,0,0,0,0,0,0,0,0,0~
,0,0)';OUT;
    'DDR2_CLK_DN'<0>:'(0,0,0,0,AA54,0,0,0,0,0,0,0,0,0,0,0,0,0,0,0,0,0,0,0,0,0,0,~
0,0,0)';OUT;
    'DDR2_CLK_DP'<3>:'(0,0,0,0,V57,0,0,0,0,0,0,0,0,0,0,0,0,0,0,0,0,0,0,0,0,0,0,0~
,0,0)';OUT;
    'DDR2_CLK_DP'<2>:'(0,0,0,0,AB57,0,0,0,0,0,0,0,0,0,0,0,0,0,0,0,0,0,0,0,0,0,0,~
0,0,0)';OUT;
    'DDR2_CLK_DP'<1>:'(0,0,0,0,V55,0,0,0,0,0,0,0,0,0,0,0,0,0,0,0,0,0,0,0,0,0,0,0~
,0,0)';OUT;
    'DDR2_CLK_DP'<0>:'(0,0,0,0,AB55,0,0,0,0,0,0,0,0,0,0,0,0,0,0,0,0,0,0,0,0,0,0,~
0,0,0)';OUT;
    'DDR2_CS_N'<7>:'(0,0,0,0,V45,0,0,0,0,0,0,0,0,0,0,0,0,0,0,0,0,0,0,0,0,0,0,0,0~
,0)';OUT;
    'DDR2_CS_N'<6>:'(0,0,0,0,T45,0,0,0,0,0,0,0,0,0,0,0,0,0,0,0,0,0,0,0,0,0,0,0,0~
,0)';OUT;
    'DDR2_CS_N'<5>:'(0,0,0,0,W48,0,0,0,0,0,0,0,0,0,0,0,0,0,0,0,0,0,0,0,0,0,0,0,0~
,0)';OUT;
    'DDR2_CS_N'<4>:'(0,0,0,0,AB51,0,0,0,0,0,0,0,0,0,0,0,0,0,0,0,0,0,0,0,0,0,0,0,~
0,0)';OUT;
    'DDR2_CS_N'<3>:'(0,0,0,0,AA46,0,0,0,0,0,0,0,0,0,0,0,0,0,0,0,0,0,0,0,0,0,0,0,~
0,0)';OUT;
    'DDR2_CS_N'<2>:'(0,0,0,0,W46,0,0,0,0,0,0,0,0,0,0,0,0,0,0,0,0,0,0,0,0,0,0,0,0~
,0)';OUT;
    'DDR2_CS_N'<1>:'(0,0,0,0,AB49,0,0,0,0,0,0,0,0,0,0,0,0,0,0,0,0,0,0,0,0,0,0,0,~
0,0)';OUT;
    'DDR2_CS_N'<0>:'(0,0,0,0,V51,0,0,0,0,0,0,0,0,0,0,0,0,0,0,0,0,0,0,0,0,0,0,0,0~
,0)';OUT;
    'DDR2_DQ'<63>:'(0,0,0,0,AH23,0,0,0,0,0,0,0,0,0,0,0,0,0,0,0,0,0,0,0,0,0,0,0,0~
,0)';BIDI;
    'DDR2_DQ'<62>:'(0,0,0,0,AD23,0,0,0,0,0,0,0,0,0,0,0,0,0,0,0,0,0,0,0,0,0,0,0,0~
,0)';BIDI;
    'DDR2_DQ'<61>:'(0,0,0,0,AG26,0,0,0,0,0,0,0,0,0,0,0,0,0,0,0,0,0,0,0,0,0,0,0,0~
,0)';BIDI;
    'DDR2_DQ'<60>:'(0,0,0,0,AE26,0,0,0,0,0,0,0,0,0,0,0,0,0,0,0,0,0,0,0,0,0,0,0,0~
,0)';BIDI;
    'DDR2_DQ'<59>:'(0,0,0,0,AG22,0,0,0,0,0,0,0,0,0,0,0,0,0,0,0,0,0,0,0,0,0,0,0,0~
,0)';BIDI;
    'DDR2_DQ'<58>:'(0,0,0,0,AE22,0,0,0,0,0,0,0,0,0,0,0,0,0,0,0,0,0,0,0,0,0,0,0,0~
,0)';BIDI;
    'DDR2_DQ'<57>:'(0,0,0,0,AH25,0,0,0,0,0,0,0,0,0,0,0,0,0,0,0,0,0,0,0,0,0,0,0,0~
,0)';BIDI;
    'DDR2_DQ'<56>:'(0,0,0,0,AD25,0,0,0,0,0,0,0,0,0,0,0,0,0,0,0,0,0,0,0,0,0,0,0,0~
,0)';BIDI;
    'DDR2_DQ'<55>:'(0,0,0,0,AH29,0,0,0,0,0,0,0,0,0,0,0,0,0,0,0,0,0,0,0,0,0,0,0,0~
,0)';BIDI;
    'DDR2_DQ'<54>:'(0,0,0,0,AD29,0,0,0,0,0,0,0,0,0,0,0,0,0,0,0,0,0,0,0,0,0,0,0,0~
,0)';BIDI;
    'DDR2_DQ'<53>:'(0,0,0,0,AG32,0,0,0,0,0,0,0,0,0,0,0,0,0,0,0,0,0,0,0,0,0,0,0,0~
,0)';BIDI;
    'DDR2_DQ'<52>:'(0,0,0,0,AE32,0,0,0,0,0,0,0,0,0,0,0,0,0,0,0,0,0,0,0,0,0,0,0,0~
,0)';BIDI;
    'DDR2_DQ'<51>:'(0,0,0,0,AG28,0,0,0,0,0,0,0,0,0,0,0,0,0,0,0,0,0,0,0,0,0,0,0,0~
,0)';BIDI;
    'DDR2_DQ'<50>:'(0,0,0,0,AE28,0,0,0,0,0,0,0,0,0,0,0,0,0,0,0,0,0,0,0,0,0,0,0,0~
,0)';BIDI;
    'DDR2_DQ'<49>:'(0,0,0,0,AH31,0,0,0,0,0,0,0,0,0,0,0,0,0,0,0,0,0,0,0,0,0,0,0,0~
,0)';BIDI;
    'DDR2_DQ'<48>:'(0,0,0,0,AD31,0,0,0,0,0,0,0,0,0,0,0,0,0,0,0,0,0,0,0,0,0,0,0,0~
,0)';BIDI;
    'DDR2_DQ'<47>:'(0,0,0,0,AA32,0,0,0,0,0,0,0,0,0,0,0,0,0,0,0,0,0,0,0,0,0,0,0,0~
,0)';BIDI;
    'DDR2_DQ'<46>:'(0,0,0,0,U32,0,0,0,0,0,0,0,0,0,0,0,0,0,0,0,0,0,0,0,0,0,0,0,0,~
0)';BIDI;
    'DDR2_DQ'<45>:'(0,0,0,0,Y35,0,0,0,0,0,0,0,0,0,0,0,0,0,0,0,0,0,0,0,0,0,0,0,0,~
0)';BIDI;
    'DDR2_DQ'<44>:'(0,0,0,0,V35,0,0,0,0,0,0,0,0,0,0,0,0,0,0,0,0,0,0,0,0,0,0,0,0,~
0)';BIDI;
    'DDR2_DQ'<43>:'(0,0,0,0,Y31,0,0,0,0,0,0,0,0,0,0,0,0,0,0,0,0,0,0,0,0,0,0,0,0,~
0)';BIDI;
    'DDR2_DQ'<42>:'(0,0,0,0,V31,0,0,0,0,0,0,0,0,0,0,0,0,0,0,0,0,0,0,0,0,0,0,0,0,~
0)';BIDI;
    'DDR2_DQ'<41>:'(0,0,0,0,AA34,0,0,0,0,0,0,0,0,0,0,0,0,0,0,0,0,0,0,0,0,0,0,0,0~
,0)';BIDI;
    'DDR2_DQ'<40>:'(0,0,0,0,U34,0,0,0,0,0,0,0,0,0,0,0,0,0,0,0,0,0,0,0,0,0,0,0,0,~
0)';BIDI;
    'DDR2_DQ'<39>:'(0,0,0,0,AA38,0,0,0,0,0,0,0,0,0,0,0,0,0,0,0,0,0,0,0,0,0,0,0,0~
,0)';BIDI;
    'DDR2_DQ'<38>:'(0,0,0,0,U38,0,0,0,0,0,0,0,0,0,0,0,0,0,0,0,0,0,0,0,0,0,0,0,0,~
0)';BIDI;
    'DDR2_DQ'<37>:'(0,0,0,0,Y41,0,0,0,0,0,0,0,0,0,0,0,0,0,0,0,0,0,0,0,0,0,0,0,0,~
0)';BIDI;
    'DDR2_DQ'<36>:'(0,0,0,0,V41,0,0,0,0,0,0,0,0,0,0,0,0,0,0,0,0,0,0,0,0,0,0,0,0,~
0)';BIDI;
    'DDR2_DQ'<35>:'(0,0,0,0,Y37,0,0,0,0,0,0,0,0,0,0,0,0,0,0,0,0,0,0,0,0,0,0,0,0,~
0)';BIDI;
    'DDR2_DQ'<34>:'(0,0,0,0,V37,0,0,0,0,0,0,0,0,0,0,0,0,0,0,0,0,0,0,0,0,0,0,0,0,~
0)';BIDI;
    'DDR2_DQ'<33>:'(0,0,0,0,AA40,0,0,0,0,0,0,0,0,0,0,0,0,0,0,0,0,0,0,0,0,0,0,0,0~
,0)';BIDI;
    'DDR2_DQ'<32>:'(0,0,0,0,U40,0,0,0,0,0,0,0,0,0,0,0,0,0,0,0,0,0,0,0,0,0,0,0,0,~
0)';BIDI;
    'DDR2_DQ'<31>:'(0,0,0,0,AT65,0,0,0,0,0,0,0,0,0,0,0,0,0,0,0,0,0,0,0,0,0,0,0,0~
,0)';BIDI;
    'DDR2_DQ'<30>:'(0,0,0,0,AM65,0,0,0,0,0,0,0,0,0,0,0,0,0,0,0,0,0,0,0,0,0,0,0,0~
,0)';BIDI;
    'DDR2_DQ'<29>:'(0,0,0,0,AR68,0,0,0,0,0,0,0,0,0,0,0,0,0,0,0,0,0,0,0,0,0,0,0,0~
,0)';BIDI;
    'DDR2_DQ'<28>:'(0,0,0,0,AN68,0,0,0,0,0,0,0,0,0,0,0,0,0,0,0,0,0,0,0,0,0,0,0,0~
,0)';BIDI;
    'DDR2_DQ'<27>:'(0,0,0,0,AR64,0,0,0,0,0,0,0,0,0,0,0,0,0,0,0,0,0,0,0,0,0,0,0,0~
,0)';BIDI;
    'DDR2_DQ'<26>:'(0,0,0,0,AN64,0,0,0,0,0,0,0,0,0,0,0,0,0,0,0,0,0,0,0,0,0,0,0,0~
,0)';BIDI;
    'DDR2_DQ'<25>:'(0,0,0,0,AT67,0,0,0,0,0,0,0,0,0,0,0,0,0,0,0,0,0,0,0,0,0,0,0,0~
,0)';BIDI;
    'DDR2_DQ'<24>:'(0,0,0,0,AM67,0,0,0,0,0,0,0,0,0,0,0,0,0,0,0,0,0,0,0,0,0,0,0,0~
,0)';BIDI;
    'DDR2_DQ'<23>:'(0,0,0,0,V69,0,0,0,0,0,0,0,0,0,0,0,0,0,0,0,0,0,0,0,0,0,0,0,0,~
0)';BIDI;
    'DDR2_DQ'<22>:'(0,0,0,0,T71,0,0,0,0,0,0,0,0,0,0,0,0,0,0,0,0,0,0,0,0,0,0,0,0,~
0)';BIDI;
    'DDR2_DQ'<21>:'(0,0,0,0,AB71,0,0,0,0,0,0,0,0,0,0,0,0,0,0,0,0,0,0,0,0,0,0,0,0~
,0)';BIDI;
    'DDR2_DQ'<20>:'(0,0,0,0,AA72,0,0,0,0,0,0,0,0,0,0,0,0,0,0,0,0,0,0,0,0,0,0,0,0~
,0)';BIDI;
    'DDR2_DQ'<19>:'(0,0,0,0,T69,0,0,0,0,0,0,0,0,0,0,0,0,0,0,0,0,0,0,0,0,0,0,0,0,~
0)';BIDI;
    'DDR2_DQ'<18>:'(0,0,0,0,R70,0,0,0,0,0,0,0,0,0,0,0,0,0,0,0,0,0,0,0,0,0,0,0,0,~
0)';BIDI;
    'DDR2_DQ'<17>:'(0,0,0,0,AA70,0,0,0,0,0,0,0,0,0,0,0,0,0,0,0,0,0,0,0,0,0,0,0,0~
,0)';BIDI;
    'DDR2_DQ'<16>:'(0,0,0,0,W72,0,0,0,0,0,0,0,0,0,0,0,0,0,0,0,0,0,0,0,0,0,0,0,0,~
0)';BIDI;
    'DDR2_DQ'<15>:'(0,0,0,0,Y75,0,0,0,0,0,0,0,0,0,0,0,0,0,0,0,0,0,0,0,0,0,0,0,0,~
0)';BIDI;
    'DDR2_DQ'<14>:'(0,0,0,0,AB77,0,0,0,0,0,0,0,0,0,0,0,0,0,0,0,0,0,0,0,0,0,0,0,0~
,0)';BIDI;
    'DDR2_DQ'<13>:'(0,0,0,0,AE74,0,0,0,0,0,0,0,0,0,0,0,0,0,0,0,0,0,0,0,0,0,0,0,0~
,0)';BIDI;
    'DDR2_DQ'<12>:'(0,0,0,0,AF75,0,0,0,0,0,0,0,0,0,0,0,0,0,0,0,0,0,0,0,0,0,0,0,0~
,0)';BIDI;
    'DDR2_DQ'<11>:'(0,0,0,0,W76,0,0,0,0,0,0,0,0,0,0,0,0,0,0,0,0,0,0,0,0,0,0,0,0,~
0)';BIDI;
    'DDR2_DQ'<10>:'(0,0,0,0,Y77,0,0,0,0,0,0,0,0,0,0,0,0,0,0,0,0,0,0,0,0,0,0,0,0,~
0)';BIDI;
    'DDR2_DQ'<9>:'(0,0,0,0,AC74,0,0,0,0,0,0,0,0,0,0,0,0,0,0,0,0,0,0,0,0,0,0,0,0,~
0)';BIDI;
    'DDR2_DQ'<8>:'(0,0,0,0,AE76,0,0,0,0,0,0,0,0,0,0,0,0,0,0,0,0,0,0,0,0,0,0,0,0,~
0)';BIDI;
    'DDR2_DQ'<7>:'(0,0,0,0,AK75,0,0,0,0,0,0,0,0,0,0,0,0,0,0,0,0,0,0,0,0,0,0,0,0,~
0)';BIDI;
    'DDR2_DQ'<6>:'(0,0,0,0,AM77,0,0,0,0,0,0,0,0,0,0,0,0,0,0,0,0,0,0,0,0,0,0,0,0,~
0)';BIDI;
    'DDR2_DQ'<5>:'(0,0,0,0,AR74,0,0,0,0,0,0,0,0,0,0,0,0,0,0,0,0,0,0,0,0,0,0,0,0,~
0)';BIDI;
    'DDR2_DQ'<4>:'(0,0,0,0,AT75,0,0,0,0,0,0,0,0,0,0,0,0,0,0,0,0,0,0,0,0,0,0,0,0,~
0)';BIDI;
    'DDR2_DQ'<3>:'(0,0,0,0,AJ76,0,0,0,0,0,0,0,0,0,0,0,0,0,0,0,0,0,0,0,0,0,0,0,0,~
0)';BIDI;
    'DDR2_DQ'<2>:'(0,0,0,0,AK77,0,0,0,0,0,0,0,0,0,0,0,0,0,0,0,0,0,0,0,0,0,0,0,0,~
0)';BIDI;
    'DDR2_DQ'<1>:'(0,0,0,0,AN74,0,0,0,0,0,0,0,0,0,0,0,0,0,0,0,0,0,0,0,0,0,0,0,0,~
0)';BIDI;
    'DDR2_DQ'<0>:'(0,0,0,0,AR76,0,0,0,0,0,0,0,0,0,0,0,0,0,0,0,0,0,0,0,0,0,0,0,0,~
0)';BIDI;
    'DDR2_DQS_DN'<17>:'(0,0,0,0,AT71,0,0,0,0,0,0,0,0,0,0,0,0,0,0,0,0,0,0,0,0,0,0~
,0,0,0)';BIDI;
    'DDR2_DQS_DN'<16>:'(0,0,0,0,AC24,0,0,0,0,0,0,0,0,0,0,0,0,0,0,0,0,0,0,0,0,0,0~
,0,0,0)';BIDI;
    'DDR2_DQS_DN'<15>:'(0,0,0,0,AC30,0,0,0,0,0,0,0,0,0,0,0,0,0,0,0,0,0,0,0,0,0,0~
,0,0,0)';BIDI;
    'DDR2_DQS_DN'<14>:'(0,0,0,0,T33,0,0,0,0,0,0,0,0,0,0,0,0,0,0,0,0,0,0,0,0,0,0,~
0,0,0)';BIDI;
    'DDR2_DQS_DN'<13>:'(0,0,0,0,T39,0,0,0,0,0,0,0,0,0,0,0,0,0,0,0,0,0,0,0,0,0,0,~
0,0,0)';BIDI;
    'DDR2_DQS_DN'<12>:'(0,0,0,0,AL66,0,0,0,0,0,0,0,0,0,0,0,0,0,0,0,0,0,0,0,0,0,0~
,0,0,0)';BIDI;
    'DDR2_DQS_DN'<11>:'(0,0,0,0,U72,0,0,0,0,0,0,0,0,0,0,0,0,0,0,0,0,0,0,0,0,0,0,~
0,0,0)';BIDI;
    'DDR2_DQS_DN'<10>:'(0,0,0,0,AD77,0,0,0,0,0,0,0,0,0,0,0,0,0,0,0,0,0,0,0,0,0,0~
,0,0,0)';BIDI;
    'DDR2_DQS_DN'<9>:'(0,0,0,0,AP77,0,0,0,0,0,0,0,0,0,0,0,0,0,0,0,0,0,0,0,0,0,0,~
0,0,0)';BIDI;
    'DDR2_DQS_DN'<8>:'(0,0,0,0,BB71,0,0,0,0,0,0,0,0,0,0,0,0,0,0,0,0,0,0,0,0,0,0,~
0,0,0)';BIDI;
    'DDR2_DQS_DN'<7>:'(0,0,0,0,AJ24,0,0,0,0,0,0,0,0,0,0,0,0,0,0,0,0,0,0,0,0,0,0,~
0,0,0)';BIDI;
    'DDR2_DQS_DN'<6>:'(0,0,0,0,AJ30,0,0,0,0,0,0,0,0,0,0,0,0,0,0,0,0,0,0,0,0,0,0,~
0,0,0)';BIDI;
    'DDR2_DQS_DN'<5>:'(0,0,0,0,AB33,0,0,0,0,0,0,0,0,0,0,0,0,0,0,0,0,0,0,0,0,0,0,~
0,0,0)';BIDI;
    'DDR2_DQS_DN'<4>:'(0,0,0,0,AB39,0,0,0,0,0,0,0,0,0,0,0,0,0,0,0,0,0,0,0,0,0,0,~
0,0,0)';BIDI;
    'DDR2_DQS_DN'<3>:'(0,0,0,0,AU66,0,0,0,0,0,0,0,0,0,0,0,0,0,0,0,0,0,0,0,0,0,0,~
0,0,0)';BIDI;
    'DDR2_DQS_DN'<2>:'(0,0,0,0,Y69,0,0,0,0,0,0,0,0,0,0,0,0,0,0,0,0,0,0,0,0,0,0,0~
,0,0)';BIDI;
    'DDR2_DQS_DN'<1>:'(0,0,0,0,AA74,0,0,0,0,0,0,0,0,0,0,0,0,0,0,0,0,0,0,0,0,0,0,~
0,0,0)';BIDI;
    'DDR2_DQS_DN'<0>:'(0,0,0,0,AL74,0,0,0,0,0,0,0,0,0,0,0,0,0,0,0,0,0,0,0,0,0,0,~
0,0,0)';BIDI;
    'DDR2_DQS_DP'<17>:'(0,0,0,0,AV71,0,0,0,0,0,0,0,0,0,0,0,0,0,0,0,0,0,0,0,0,0,0~
,0,0,0)';BIDI;
    'DDR2_DQS_DP'<16>:'(0,0,0,0,AE24,0,0,0,0,0,0,0,0,0,0,0,0,0,0,0,0,0,0,0,0,0,0~
,0,0,0)';BIDI;
    'DDR2_DQS_DP'<15>:'(0,0,0,0,AE30,0,0,0,0,0,0,0,0,0,0,0,0,0,0,0,0,0,0,0,0,0,0~
,0,0,0)';BIDI;
    'DDR2_DQS_DP'<14>:'(0,0,0,0,V33,0,0,0,0,0,0,0,0,0,0,0,0,0,0,0,0,0,0,0,0,0,0,~
0,0,0)';BIDI;
    'DDR2_DQS_DP'<13>:'(0,0,0,0,V39,0,0,0,0,0,0,0,0,0,0,0,0,0,0,0,0,0,0,0,0,0,0,~
0,0,0)';BIDI;
    'DDR2_DQS_DP'<12>:'(0,0,0,0,AN66,0,0,0,0,0,0,0,0,0,0,0,0,0,0,0,0,0,0,0,0,0,0~
,0,0,0)';BIDI;
    'DDR2_DQS_DP'<11>:'(0,0,0,0,V71,0,0,0,0,0,0,0,0,0,0,0,0,0,0,0,0,0,0,0,0,0,0,~
0,0,0)';BIDI;
    'DDR2_DQS_DP'<10>:'(0,0,0,0,AC76,0,0,0,0,0,0,0,0,0,0,0,0,0,0,0,0,0,0,0,0,0,0~
,0,0,0)';BIDI;
    'DDR2_DQS_DP'<9>:'(0,0,0,0,AN76,0,0,0,0,0,0,0,0,0,0,0,0,0,0,0,0,0,0,0,0,0,0,~
0,0,0)';BIDI;
    'DDR2_DQS_DP'<8>:'(0,0,0,0,AY71,0,0,0,0,0,0,0,0,0,0,0,0,0,0,0,0,0,0,0,0,0,0,~
0,0,0)';BIDI;
    'DDR2_DQS_DP'<7>:'(0,0,0,0,AG24,0,0,0,0,0,0,0,0,0,0,0,0,0,0,0,0,0,0,0,0,0,0,~
0,0,0)';BIDI;
    'DDR2_DQS_DP'<6>:'(0,0,0,0,AG30,0,0,0,0,0,0,0,0,0,0,0,0,0,0,0,0,0,0,0,0,0,0,~
0,0,0)';BIDI;
    'DDR2_DQS_DP'<5>:'(0,0,0,0,Y33,0,0,0,0,0,0,0,0,0,0,0,0,0,0,0,0,0,0,0,0,0,0,0~
,0,0)';BIDI;
    'DDR2_DQS_DP'<4>:'(0,0,0,0,Y39,0,0,0,0,0,0,0,0,0,0,0,0,0,0,0,0,0,0,0,0,0,0,0~
,0,0)';BIDI;
    'DDR2_DQS_DP'<3>:'(0,0,0,0,AR66,0,0,0,0,0,0,0,0,0,0,0,0,0,0,0,0,0,0,0,0,0,0,~
0,0,0)';BIDI;
    'DDR2_DQS_DP'<2>:'(0,0,0,0,W70,0,0,0,0,0,0,0,0,0,0,0,0,0,0,0,0,0,0,0,0,0,0,0~
,0,0)';BIDI;
    'DDR2_DQS_DP'<1>:'(0,0,0,0,AB75,0,0,0,0,0,0,0,0,0,0,0,0,0,0,0,0,0,0,0,0,0,0,~
0,0,0)';BIDI;
    'DDR2_DQS_DP'<0>:'(0,0,0,0,AM75,0,0,0,0,0,0,0,0,0,0,0,0,0,0,0,0,0,0,0,0,0,0,~
0,0,0)';BIDI;
    'DDR2_ECC'<7>:'(0,0,0,0,BA70,0,0,0,0,0,0,0,0,0,0,0,0,0,0,0,0,0,0,0,0,0,0,0,0~
,0)';BIDI;
    'DDR2_ECC'<6>:'(0,0,0,0,AU70,0,0,0,0,0,0,0,0,0,0,0,0,0,0,0,0,0,0,0,0,0,0,0,0~
,0)';BIDI;
    'DDR2_ECC'<5>:'(0,0,0,0,AY73,0,0,0,0,0,0,0,0,0,0,0,0,0,0,0,0,0,0,0,0,0,0,0,0~
,0)';BIDI;
    'DDR2_ECC'<4>:'(0,0,0,0,AV73,0,0,0,0,0,0,0,0,0,0,0,0,0,0,0,0,0,0,0,0,0,0,0,0~
,0)';BIDI;
    'DDR2_ECC'<3>:'(0,0,0,0,AY69,0,0,0,0,0,0,0,0,0,0,0,0,0,0,0,0,0,0,0,0,0,0,0,0~
,0)';BIDI;
    'DDR2_ECC'<2>:'(0,0,0,0,AV69,0,0,0,0,0,0,0,0,0,0,0,0,0,0,0,0,0,0,0,0,0,0,0,0~
,0)';BIDI;
    'DDR2_ECC'<1>:'(0,0,0,0,BA72,0,0,0,0,0,0,0,0,0,0,0,0,0,0,0,0,0,0,0,0,0,0,0,0~
,0)';BIDI;
    'DDR2_ECC'<0>:'(0,0,0,0,AU72,0,0,0,0,0,0,0,0,0,0,0,0,0,0,0,0,0,0,0,0,0,0,0,0~
,0)';BIDI;
    'DDR2_MA'<17>:'(0,0,0,0,AC46,0,0,0,0,0,0,0,0,0,0,0,0,0,0,0,0,0,0,0,0,0,0,0,0~
,0)';OUT;
    'DDR2_MA'<16>:'(0,0,0,0,AA52,0,0,0,0,0,0,0,0,0,0,0,0,0,0,0,0,0,0,0,0,0,0,0,0~
,0)';OUT;
    'DDR2_MA'<15>:'(0,0,0,0,AE54,0,0,0,0,0,0,0,0,0,0,0,0,0,0,0,0,0,0,0,0,0,0,0,0~
,0)';OUT;
    'DDR2_MA'<14>:'(0,0,0,0,W50,0,0,0,0,0,0,0,0,0,0,0,0,0,0,0,0,0,0,0,0,0,0,0,0,~
0)';OUT;
    'DDR2_MA'<13>:'(0,0,0,0,AD53,0,0,0,0,0,0,0,0,0,0,0,0,0,0,0,0,0,0,0,0,0,0,0,0~
,0)';OUT;
    'DDR2_MA'<12>:'(0,0,0,0,AG62,0,0,0,0,0,0,0,0,0,0,0,0,0,0,0,0,0,0,0,0,0,0,0,0~
,0)';OUT;
    'DDR2_MA'<11>:'(0,0,0,0,AG60,0,0,0,0,0,0,0,0,0,0,0,0,0,0,0,0,0,0,0,0,0,0,0,0~
,0)';OUT;
    'DDR2_MA'<10>:'(0,0,0,0,AD55,0,0,0,0,0,0,0,0,0,0,0,0,0,0,0,0,0,0,0,0,0,0,0,0~
,0)';OUT;
    'DDR2_MA'<9>:'(0,0,0,0,AG58,0,0,0,0,0,0,0,0,0,0,0,0,0,0,0,0,0,0,0,0,0,0,0,0,~
0)';OUT;
    'DDR2_MA'<8>:'(0,0,0,0,AD59,0,0,0,0,0,0,0,0,0,0,0,0,0,0,0,0,0,0,0,0,0,0,0,0,~
0)';OUT;
    'DDR2_MA'<7>:'(0,0,0,0,AE60,0,0,0,0,0,0,0,0,0,0,0,0,0,0,0,0,0,0,0,0,0,0,0,0,~
0)';OUT;
    'DDR2_MA'<6>:'(0,0,0,0,AB59,0,0,0,0,0,0,0,0,0,0,0,0,0,0,0,0,0,0,0,0,0,0,0,0,~
0)';OUT;
    'DDR2_MA'<5>:'(0,0,0,0,V59,0,0,0,0,0,0,0,0,0,0,0,0,0,0,0,0,0,0,0,0,0,0,0,0,0~
)';OUT;
    'DDR2_MA'<4>:'(0,0,0,0,AA58,0,0,0,0,0,0,0,0,0,0,0,0,0,0,0,0,0,0,0,0,0,0,0,0,~
0)';OUT;
    'DDR2_MA'<3>:'(0,0,0,0,W58,0,0,0,0,0,0,0,0,0,0,0,0,0,0,0,0,0,0,0,0,0,0,0,0,0~
)';OUT;
    'DDR2_MA'<2>:'(0,0,0,0,AD57,0,0,0,0,0,0,0,0,0,0,0,0,0,0,0,0,0,0,0,0,0,0,0,0,~
0)';OUT;
    'DDR2_MA'<1>:'(0,0,0,0,AE58,0,0,0,0,0,0,0,0,0,0,0,0,0,0,0,0,0,0,0,0,0,0,0,0,~
0)';OUT;
    'DDR2_MA'<0>:'(0,0,0,0,AB53,0,0,0,0,0,0,0,0,0,0,0,0,0,0,0,0,0,0,0,0,0,0,0,0,~
0)';OUT;
    'DDR2_ODT'<3>:'(0,0,0,0,AB47,0,0,0,0,0,0,0,0,0,0,0,0,0,0,0,0,0,0,0,0,0,0,0,0~
,0)';OUT;
    'DDR2_ODT'<2>:'(0,0,0,0,V49,0,0,0,0,0,0,0,0,0,0,0,0,0,0,0,0,0,0,0,0,0,0,0,0,~
0)';OUT;
    'DDR2_ODT'<1>:'(0,0,0,0,AA48,0,0,0,0,0,0,0,0,0,0,0,0,0,0,0,0,0,0,0,0,0,0,0,0~
,0)';OUT;
    'DDR2_ODT'<0>:'(0,0,0,0,AA50,0,0,0,0,0,0,0,0,0,0,0,0,0,0,0,0,0,0,0,0,0,0,0,0~
,0)';OUT;
    'DDR2_PAR':'(0,0,0,0,V53,0,0,0,0,0,0,0,0,0,0,0,0,0,0,0,0,0,0,0,0,0,0,0,0,0)';$S;OUT;
    'DDR345_DRAM_PWR_OK':'(CR28,0,0,0,0,0,0,0,0,0,0,0,0,0,0,0,0,0,0,0,0,0,0,0,0,~
0,0,0,0,0)';$S;IN;
    'DDR345_RCOMP'<2>:'(DD49,0,0,0,0,0,0,0,0,0,0,0,0,0,0,0,0,0,0,0,0,0,0,0,0,0,0~
,0,0,0)';BIDI;
    'DDR345_RCOMP'<1>:'(DD47,0,0,0,0,0,0,0,0,0,0,0,0,0,0,0,0,0,0,0,0,0,0,0,0,0,0~
,0,0,0)';BIDI;
    'DDR345_RCOMP'<0>:'(DC48,0,0,0,0,0,0,0,0,0,0,0,0,0,0,0,0,0,0,0,0,0,0,0,0,0,0~
,0,0,0)';BIDI;
    'DDR345_RESET_N':'(DV63,0,0,0,0,0,0,0,0,0,0,0,0,0,0,0,0,0,0,0,0,0,0,0,0,0,0,~
0,0,0)';$S;OUT;
    'DDR345_SPDSCL':'(AE18,0,0,0,0,0,0,0,0,0,0,0,0,0,0,0,0,0,0,0,0,0,0,0,0,0,0,0~
,0,0)';$S;BIDI;
    'DDR345_SPDSDA':'(AD17,0,0,0,0,0,0,0,0,0,0,0,0,0,0,0,0,0,0,0,0,0,0,0,0,0,0,0~
,0,0)';$S;BIDI;
    'DDR3_ACT_N':'(0,0,0,0,0,DW60,0,0,0,0,0,0,0,0,0,0,0,0,0,0,0,0,0,0,0,0,0,0,0,~
0)';$S;OUT;
    'DDR3_ALERT_N':'(0,0,0,0,0,ED63,0,0,0,0,0,0,0,0,0,0,0,0,0,0,0,0,0,0,0,0,0,0,~
0,0)';$S;IN;
    'DDR3_BA'<1>:'(0,0,0,0,0,EA54,0,0,0,0,0,0,0,0,0,0,0,0,0,0,0,0,0,0,0,0,0,0,0,~
0)';OUT;
    'DDR3_BA'<0>:'(0,0,0,0,0,EE52,0,0,0,0,0,0,0,0,0,0,0,0,0,0,0,0,0,0,0,0,0,0,0,~
0)';OUT;
    'DDR3_BG'<1>:'(0,0,0,0,0,DW62,0,0,0,0,0,0,0,0,0,0,0,0,0,0,0,0,0,0,0,0,0,0,0,~
0)';OUT;
    'DDR3_BG'<0>:'(0,0,0,0,0,ED61,0,0,0,0,0,0,0,0,0,0,0,0,0,0,0,0,0,0,0,0,0,0,0,~
0)';OUT;
    'DDR3_CAVREF':'(CP61,0,0,0,0,0,0,0,0,0,0,0,0,0,0,0,0,0,0,0,0,0,0,0,0,0,0,0,0~
,0)';$S;OUT;
    'DDR3_CID'<2>:'(0,0,0,0,0,DV47,0,0,0,0,0,0,0,0,0,0,0,0,0,0,0,0,0,0,0,0,0,0,0~
,0)';$S;OUT;
    'DDR3_CKE'<3>:'(0,0,0,0,0,EB63,0,0,0,0,0,0,0,0,0,0,0,0,0,0,0,0,0,0,0,0,0,0,0~
,0)';OUT;
    'DDR3_CKE'<2>:'(0,0,0,0,0,EA62,0,0,0,0,0,0,0,0,0,0,0,0,0,0,0,0,0,0,0,0,0,0,0~
,0)';OUT;
    'DDR3_CKE'<1>:'(0,0,0,0,0,EF63,0,0,0,0,0,0,0,0,0,0,0,0,0,0,0,0,0,0,0,0,0,0,0~
,0)';OUT;
    'DDR3_CKE'<0>:'(0,0,0,0,0,EE62,0,0,0,0,0,0,0,0,0,0,0,0,0,0,0,0,0,0,0,0,0,0,0~
,0)';OUT;
    'DDR3_CLK_DN'<3>:'(0,0,0,0,0,EF57,0,0,0,0,0,0,0,0,0,0,0,0,0,0,0,0,0,0,0,0,0,~
0,0,0)';OUT;
    'DDR3_CLK_DN'<2>:'(0,0,0,0,0,DW56,0,0,0,0,0,0,0,0,0,0,0,0,0,0,0,0,0,0,0,0,0,~
0,0,0)';OUT;
    'DDR3_CLK_DN'<1>:'(0,0,0,0,0,EF55,0,0,0,0,0,0,0,0,0,0,0,0,0,0,0,0,0,0,0,0,0,~
0,0,0)';OUT;
    'DDR3_CLK_DN'<0>:'(0,0,0,0,0,ED55,0,0,0,0,0,0,0,0,0,0,0,0,0,0,0,0,0,0,0,0,0,~
0,0,0)';OUT;
    'DDR3_CLK_DP'<3>:'(0,0,0,0,0,EE56,0,0,0,0,0,0,0,0,0,0,0,0,0,0,0,0,0,0,0,0,0,~
0,0,0)';OUT;
    'DDR3_CLK_DP'<2>:'(0,0,0,0,0,EA56,0,0,0,0,0,0,0,0,0,0,0,0,0,0,0,0,0,0,0,0,0,~
0,0,0)';OUT;
    'DDR3_CLK_DP'<1>:'(0,0,0,0,0,EE54,0,0,0,0,0,0,0,0,0,0,0,0,0,0,0,0,0,0,0,0,0,~
0,0,0)';OUT;
    'DDR3_CLK_DP'<0>:'(0,0,0,0,0,EB55,0,0,0,0,0,0,0,0,0,0,0,0,0,0,0,0,0,0,0,0,0,~
0,0,0)';OUT;
    'DDR3_CS_N'<7>:'(0,0,0,0,0,EB45,0,0,0,0,0,0,0,0,0,0,0,0,0,0,0,0,0,0,0,0,0,0,~
0,0)';OUT;
    'DDR3_CS_N'<6>:'(0,0,0,0,0,DV45,0,0,0,0,0,0,0,0,0,0,0,0,0,0,0,0,0,0,0,0,0,0,~
0,0)';OUT;
    'DDR3_CS_N'<5>:'(0,0,0,0,0,EB49,0,0,0,0,0,0,0,0,0,0,0,0,0,0,0,0,0,0,0,0,0,0,~
0,0)';OUT;
    'DDR3_CS_N'<4>:'(0,0,0,0,0,EB51,0,0,0,0,0,0,0,0,0,0,0,0,0,0,0,0,0,0,0,0,0,0,~
0,0)';OUT;
    'DDR3_CS_N'<3>:'(0,0,0,0,0,EB47,0,0,0,0,0,0,0,0,0,0,0,0,0,0,0,0,0,0,0,0,0,0,~
0,0)';OUT;
    'DDR3_CS_N'<2>:'(0,0,0,0,0,ED47,0,0,0,0,0,0,0,0,0,0,0,0,0,0,0,0,0,0,0,0,0,0,~
0,0)';OUT;
    'DDR3_CS_N'<1>:'(0,0,0,0,0,ED49,0,0,0,0,0,0,0,0,0,0,0,0,0,0,0,0,0,0,0,0,0,0,~
0,0)';OUT;
    'DDR3_CS_N'<0>:'(0,0,0,0,0,EF51,0,0,0,0,0,0,0,0,0,0,0,0,0,0,0,0,0,0,0,0,0,0,~
0,0)';OUT;
    'DDR3_DQ'<63>:'(0,0,0,0,0,DW22,0,0,0,0,0,0,0,0,0,0,0,0,0,0,0,0,0,0,0,0,0,0,0~
,0)';BIDI;
    'DDR3_DQ'<62>:'(0,0,0,0,0,EC22,0,0,0,0,0,0,0,0,0,0,0,0,0,0,0,0,0,0,0,0,0,0,0~
,0)';BIDI;
    'DDR3_DQ'<61>:'(0,0,0,0,0,DT25,0,0,0,0,0,0,0,0,0,0,0,0,0,0,0,0,0,0,0,0,0,0,0~
,0)';BIDI;
    'DDR3_DQ'<60>:'(0,0,0,0,0,DP25,0,0,0,0,0,0,0,0,0,0,0,0,0,0,0,0,0,0,0,0,0,0,0~
,0)';BIDI;
    'DDR3_DQ'<59>:'(0,0,0,0,0,EB21,0,0,0,0,0,0,0,0,0,0,0,0,0,0,0,0,0,0,0,0,0,0,0~
,0)';BIDI;
    'DDR3_DQ'<58>:'(0,0,0,0,0,DY21,0,0,0,0,0,0,0,0,0,0,0,0,0,0,0,0,0,0,0,0,0,0,0~
,0)';BIDI;
    'DDR3_DQ'<57>:'(0,0,0,0,0,DU24,0,0,0,0,0,0,0,0,0,0,0,0,0,0,0,0,0,0,0,0,0,0,0~
,0)';BIDI;
    'DDR3_DQ'<56>:'(0,0,0,0,0,DN24,0,0,0,0,0,0,0,0,0,0,0,0,0,0,0,0,0,0,0,0,0,0,0~
,0)';BIDI;
    'DDR3_DQ'<55>:'(0,0,0,0,0,DU28,0,0,0,0,0,0,0,0,0,0,0,0,0,0,0,0,0,0,0,0,0,0,0~
,0)';BIDI;
    'DDR3_DQ'<54>:'(0,0,0,0,0,DN28,0,0,0,0,0,0,0,0,0,0,0,0,0,0,0,0,0,0,0,0,0,0,0~
,0)';BIDI;
    'DDR3_DQ'<53>:'(0,0,0,0,0,DT31,0,0,0,0,0,0,0,0,0,0,0,0,0,0,0,0,0,0,0,0,0,0,0~
,0)';BIDI;
    'DDR3_DQ'<52>:'(0,0,0,0,0,DP31,0,0,0,0,0,0,0,0,0,0,0,0,0,0,0,0,0,0,0,0,0,0,0~
,0)';BIDI;
    'DDR3_DQ'<51>:'(0,0,0,0,0,DT27,0,0,0,0,0,0,0,0,0,0,0,0,0,0,0,0,0,0,0,0,0,0,0~
,0)';BIDI;
    'DDR3_DQ'<50>:'(0,0,0,0,0,DP27,0,0,0,0,0,0,0,0,0,0,0,0,0,0,0,0,0,0,0,0,0,0,0~
,0)';BIDI;
    'DDR3_DQ'<49>:'(0,0,0,0,0,DU30,0,0,0,0,0,0,0,0,0,0,0,0,0,0,0,0,0,0,0,0,0,0,0~
,0)';BIDI;
    'DDR3_DQ'<48>:'(0,0,0,0,0,DN30,0,0,0,0,0,0,0,0,0,0,0,0,0,0,0,0,0,0,0,0,0,0,0~
,0)';BIDI;
    'DDR3_DQ'<47>:'(0,0,0,0,0,DU34,0,0,0,0,0,0,0,0,0,0,0,0,0,0,0,0,0,0,0,0,0,0,0~
,0)';BIDI;
    'DDR3_DQ'<46>:'(0,0,0,0,0,DN34,0,0,0,0,0,0,0,0,0,0,0,0,0,0,0,0,0,0,0,0,0,0,0~
,0)';BIDI;
    'DDR3_DQ'<45>:'(0,0,0,0,0,DT37,0,0,0,0,0,0,0,0,0,0,0,0,0,0,0,0,0,0,0,0,0,0,0~
,0)';BIDI;
    'DDR3_DQ'<44>:'(0,0,0,0,0,DP37,0,0,0,0,0,0,0,0,0,0,0,0,0,0,0,0,0,0,0,0,0,0,0~
,0)';BIDI;
    'DDR3_DQ'<43>:'(0,0,0,0,0,DT33,0,0,0,0,0,0,0,0,0,0,0,0,0,0,0,0,0,0,0,0,0,0,0~
,0)';BIDI;
    'DDR3_DQ'<42>:'(0,0,0,0,0,DP33,0,0,0,0,0,0,0,0,0,0,0,0,0,0,0,0,0,0,0,0,0,0,0~
,0)';BIDI;
    'DDR3_DQ'<41>:'(0,0,0,0,0,DU36,0,0,0,0,0,0,0,0,0,0,0,0,0,0,0,0,0,0,0,0,0,0,0~
,0)';BIDI;
    'DDR3_DQ'<40>:'(0,0,0,0,0,DN36,0,0,0,0,0,0,0,0,0,0,0,0,0,0,0,0,0,0,0,0,0,0,0~
,0)';BIDI;
    'DDR3_DQ'<39>:'(0,0,0,0,0,ED37,0,0,0,0,0,0,0,0,0,0,0,0,0,0,0,0,0,0,0,0,0,0,0~
,0)';BIDI;
    'DDR3_DQ'<38>:'(0,0,0,0,0,DY37,0,0,0,0,0,0,0,0,0,0,0,0,0,0,0,0,0,0,0,0,0,0,0~
,0)';BIDI;
    'DDR3_DQ'<37>:'(0,0,0,0,0,EA40,0,0,0,0,0,0,0,0,0,0,0,0,0,0,0,0,0,0,0,0,0,0,0~
,0)';BIDI;
    'DDR3_DQ'<36>:'(0,0,0,0,0,DY39,0,0,0,0,0,0,0,0,0,0,0,0,0,0,0,0,0,0,0,0,0,0,0~
,0)';BIDI;
    'DDR3_DQ'<35>:'(0,0,0,0,0,EC36,0,0,0,0,0,0,0,0,0,0,0,0,0,0,0,0,0,0,0,0,0,0,0~
,0)';BIDI;
    'DDR3_DQ'<34>:'(0,0,0,0,0,EA36,0,0,0,0,0,0,0,0,0,0,0,0,0,0,0,0,0,0,0,0,0,0,0~
,0)';BIDI;
    'DDR3_DQ'<33>:'(0,0,0,0,0,ED39,0,0,0,0,0,0,0,0,0,0,0,0,0,0,0,0,0,0,0,0,0,0,0~
,0)';BIDI;
    'DDR3_DQ'<32>:'(0,0,0,0,0,EC40,0,0,0,0,0,0,0,0,0,0,0,0,0,0,0,0,0,0,0,0,0,0,0~
,0)';BIDI;
    'DDR3_DQ'<31>:'(0,0,0,0,0,DU74,0,0,0,0,0,0,0,0,0,0,0,0,0,0,0,0,0,0,0,0,0,0,0~
,0)';BIDI;
    'DDR3_DQ'<30>:'(0,0,0,0,0,DN74,0,0,0,0,0,0,0,0,0,0,0,0,0,0,0,0,0,0,0,0,0,0,0~
,0)';BIDI;
    'DDR3_DQ'<29>:'(0,0,0,0,0,DT77,0,0,0,0,0,0,0,0,0,0,0,0,0,0,0,0,0,0,0,0,0,0,0~
,0)';BIDI;
    'DDR3_DQ'<28>:'(0,0,0,0,0,DP77,0,0,0,0,0,0,0,0,0,0,0,0,0,0,0,0,0,0,0,0,0,0,0~
,0)';BIDI;
    'DDR3_DQ'<27>:'(0,0,0,0,0,DT73,0,0,0,0,0,0,0,0,0,0,0,0,0,0,0,0,0,0,0,0,0,0,0~
,0)';BIDI;
    'DDR3_DQ'<26>:'(0,0,0,0,0,DP73,0,0,0,0,0,0,0,0,0,0,0,0,0,0,0,0,0,0,0,0,0,0,0~
,0)';BIDI;
    'DDR3_DQ'<25>:'(0,0,0,0,0,DU76,0,0,0,0,0,0,0,0,0,0,0,0,0,0,0,0,0,0,0,0,0,0,0~
,0)';BIDI;
    'DDR3_DQ'<24>:'(0,0,0,0,0,DN76,0,0,0,0,0,0,0,0,0,0,0,0,0,0,0,0,0,0,0,0,0,0,0~
,0)';BIDI;
    'DDR3_DQ'<23>:'(0,0,0,0,0,DN82,0,0,0,0,0,0,0,0,0,0,0,0,0,0,0,0,0,0,0,0,0,0,0~
,0)';BIDI;
    'DDR3_DQ'<22>:'(0,0,0,0,0,DR80,0,0,0,0,0,0,0,0,0,0,0,0,0,0,0,0,0,0,0,0,0,0,0~
,0)';BIDI;
    'DDR3_DQ'<21>:'(0,0,0,0,0,DJ80,0,0,0,0,0,0,0,0,0,0,0,0,0,0,0,0,0,0,0,0,0,0,0~
,0)';BIDI;
    'DDR3_DQ'<20>:'(0,0,0,0,0,DK79,0,0,0,0,0,0,0,0,0,0,0,0,0,0,0,0,0,0,0,0,0,0,0~
,0)';BIDI;
    'DDR3_DQ'<19>:'(0,0,0,0,0,DR82,0,0,0,0,0,0,0,0,0,0,0,0,0,0,0,0,0,0,0,0,0,0,0~
,0)';BIDI;
    'DDR3_DQ'<18>:'(0,0,0,0,0,DT81,0,0,0,0,0,0,0,0,0,0,0,0,0,0,0,0,0,0,0,0,0,0,0~
,0)';BIDI;
    'DDR3_DQ'<17>:'(0,0,0,0,0,DK81,0,0,0,0,0,0,0,0,0,0,0,0,0,0,0,0,0,0,0,0,0,0,0~
,0)';BIDI;
    'DDR3_DQ'<16>:'(0,0,0,0,0,DM79,0,0,0,0,0,0,0,0,0,0,0,0,0,0,0,0,0,0,0,0,0,0,0~
,0)';BIDI;
    'DDR3_DQ'<15>:'(0,0,0,0,0,DV85,0,0,0,0,0,0,0,0,0,0,0,0,0,0,0,0,0,0,0,0,0,0,0~
,0)';BIDI;
    'DDR3_DQ'<14>:'(0,0,0,0,0,DR84,0,0,0,0,0,0,0,0,0,0,0,0,0,0,0,0,0,0,0,0,0,0,0~
,0)';BIDI;
    'DDR3_DQ'<13>:'(0,0,0,0,0,DE84,0,0,0,0,0,0,0,0,0,0,0,0,0,0,0,0,0,0,0,0,0,0,0~
,0)';BIDI;
    'DDR3_DQ'<12>:'(0,0,0,0,0,DD85,0,0,0,0,0,0,0,0,0,0,0,0,0,0,0,0,0,0,0,0,0,0,0~
,0)';BIDI;
    'DDR3_DQ'<11>:'(0,0,0,0,0,DY83,0,0,0,0,0,0,0,0,0,0,0,0,0,0,0,0,0,0,0,0,0,0,0~
,0)';BIDI;
    'DDR3_DQ'<10>:'(0,0,0,0,0,DV83,0,0,0,0,0,0,0,0,0,0,0,0,0,0,0,0,0,0,0,0,0,0,0~
,0)';BIDI;
    'DDR3_DQ'<9>:'(0,0,0,0,0,DH85,0,0,0,0,0,0,0,0,0,0,0,0,0,0,0,0,0,0,0,0,0,0,0,~
0)';BIDI;
    'DDR3_DQ'<8>:'(0,0,0,0,0,DG84,0,0,0,0,0,0,0,0,0,0,0,0,0,0,0,0,0,0,0,0,0,0,0,~
0)';BIDI;
    'DDR3_DQ'<7>:'(0,0,0,0,0,CW84,0,0,0,0,0,0,0,0,0,0,0,0,0,0,0,0,0,0,0,0,0,0,0,~
0)';BIDI;
    'DDR3_DQ'<6>:'(0,0,0,0,0,CW86,0,0,0,0,0,0,0,0,0,0,0,0,0,0,0,0,0,0,0,0,0,0,0,~
0)';BIDI;
    'DDR3_DQ'<5>:'(0,0,0,0,0,CL86,0,0,0,0,0,0,0,0,0,0,0,0,0,0,0,0,0,0,0,0,0,0,0,~
0)';BIDI;
    'DDR3_DQ'<4>:'(0,0,0,0,0,CL84,0,0,0,0,0,0,0,0,0,0,0,0,0,0,0,0,0,0,0,0,0,0,0,~
0)';BIDI;
    'DDR3_DQ'<3>:'(0,0,0,0,0,DA84,0,0,0,0,0,0,0,0,0,0,0,0,0,0,0,0,0,0,0,0,0,0,0,~
0)';BIDI;
    'DDR3_DQ'<2>:'(0,0,0,0,0,DA86,0,0,0,0,0,0,0,0,0,0,0,0,0,0,0,0,0,0,0,0,0,0,0,~
0)';BIDI;
    'DDR3_DQ'<1>:'(0,0,0,0,0,CN86,0,0,0,0,0,0,0,0,0,0,0,0,0,0,0,0,0,0,0,0,0,0,0,~
0)';BIDI;
    'DDR3_DQ'<0>:'(0,0,0,0,0,CN84,0,0,0,0,0,0,0,0,0,0,0,0,0,0,0,0,0,0,0,0,0,0,0,~
0)';BIDI;
    'DDR3_DQS_DN'<17>:'(0,0,0,0,0,DB67,0,0,0,0,0,0,0,0,0,0,0,0,0,0,0,0,0,0,0,0,0~
,0,0,0)';BIDI;
    'DDR3_DQS_DN'<16>:'(0,0,0,0,0,DM23,0,0,0,0,0,0,0,0,0,0,0,0,0,0,0,0,0,0,0,0,0~
,0,0,0)';BIDI;
    'DDR3_DQS_DN'<15>:'(0,0,0,0,0,DM29,0,0,0,0,0,0,0,0,0,0,0,0,0,0,0,0,0,0,0,0,0~
,0,0,0)';BIDI;
    'DDR3_DQS_DN'<14>:'(0,0,0,0,0,DP35,0,0,0,0,0,0,0,0,0,0,0,0,0,0,0,0,0,0,0,0,0~
,0,0,0)';BIDI;
    'DDR3_DQS_DN'<13>:'(0,0,0,0,0,EA38,0,0,0,0,0,0,0,0,0,0,0,0,0,0,0,0,0,0,0,0,0~
,0,0,0)';BIDI;
    'DDR3_DQS_DN'<12>:'(0,0,0,0,0,DP75,0,0,0,0,0,0,0,0,0,0,0,0,0,0,0,0,0,0,0,0,0~
,0,0,0)';BIDI;
    'DDR3_DQS_DN'<11>:'(0,0,0,0,0,DN80,0,0,0,0,0,0,0,0,0,0,0,0,0,0,0,0,0,0,0,0,0~
,0,0,0)';BIDI;
    'DDR3_DQS_DN'<10>:'(0,0,0,0,0,DM85,0,0,0,0,0,0,0,0,0,0,0,0,0,0,0,0,0,0,0,0,0~
,0,0,0)';BIDI;
    'DDR3_DQS_DN'<9>:'(0,0,0,0,0,CR84,0,0,0,0,0,0,0,0,0,0,0,0,0,0,0,0,0,0,0,0,0,~
0,0,0)';BIDI;
    'DDR3_DQS_DN'<8>:'(0,0,0,0,0,DF67,0,0,0,0,0,0,0,0,0,0,0,0,0,0,0,0,0,0,0,0,0,~
0,0,0)';BIDI;
    'DDR3_DQS_DN'<7>:'(0,0,0,0,0,DV23,0,0,0,0,0,0,0,0,0,0,0,0,0,0,0,0,0,0,0,0,0,~
0,0,0)';BIDI;
    'DDR3_DQS_DN'<6>:'(0,0,0,0,0,DV29,0,0,0,0,0,0,0,0,0,0,0,0,0,0,0,0,0,0,0,0,0,~
0,0,0)';BIDI;
    'DDR3_DQS_DN'<5>:'(0,0,0,0,0,DV35,0,0,0,0,0,0,0,0,0,0,0,0,0,0,0,0,0,0,0,0,0,~
0,0,0)';BIDI;
    'DDR3_DQS_DN'<4>:'(0,0,0,0,0,EE38,0,0,0,0,0,0,0,0,0,0,0,0,0,0,0,0,0,0,0,0,0,~
0,0,0)';BIDI;
    'DDR3_DQS_DN'<3>:'(0,0,0,0,0,DV75,0,0,0,0,0,0,0,0,0,0,0,0,0,0,0,0,0,0,0,0,0,~
0,0,0)';BIDI;
    'DDR3_DQS_DN'<2>:'(0,0,0,0,0,DL82,0,0,0,0,0,0,0,0,0,0,0,0,0,0,0,0,0,0,0,0,0,~
0,0,0)';BIDI;
    'DDR3_DQS_DN'<1>:'(0,0,0,0,0,DN84,0,0,0,0,0,0,0,0,0,0,0,0,0,0,0,0,0,0,0,0,0,~
0,0,0)';BIDI;
    'DDR3_DQS_DN'<0>:'(0,0,0,0,0,CU84,0,0,0,0,0,0,0,0,0,0,0,0,0,0,0,0,0,0,0,0,0,~
0,0,0)';BIDI;
    'DDR3_DQS_DP'<17>:'(0,0,0,0,0,CY67,0,0,0,0,0,0,0,0,0,0,0,0,0,0,0,0,0,0,0,0,0~
,0,0,0)';BIDI;
    'DDR3_DQS_DP'<16>:'(0,0,0,0,0,DP23,0,0,0,0,0,0,0,0,0,0,0,0,0,0,0,0,0,0,0,0,0~
,0,0,0)';BIDI;
    'DDR3_DQS_DP'<15>:'(0,0,0,0,0,DP29,0,0,0,0,0,0,0,0,0,0,0,0,0,0,0,0,0,0,0,0,0~
,0,0,0)';BIDI;
    'DDR3_DQS_DP'<14>:'(0,0,0,0,0,DM35,0,0,0,0,0,0,0,0,0,0,0,0,0,0,0,0,0,0,0,0,0~
,0,0,0)';BIDI;
    'DDR3_DQS_DP'<13>:'(0,0,0,0,0,DW38,0,0,0,0,0,0,0,0,0,0,0,0,0,0,0,0,0,0,0,0,0~
,0,0,0)';BIDI;
    'DDR3_DQS_DP'<12>:'(0,0,0,0,0,DM75,0,0,0,0,0,0,0,0,0,0,0,0,0,0,0,0,0,0,0,0,0~
,0,0,0)';BIDI;
    'DDR3_DQS_DP'<11>:'(0,0,0,0,0,DP79,0,0,0,0,0,0,0,0,0,0,0,0,0,0,0,0,0,0,0,0,0~
,0,0,0)';BIDI;
    'DDR3_DQS_DP'<10>:'(0,0,0,0,0,DL84,0,0,0,0,0,0,0,0,0,0,0,0,0,0,0,0,0,0,0,0,0~
,0,0,0)';BIDI;
    'DDR3_DQS_DP'<9>:'(0,0,0,0,0,CP85,0,0,0,0,0,0,0,0,0,0,0,0,0,0,0,0,0,0,0,0,0,~
0,0,0)';BIDI;
    'DDR3_DQS_DP'<8>:'(0,0,0,0,0,DD67,0,0,0,0,0,0,0,0,0,0,0,0,0,0,0,0,0,0,0,0,0,~
0,0,0)';BIDI;
    'DDR3_DQS_DP'<7>:'(0,0,0,0,0,DT23,0,0,0,0,0,0,0,0,0,0,0,0,0,0,0,0,0,0,0,0,0,~
0,0,0)';BIDI;
    'DDR3_DQS_DP'<6>:'(0,0,0,0,0,DT29,0,0,0,0,0,0,0,0,0,0,0,0,0,0,0,0,0,0,0,0,0,~
0,0,0)';BIDI;
    'DDR3_DQS_DP'<5>:'(0,0,0,0,0,DT35,0,0,0,0,0,0,0,0,0,0,0,0,0,0,0,0,0,0,0,0,0,~
0,0,0)';BIDI;
    'DDR3_DQS_DP'<4>:'(0,0,0,0,0,EC38,0,0,0,0,0,0,0,0,0,0,0,0,0,0,0,0,0,0,0,0,0,~
0,0,0)';BIDI;
    'DDR3_DQS_DP'<3>:'(0,0,0,0,0,DT75,0,0,0,0,0,0,0,0,0,0,0,0,0,0,0,0,0,0,0,0,0,~
0,0,0)';BIDI;
    'DDR3_DQS_DP'<2>:'(0,0,0,0,0,DM81,0,0,0,0,0,0,0,0,0,0,0,0,0,0,0,0,0,0,0,0,0,~
0,0,0)';BIDI;
    'DDR3_DQS_DP'<1>:'(0,0,0,0,0,DP85,0,0,0,0,0,0,0,0,0,0,0,0,0,0,0,0,0,0,0,0,0,~
0,0,0)';BIDI;
    'DDR3_DQS_DP'<0>:'(0,0,0,0,0,CV85,0,0,0,0,0,0,0,0,0,0,0,0,0,0,0,0,0,0,0,0,0,~
0,0,0)';BIDI;
    'DDR3_ECC'<7>:'(0,0,0,0,0,DE66,0,0,0,0,0,0,0,0,0,0,0,0,0,0,0,0,0,0,0,0,0,0,0~
,0)';BIDI;
    'DDR3_ECC'<6>:'(0,0,0,0,0,DA66,0,0,0,0,0,0,0,0,0,0,0,0,0,0,0,0,0,0,0,0,0,0,0~
,0)';BIDI;
    'DDR3_ECC'<5>:'(0,0,0,0,0,DD69,0,0,0,0,0,0,0,0,0,0,0,0,0,0,0,0,0,0,0,0,0,0,0~
,0)';BIDI;
    'DDR3_ECC'<4>:'(0,0,0,0,0,DB69,0,0,0,0,0,0,0,0,0,0,0,0,0,0,0,0,0,0,0,0,0,0,0~
,0)';BIDI;
    'DDR3_ECC'<3>:'(0,0,0,0,0,DD65,0,0,0,0,0,0,0,0,0,0,0,0,0,0,0,0,0,0,0,0,0,0,0~
,0)';BIDI;
    'DDR3_ECC'<2>:'(0,0,0,0,0,DB65,0,0,0,0,0,0,0,0,0,0,0,0,0,0,0,0,0,0,0,0,0,0,0~
,0)';BIDI;
    'DDR3_ECC'<1>:'(0,0,0,0,0,DE68,0,0,0,0,0,0,0,0,0,0,0,0,0,0,0,0,0,0,0,0,0,0,0~
,0)';BIDI;
    'DDR3_ECC'<0>:'(0,0,0,0,0,DA68,0,0,0,0,0,0,0,0,0,0,0,0,0,0,0,0,0,0,0,0,0,0,0~
,0)';BIDI;
    'DDR3_MA'<17>:'(0,0,0,0,0,EA46,0,0,0,0,0,0,0,0,0,0,0,0,0,0,0,0,0,0,0,0,0,0,0~
,0)';OUT;
    'DDR3_MA'<16>:'(0,0,0,0,0,EA52,0,0,0,0,0,0,0,0,0,0,0,0,0,0,0,0,0,0,0,0,0,0,0~
,0)';OUT;
    'DDR3_MA'<15>:'(0,0,0,0,0,DV49,0,0,0,0,0,0,0,0,0,0,0,0,0,0,0,0,0,0,0,0,0,0,0~
,0)';OUT;
    'DDR3_MA'<14>:'(0,0,0,0,0,ED51,0,0,0,0,0,0,0,0,0,0,0,0,0,0,0,0,0,0,0,0,0,0,0~
,0)';OUT;
    'DDR3_MA'<13>:'(0,0,0,0,0,DW48,0,0,0,0,0,0,0,0,0,0,0,0,0,0,0,0,0,0,0,0,0,0,0~
,0)';OUT;
    'DDR3_MA'<12>:'(0,0,0,0,0,DT63,0,0,0,0,0,0,0,0,0,0,0,0,0,0,0,0,0,0,0,0,0,0,0~
,0)';OUT;
    'DDR3_MA'<11>:'(0,0,0,0,0,EB61,0,0,0,0,0,0,0,0,0,0,0,0,0,0,0,0,0,0,0,0,0,0,0~
,0)';OUT;
    'DDR3_MA'<10>:'(0,0,0,0,0,DW54,0,0,0,0,0,0,0,0,0,0,0,0,0,0,0,0,0,0,0,0,0,0,0~
,0)';OUT;
    'DDR3_MA'<9>:'(0,0,0,0,0,EF61,0,0,0,0,0,0,0,0,0,0,0,0,0,0,0,0,0,0,0,0,0,0,0,~
0)';OUT;
    'DDR3_MA'<8>:'(0,0,0,0,0,EB59,0,0,0,0,0,0,0,0,0,0,0,0,0,0,0,0,0,0,0,0,0,0,0,~
0)';OUT;
    'DDR3_MA'<7>:'(0,0,0,0,0,EA60,0,0,0,0,0,0,0,0,0,0,0,0,0,0,0,0,0,0,0,0,0,0,0,~
0)';OUT;
    'DDR3_MA'<6>:'(0,0,0,0,0,EE60,0,0,0,0,0,0,0,0,0,0,0,0,0,0,0,0,0,0,0,0,0,0,0,~
0)';OUT;
    'DDR3_MA'<5>:'(0,0,0,0,0,EA58,0,0,0,0,0,0,0,0,0,0,0,0,0,0,0,0,0,0,0,0,0,0,0,~
0)';OUT;
    'DDR3_MA'<4>:'(0,0,0,0,0,ED59,0,0,0,0,0,0,0,0,0,0,0,0,0,0,0,0,0,0,0,0,0,0,0,~
0)';OUT;
    'DDR3_MA'<3>:'(0,0,0,0,0,EB57,0,0,0,0,0,0,0,0,0,0,0,0,0,0,0,0,0,0,0,0,0,0,0,~
0)';OUT;
    'DDR3_MA'<2>:'(0,0,0,0,0,EE58,0,0,0,0,0,0,0,0,0,0,0,0,0,0,0,0,0,0,0,0,0,0,0,~
0)';OUT;
    'DDR3_MA'<1>:'(0,0,0,0,0,ED57,0,0,0,0,0,0,0,0,0,0,0,0,0,0,0,0,0,0,0,0,0,0,0,~
0)';OUT;
    'DDR3_MA'<0>:'(0,0,0,0,0,EB53,0,0,0,0,0,0,0,0,0,0,0,0,0,0,0,0,0,0,0,0,0,0,0,~
0)';OUT;
    'DDR3_ODT'<3>:'(0,0,0,0,0,EA48,0,0,0,0,0,0,0,0,0,0,0,0,0,0,0,0,0,0,0,0,0,0,0~
,0)';OUT;
    'DDR3_ODT'<2>:'(0,0,0,0,0,EA50,0,0,0,0,0,0,0,0,0,0,0,0,0,0,0,0,0,0,0,0,0,0,0~
,0)';OUT;
    'DDR3_ODT'<1>:'(0,0,0,0,0,EE48,0,0,0,0,0,0,0,0,0,0,0,0,0,0,0,0,0,0,0,0,0,0,0~
,0)';OUT;
    'DDR3_ODT'<0>:'(0,0,0,0,0,EE50,0,0,0,0,0,0,0,0,0,0,0,0,0,0,0,0,0,0,0,0,0,0,0~
,0)';OUT;
    'DDR3_PAR':'(0,0,0,0,0,ED53,0,0,0,0,0,0,0,0,0,0,0,0,0,0,0,0,0,0,0,0,0,0,0,0)~
';$S;OUT;
    'DDR4_ACT_N':'(0,0,0,0,0,0,DR62,0,0,0,0,0,0,0,0,0,0,0,0,0,0,0,0,0,0,0,0,0,0,~
0)';$S;OUT;
    'DDR4_ALERT_N':'(0,0,0,0,0,0,DT61,0,0,0,0,0,0,0,0,0,0,0,0,0,0,0,0,0,0,0,0,0,~
0,0)';$S;IN;
    'DDR4_BA'<1>:'(0,0,0,0,0,0,DV55,0,0,0,0,0,0,0,0,0,0,0,0,0,0,0,0,0,0,0,0,0,0,~
0)';OUT;
    'DDR4_BA'<0>:'(0,0,0,0,0,0,DM53,0,0,0,0,0,0,0,0,0,0,0,0,0,0,0,0,0,0,0,0,0,0,~
0)';OUT;
    'DDR4_BG'<1>:'(0,0,0,0,0,0,DM61,0,0,0,0,0,0,0,0,0,0,0,0,0,0,0,0,0,0,0,0,0,0,~
0)';OUT;
    'DDR4_BG'<0>:'(0,0,0,0,0,0,DJ62,0,0,0,0,0,0,0,0,0,0,0,0,0,0,0,0,0,0,0,0,0,0,~
0)';OUT;
    'DDR4_CAVREF':'(CT61,0,0,0,0,0,0,0,0,0,0,0,0,0,0,0,0,0,0,0,0,0,0,0,0,0,0,0,0~
,0)';$S;OUT;
    'DDR4_CID'<2>:'(0,0,0,0,0,0,DT47,0,0,0,0,0,0,0,0,0,0,0,0,0,0,0,0,0,0,0,0,0,0~
,0)';$S;OUT;
    'DDR4_CKE'<3>:'(0,0,0,0,0,0,DR64,0,0,0,0,0,0,0,0,0,0,0,0,0,0,0,0,0,0,0,0,0,0~
,0)';OUT;
    'DDR4_CKE'<2>:'(0,0,0,0,0,0,DL64,0,0,0,0,0,0,0,0,0,0,0,0,0,0,0,0,0,0,0,0,0,0~
,0)';OUT;
    'DDR4_CKE'<1>:'(0,0,0,0,0,0,DN64,0,0,0,0,0,0,0,0,0,0,0,0,0,0,0,0,0,0,0,0,0,0~
,0)';OUT;
    'DDR4_CKE'<0>:'(0,0,0,0,0,0,DM63,0,0,0,0,0,0,0,0,0,0,0,0,0,0,0,0,0,0,0,0,0,0~
,0)';OUT;
    'DDR4_CLK_DN'<3>:'(0,0,0,0,0,0,DT57,0,0,0,0,0,0,0,0,0,0,0,0,0,0,0,0,0,0,0,0,~
0,0,0)';OUT;
    'DDR4_CLK_DN'<2>:'(0,0,0,0,0,0,DM57,0,0,0,0,0,0,0,0,0,0,0,0,0,0,0,0,0,0,0,0,~
0,0,0)';OUT;
    'DDR4_CLK_DN'<1>:'(0,0,0,0,0,0,DR54,0,0,0,0,0,0,0,0,0,0,0,0,0,0,0,0,0,0,0,0,~
0,0,0)';OUT;
    'DDR4_CLK_DN'<0>:'(0,0,0,0,0,0,DM55,0,0,0,0,0,0,0,0,0,0,0,0,0,0,0,0,0,0,0,0,~
0,0,0)';OUT;
    'DDR4_CLK_DP'<3>:'(0,0,0,0,0,0,DR56,0,0,0,0,0,0,0,0,0,0,0,0,0,0,0,0,0,0,0,0,~
0,0,0)';OUT;
    'DDR4_CLK_DP'<2>:'(0,0,0,0,0,0,DN56,0,0,0,0,0,0,0,0,0,0,0,0,0,0,0,0,0,0,0,0,~
0,0,0)';OUT;
    'DDR4_CLK_DP'<1>:'(0,0,0,0,0,0,DT53,0,0,0,0,0,0,0,0,0,0,0,0,0,0,0,0,0,0,0,0,~
0,0,0)';OUT;
    'DDR4_CLK_DP'<0>:'(0,0,0,0,0,0,DN54,0,0,0,0,0,0,0,0,0,0,0,0,0,0,0,0,0,0,0,0,~
0,0,0)';OUT;
    'DDR4_CS_N'<7>:'(0,0,0,0,0,0,DN46,0,0,0,0,0,0,0,0,0,0,0,0,0,0,0,0,0,0,0,0,0,~
0,0)';OUT;
    'DDR4_CS_N'<6>:'(0,0,0,0,0,0,DT45,0,0,0,0,0,0,0,0,0,0,0,0,0,0,0,0,0,0,0,0,0,~
0,0)';OUT;
    'DDR4_CS_N'<5>:'(0,0,0,0,0,0,DM49,0,0,0,0,0,0,0,0,0,0,0,0,0,0,0,0,0,0,0,0,0,~
0,0)';OUT;
    'DDR4_CS_N'<4>:'(0,0,0,0,0,0,DW50,0,0,0,0,0,0,0,0,0,0,0,0,0,0,0,0,0,0,0,0,0,~
0,0)';OUT;
    'DDR4_CS_N'<3>:'(0,0,0,0,0,0,DK47,0,0,0,0,0,0,0,0,0,0,0,0,0,0,0,0,0,0,0,0,0,~
0,0)';OUT;
    'DDR4_CS_N'<2>:'(0,0,0,0,0,0,DR46,0,0,0,0,0,0,0,0,0,0,0,0,0,0,0,0,0,0,0,0,0,~
0,0)';OUT;
    'DDR4_CS_N'<1>:'(0,0,0,0,0,0,DN50,0,0,0,0,0,0,0,0,0,0,0,0,0,0,0,0,0,0,0,0,0,~
0,0)';OUT;
    'DDR4_CS_N'<0>:'(0,0,0,0,0,0,DV51,0,0,0,0,0,0,0,0,0,0,0,0,0,0,0,0,0,0,0,0,0,~
0,0)';OUT;
    'DDR4_DQ'<63>:'(0,0,0,0,0,0,DK25,0,0,0,0,0,0,0,0,0,0,0,0,0,0,0,0,0,0,0,0,0,0~
,0)';BIDI;
    'DDR4_DQ'<62>:'(0,0,0,0,0,0,DF25,0,0,0,0,0,0,0,0,0,0,0,0,0,0,0,0,0,0,0,0,0,0~
,0)';BIDI;
    'DDR4_DQ'<61>:'(0,0,0,0,0,0,DJ28,0,0,0,0,0,0,0,0,0,0,0,0,0,0,0,0,0,0,0,0,0,0~
,0)';BIDI;
    'DDR4_DQ'<60>:'(0,0,0,0,0,0,DG28,0,0,0,0,0,0,0,0,0,0,0,0,0,0,0,0,0,0,0,0,0,0~
,0)';BIDI;
    'DDR4_DQ'<59>:'(0,0,0,0,0,0,DJ24,0,0,0,0,0,0,0,0,0,0,0,0,0,0,0,0,0,0,0,0,0,0~
,0)';BIDI;
    'DDR4_DQ'<58>:'(0,0,0,0,0,0,DD25,0,0,0,0,0,0,0,0,0,0,0,0,0,0,0,0,0,0,0,0,0,0~
,0)';BIDI;
    'DDR4_DQ'<57>:'(0,0,0,0,0,0,DK27,0,0,0,0,0,0,0,0,0,0,0,0,0,0,0,0,0,0,0,0,0,0~
,0)';BIDI;
    'DDR4_DQ'<56>:'(0,0,0,0,0,0,DF27,0,0,0,0,0,0,0,0,0,0,0,0,0,0,0,0,0,0,0,0,0,0~
,0)';BIDI;
    'DDR4_DQ'<55>:'(0,0,0,0,0,0,ED25,0,0,0,0,0,0,0,0,0,0,0,0,0,0,0,0,0,0,0,0,0,0~
,0)';BIDI;
    'DDR4_DQ'<54>:'(0,0,0,0,0,0,DY25,0,0,0,0,0,0,0,0,0,0,0,0,0,0,0,0,0,0,0,0,0,0~
,0)';BIDI;
    'DDR4_DQ'<53>:'(0,0,0,0,0,0,EA28,0,0,0,0,0,0,0,0,0,0,0,0,0,0,0,0,0,0,0,0,0,0~
,0)';BIDI;
    'DDR4_DQ'<52>:'(0,0,0,0,0,0,DY27,0,0,0,0,0,0,0,0,0,0,0,0,0,0,0,0,0,0,0,0,0,0~
,0)';BIDI;
    'DDR4_DQ'<51>:'(0,0,0,0,0,0,EC24,0,0,0,0,0,0,0,0,0,0,0,0,0,0,0,0,0,0,0,0,0,0~
,0)';BIDI;
    'DDR4_DQ'<50>:'(0,0,0,0,0,0,EA24,0,0,0,0,0,0,0,0,0,0,0,0,0,0,0,0,0,0,0,0,0,0~
,0)';BIDI;
    'DDR4_DQ'<49>:'(0,0,0,0,0,0,ED27,0,0,0,0,0,0,0,0,0,0,0,0,0,0,0,0,0,0,0,0,0,0~
,0)';BIDI;
    'DDR4_DQ'<48>:'(0,0,0,0,0,0,EC28,0,0,0,0,0,0,0,0,0,0,0,0,0,0,0,0,0,0,0,0,0,0~
,0)';BIDI;
    'DDR4_DQ'<47>:'(0,0,0,0,0,0,ED31,0,0,0,0,0,0,0,0,0,0,0,0,0,0,0,0,0,0,0,0,0,0~
,0)';BIDI;
    'DDR4_DQ'<46>:'(0,0,0,0,0,0,DY31,0,0,0,0,0,0,0,0,0,0,0,0,0,0,0,0,0,0,0,0,0,0~
,0)';BIDI;
    'DDR4_DQ'<45>:'(0,0,0,0,0,0,EA34,0,0,0,0,0,0,0,0,0,0,0,0,0,0,0,0,0,0,0,0,0,0~
,0)';BIDI;
    'DDR4_DQ'<44>:'(0,0,0,0,0,0,DY33,0,0,0,0,0,0,0,0,0,0,0,0,0,0,0,0,0,0,0,0,0,0~
,0)';BIDI;
    'DDR4_DQ'<43>:'(0,0,0,0,0,0,EC30,0,0,0,0,0,0,0,0,0,0,0,0,0,0,0,0,0,0,0,0,0,0~
,0)';BIDI;
    'DDR4_DQ'<42>:'(0,0,0,0,0,0,EA30,0,0,0,0,0,0,0,0,0,0,0,0,0,0,0,0,0,0,0,0,0,0~
,0)';BIDI;
    'DDR4_DQ'<41>:'(0,0,0,0,0,0,ED33,0,0,0,0,0,0,0,0,0,0,0,0,0,0,0,0,0,0,0,0,0,0~
,0)';BIDI;
    'DDR4_DQ'<40>:'(0,0,0,0,0,0,EC34,0,0,0,0,0,0,0,0,0,0,0,0,0,0,0,0,0,0,0,0,0,0~
,0)';BIDI;
    'DDR4_DQ'<39>:'(0,0,0,0,0,0,DU40,0,0,0,0,0,0,0,0,0,0,0,0,0,0,0,0,0,0,0,0,0,0~
,0)';BIDI;
    'DDR4_DQ'<38>:'(0,0,0,0,0,0,DN40,0,0,0,0,0,0,0,0,0,0,0,0,0,0,0,0,0,0,0,0,0,0~
,0)';BIDI;
    'DDR4_DQ'<37>:'(0,0,0,0,0,0,DN42,0,0,0,0,0,0,0,0,0,0,0,0,0,0,0,0,0,0,0,0,0,0~
,0)';BIDI;
    'DDR4_DQ'<36>:'(0,0,0,0,0,0,DL42,0,0,0,0,0,0,0,0,0,0,0,0,0,0,0,0,0,0,0,0,0,0~
,0)';BIDI;
    'DDR4_DQ'<35>:'(0,0,0,0,0,0,DT39,0,0,0,0,0,0,0,0,0,0,0,0,0,0,0,0,0,0,0,0,0,0~
,0)';BIDI;
    'DDR4_DQ'<34>:'(0,0,0,0,0,0,DP39,0,0,0,0,0,0,0,0,0,0,0,0,0,0,0,0,0,0,0,0,0,0~
,0)';BIDI;
    'DDR4_DQ'<33>:'(0,0,0,0,0,0,DW42,0,0,0,0,0,0,0,0,0,0,0,0,0,0,0,0,0,0,0,0,0,0~
,0)';BIDI;
    'DDR4_DQ'<32>:'(0,0,0,0,0,0,DU42,0,0,0,0,0,0,0,0,0,0,0,0,0,0,0,0,0,0,0,0,0,0~
,0)';BIDI;
    'DDR4_DQ'<31>:'(0,0,0,0,0,0,EE72,0,0,0,0,0,0,0,0,0,0,0,0,0,0,0,0,0,0,0,0,0,0~
,0)';BIDI;
    'DDR4_DQ'<30>:'(0,0,0,0,0,0,EA72,0,0,0,0,0,0,0,0,0,0,0,0,0,0,0,0,0,0,0,0,0,0~
,0)';BIDI;
    'DDR4_DQ'<29>:'(0,0,0,0,0,0,EB75,0,0,0,0,0,0,0,0,0,0,0,0,0,0,0,0,0,0,0,0,0,0~
,0)';BIDI;
    'DDR4_DQ'<28>:'(0,0,0,0,0,0,EA74,0,0,0,0,0,0,0,0,0,0,0,0,0,0,0,0,0,0,0,0,0,0~
,0)';BIDI;
    'DDR4_DQ'<27>:'(0,0,0,0,0,0,ED71,0,0,0,0,0,0,0,0,0,0,0,0,0,0,0,0,0,0,0,0,0,0~
,0)';BIDI;
    'DDR4_DQ'<26>:'(0,0,0,0,0,0,EB71,0,0,0,0,0,0,0,0,0,0,0,0,0,0,0,0,0,0,0,0,0,0~
,0)';BIDI;
    'DDR4_DQ'<25>:'(0,0,0,0,0,0,EE74,0,0,0,0,0,0,0,0,0,0,0,0,0,0,0,0,0,0,0,0,0,0~
,0)';BIDI;
    'DDR4_DQ'<24>:'(0,0,0,0,0,0,ED75,0,0,0,0,0,0,0,0,0,0,0,0,0,0,0,0,0,0,0,0,0,0~
,0)';BIDI;
    'DDR4_DQ'<23>:'(0,0,0,0,0,0,EC78,0,0,0,0,0,0,0,0,0,0,0,0,0,0,0,0,0,0,0,0,0,0~
,0)';BIDI;
    'DDR4_DQ'<22>:'(0,0,0,0,0,0,DW78,0,0,0,0,0,0,0,0,0,0,0,0,0,0,0,0,0,0,0,0,0,0~
,0)';BIDI;
    'DDR4_DQ'<21>:'(0,0,0,0,0,0,EB81,0,0,0,0,0,0,0,0,0,0,0,0,0,0,0,0,0,0,0,0,0,0~
,0)';BIDI;
    'DDR4_DQ'<20>:'(0,0,0,0,0,0,DY81,0,0,0,0,0,0,0,0,0,0,0,0,0,0,0,0,0,0,0,0,0,0~
,0)';BIDI;
    'DDR4_DQ'<19>:'(0,0,0,0,0,0,EB77,0,0,0,0,0,0,0,0,0,0,0,0,0,0,0,0,0,0,0,0,0,0~
,0)';BIDI;
    'DDR4_DQ'<18>:'(0,0,0,0,0,0,DY77,0,0,0,0,0,0,0,0,0,0,0,0,0,0,0,0,0,0,0,0,0,0~
,0)';BIDI;
    'DDR4_DQ'<17>:'(0,0,0,0,0,0,EC80,0,0,0,0,0,0,0,0,0,0,0,0,0,0,0,0,0,0,0,0,0,0~
,0)';BIDI;
    'DDR4_DQ'<16>:'(0,0,0,0,0,0,DW80,0,0,0,0,0,0,0,0,0,0,0,0,0,0,0,0,0,0,0,0,0,0~
,0)';BIDI;
    'DDR4_DQ'<15>:'(0,0,0,0,0,0,DE82,0,0,0,0,0,0,0,0,0,0,0,0,0,0,0,0,0,0,0,0,0,0~
,0)';BIDI;
    'DDR4_DQ'<14>:'(0,0,0,0,0,0,DC82,0,0,0,0,0,0,0,0,0,0,0,0,0,0,0,0,0,0,0,0,0,0~
,0)';BIDI;
    'DDR4_DQ'<13>:'(0,0,0,0,0,0,CW80,0,0,0,0,0,0,0,0,0,0,0,0,0,0,0,0,0,0,0,0,0,0~
,0)';BIDI;
    'DDR4_DQ'<12>:'(0,0,0,0,0,0,CY79,0,0,0,0,0,0,0,0,0,0,0,0,0,0,0,0,0,0,0,0,0,0~
,0)';BIDI;
    'DDR4_DQ'<11>:'(0,0,0,0,0,0,DF81,0,0,0,0,0,0,0,0,0,0,0,0,0,0,0,0,0,0,0,0,0,0~
,0)';BIDI;
    'DDR4_DQ'<10>:'(0,0,0,0,0,0,DE80,0,0,0,0,0,0,0,0,0,0,0,0,0,0,0,0,0,0,0,0,0,0~
,0)';BIDI;
    'DDR4_DQ'<9>:'(0,0,0,0,0,0,CY81,0,0,0,0,0,0,0,0,0,0,0,0,0,0,0,0,0,0,0,0,0,0,~
0)';BIDI;
    'DDR4_DQ'<8>:'(0,0,0,0,0,0,DB79,0,0,0,0,0,0,0,0,0,0,0,0,0,0,0,0,0,0,0,0,0,0,~
0)';BIDI;
    'DDR4_DQ'<7>:'(0,0,0,0,0,0,CN82,0,0,0,0,0,0,0,0,0,0,0,0,0,0,0,0,0,0,0,0,0,0,~
0)';BIDI;
    'DDR4_DQ'<6>:'(0,0,0,0,0,0,CR80,0,0,0,0,0,0,0,0,0,0,0,0,0,0,0,0,0,0,0,0,0,0,~
0)';BIDI;
    'DDR4_DQ'<5>:'(0,0,0,0,0,0,CJ80,0,0,0,0,0,0,0,0,0,0,0,0,0,0,0,0,0,0,0,0,0,0,~
0)';BIDI;
    'DDR4_DQ'<4>:'(0,0,0,0,0,0,CK79,0,0,0,0,0,0,0,0,0,0,0,0,0,0,0,0,0,0,0,0,0,0,~
0)';BIDI;
    'DDR4_DQ'<3>:'(0,0,0,0,0,0,CR82,0,0,0,0,0,0,0,0,0,0,0,0,0,0,0,0,0,0,0,0,0,0,~
0)';BIDI;
    'DDR4_DQ'<2>:'(0,0,0,0,0,0,CT81,0,0,0,0,0,0,0,0,0,0,0,0,0,0,0,0,0,0,0,0,0,0,~
0)';BIDI;
    'DDR4_DQ'<1>:'(0,0,0,0,0,0,CK81,0,0,0,0,0,0,0,0,0,0,0,0,0,0,0,0,0,0,0,0,0,0,~
0)';BIDI;
    'DDR4_DQ'<0>:'(0,0,0,0,0,0,CM79,0,0,0,0,0,0,0,0,0,0,0,0,0,0,0,0,0,0,0,0,0,0,~
0)';BIDI;
    'DDR4_DQS_DN'<17>:'(0,0,0,0,0,0,DV67,0,0,0,0,0,0,0,0,0,0,0,0,0,0,0,0,0,0,0,0~
,0,0,0)';BIDI;
    'DDR4_DQS_DN'<16>:'(0,0,0,0,0,0,DG26,0,0,0,0,0,0,0,0,0,0,0,0,0,0,0,0,0,0,0,0~
,0,0,0)';BIDI;
    'DDR4_DQS_DN'<15>:'(0,0,0,0,0,0,EA26,0,0,0,0,0,0,0,0,0,0,0,0,0,0,0,0,0,0,0,0~
,0,0,0)';BIDI;
    'DDR4_DQS_DN'<14>:'(0,0,0,0,0,0,EA32,0,0,0,0,0,0,0,0,0,0,0,0,0,0,0,0,0,0,0,0~
,0,0,0)';BIDI;
    'DDR4_DQS_DN'<13>:'(0,0,0,0,0,0,DP41,0,0,0,0,0,0,0,0,0,0,0,0,0,0,0,0,0,0,0,0~
,0,0,0)';BIDI;
    'DDR4_DQS_DN'<12>:'(0,0,0,0,0,0,EB73,0,0,0,0,0,0,0,0,0,0,0,0,0,0,0,0,0,0,0,0~
,0,0,0)';BIDI;
    'DDR4_DQS_DN'<11>:'(0,0,0,0,0,0,DY79,0,0,0,0,0,0,0,0,0,0,0,0,0,0,0,0,0,0,0,0~
,0,0,0)';BIDI;
    'DDR4_DQS_DN'<10>:'(0,0,0,0,0,0,DC80,0,0,0,0,0,0,0,0,0,0,0,0,0,0,0,0,0,0,0,0~
,0,0,0)';BIDI;
    'DDR4_DQS_DN'<9>:'(0,0,0,0,0,0,CN80,0,0,0,0,0,0,0,0,0,0,0,0,0,0,0,0,0,0,0,0,~
0,0,0)';BIDI;
    'DDR4_DQS_DN'<8>:'(0,0,0,0,0,0,EB67,0,0,0,0,0,0,0,0,0,0,0,0,0,0,0,0,0,0,0,0,~
0,0,0)';BIDI;
    'DDR4_DQS_DN'<7>:'(0,0,0,0,0,0,DL26,0,0,0,0,0,0,0,0,0,0,0,0,0,0,0,0,0,0,0,0,~
0,0,0)';BIDI;
    'DDR4_DQS_DN'<6>:'(0,0,0,0,0,0,EE26,0,0,0,0,0,0,0,0,0,0,0,0,0,0,0,0,0,0,0,0,~
0,0,0)';BIDI;
    'DDR4_DQS_DN'<5>:'(0,0,0,0,0,0,EE32,0,0,0,0,0,0,0,0,0,0,0,0,0,0,0,0,0,0,0,0,~
0,0,0)';BIDI;
    'DDR4_DQS_DN'<4>:'(0,0,0,0,0,0,DV41,0,0,0,0,0,0,0,0,0,0,0,0,0,0,0,0,0,0,0,0,~
0,0,0)';BIDI;
    'DDR4_DQS_DN'<3>:'(0,0,0,0,0,0,EF73,0,0,0,0,0,0,0,0,0,0,0,0,0,0,0,0,0,0,0,0,~
0,0,0)';BIDI;
    'DDR4_DQS_DN'<2>:'(0,0,0,0,0,0,ED79,0,0,0,0,0,0,0,0,0,0,0,0,0,0,0,0,0,0,0,0,~
0,0,0)';BIDI;
    'DDR4_DQS_DN'<1>:'(0,0,0,0,0,0,DA82,0,0,0,0,0,0,0,0,0,0,0,0,0,0,0,0,0,0,0,0,~
0,0,0)';BIDI;
    'DDR4_DQS_DN'<0>:'(0,0,0,0,0,0,CL82,0,0,0,0,0,0,0,0,0,0,0,0,0,0,0,0,0,0,0,0,~
0,0,0)';BIDI;
    'DDR4_DQS_DP'<17>:'(0,0,0,0,0,0,DT67,0,0,0,0,0,0,0,0,0,0,0,0,0,0,0,0,0,0,0,0~
,0,0,0)';BIDI;
    'DDR4_DQS_DP'<16>:'(0,0,0,0,0,0,DE26,0,0,0,0,0,0,0,0,0,0,0,0,0,0,0,0,0,0,0,0~
,0,0,0)';BIDI;
    'DDR4_DQS_DP'<15>:'(0,0,0,0,0,0,DW26,0,0,0,0,0,0,0,0,0,0,0,0,0,0,0,0,0,0,0,0~
,0,0,0)';BIDI;
    'DDR4_DQS_DP'<14>:'(0,0,0,0,0,0,DW32,0,0,0,0,0,0,0,0,0,0,0,0,0,0,0,0,0,0,0,0~
,0,0,0)';BIDI;
    'DDR4_DQS_DP'<13>:'(0,0,0,0,0,0,DM41,0,0,0,0,0,0,0,0,0,0,0,0,0,0,0,0,0,0,0,0~
,0,0,0)';BIDI;
    'DDR4_DQS_DP'<12>:'(0,0,0,0,0,0,DY73,0,0,0,0,0,0,0,0,0,0,0,0,0,0,0,0,0,0,0,0~
,0,0,0)';BIDI;
    'DDR4_DQS_DP'<11>:'(0,0,0,0,0,0,DV79,0,0,0,0,0,0,0,0,0,0,0,0,0,0,0,0,0,0,0,0~
,0,0,0)';BIDI;
    'DDR4_DQS_DP'<10>:'(0,0,0,0,0,0,DD79,0,0,0,0,0,0,0,0,0,0,0,0,0,0,0,0,0,0,0,0~
,0,0,0)';BIDI;
    'DDR4_DQS_DP'<9>:'(0,0,0,0,0,0,CP79,0,0,0,0,0,0,0,0,0,0,0,0,0,0,0,0,0,0,0,0,~
0,0,0)';BIDI;
    'DDR4_DQS_DP'<8>:'(0,0,0,0,0,0,DY67,0,0,0,0,0,0,0,0,0,0,0,0,0,0,0,0,0,0,0,0,~
0,0,0)';BIDI;
    'DDR4_DQS_DP'<7>:'(0,0,0,0,0,0,DJ26,0,0,0,0,0,0,0,0,0,0,0,0,0,0,0,0,0,0,0,0,~
0,0,0)';BIDI;
    'DDR4_DQS_DP'<6>:'(0,0,0,0,0,0,EC26,0,0,0,0,0,0,0,0,0,0,0,0,0,0,0,0,0,0,0,0,~
0,0,0)';BIDI;
    'DDR4_DQS_DP'<5>:'(0,0,0,0,0,0,EC32,0,0,0,0,0,0,0,0,0,0,0,0,0,0,0,0,0,0,0,0,~
0,0,0)';BIDI;
    'DDR4_DQS_DP'<4>:'(0,0,0,0,0,0,DT41,0,0,0,0,0,0,0,0,0,0,0,0,0,0,0,0,0,0,0,0,~
0,0,0)';BIDI;
    'DDR4_DQS_DP'<3>:'(0,0,0,0,0,0,ED73,0,0,0,0,0,0,0,0,0,0,0,0,0,0,0,0,0,0,0,0,~
0,0,0)';BIDI;
    'DDR4_DQS_DP'<2>:'(0,0,0,0,0,0,EB79,0,0,0,0,0,0,0,0,0,0,0,0,0,0,0,0,0,0,0,0,~
0,0,0)';BIDI;
    'DDR4_DQS_DP'<1>:'(0,0,0,0,0,0,DB81,0,0,0,0,0,0,0,0,0,0,0,0,0,0,0,0,0,0,0,0,~
0,0,0)';BIDI;
    'DDR4_DQS_DP'<0>:'(0,0,0,0,0,0,CM81,0,0,0,0,0,0,0,0,0,0,0,0,0,0,0,0,0,0,0,0,~
0,0,0)';BIDI;
    'DDR4_ECC'<7>:'(0,0,0,0,0,0,EA66,0,0,0,0,0,0,0,0,0,0,0,0,0,0,0,0,0,0,0,0,0,0~
,0)';BIDI;
    'DDR4_ECC'<6>:'(0,0,0,0,0,0,DU66,0,0,0,0,0,0,0,0,0,0,0,0,0,0,0,0,0,0,0,0,0,0~
,0)';BIDI;
    'DDR4_ECC'<5>:'(0,0,0,0,0,0,DV69,0,0,0,0,0,0,0,0,0,0,0,0,0,0,0,0,0,0,0,0,0,0~
,0)';BIDI;
    'DDR4_ECC'<4>:'(0,0,0,0,0,0,DU68,0,0,0,0,0,0,0,0,0,0,0,0,0,0,0,0,0,0,0,0,0,0~
,0)';BIDI;
    'DDR4_ECC'<3>:'(0,0,0,0,0,0,DY65,0,0,0,0,0,0,0,0,0,0,0,0,0,0,0,0,0,0,0,0,0,0~
,0)';BIDI;
    'DDR4_ECC'<2>:'(0,0,0,0,0,0,DV65,0,0,0,0,0,0,0,0,0,0,0,0,0,0,0,0,0,0,0,0,0,0~
,0)';BIDI;
    'DDR4_ECC'<1>:'(0,0,0,0,0,0,EA68,0,0,0,0,0,0,0,0,0,0,0,0,0,0,0,0,0,0,0,0,0,0~
,0)';BIDI;
    'DDR4_ECC'<0>:'(0,0,0,0,0,0,DY69,0,0,0,0,0,0,0,0,0,0,0,0,0,0,0,0,0,0,0,0,0,0~
,0)';BIDI;
    'DDR4_MA'<17>:'(0,0,0,0,0,0,DR48,0,0,0,0,0,0,0,0,0,0,0,0,0,0,0,0,0,0,0,0,0,0~
,0)';OUT;
    'DDR4_MA'<16>:'(0,0,0,0,0,0,DN52,0,0,0,0,0,0,0,0,0,0,0,0,0,0,0,0,0,0,0,0,0,0~
,0)';OUT;
    'DDR4_MA'<15>:'(0,0,0,0,0,0,DR52,0,0,0,0,0,0,0,0,0,0,0,0,0,0,0,0,0,0,0,0,0,0~
,0)';OUT;
    'DDR4_MA'<14>:'(0,0,0,0,0,0,DM51,0,0,0,0,0,0,0,0,0,0,0,0,0,0,0,0,0,0,0,0,0,0~
,0)';OUT;
    'DDR4_MA'<13>:'(0,0,0,0,0,0,DT51,0,0,0,0,0,0,0,0,0,0,0,0,0,0,0,0,0,0,0,0,0,0~
,0)';OUT;
    'DDR4_MA'<12>:'(0,0,0,0,0,0,DN60,0,0,0,0,0,0,0,0,0,0,0,0,0,0,0,0,0,0,0,0,0,0~
,0)';OUT;
    'DDR4_MA'<11>:'(0,0,0,0,0,0,DR60,0,0,0,0,0,0,0,0,0,0,0,0,0,0,0,0,0,0,0,0,0,0~
,0)';OUT;
    'DDR4_MA'<10>:'(0,0,0,0,0,0,DT55,0,0,0,0,0,0,0,0,0,0,0,0,0,0,0,0,0,0,0,0,0,0~
,0)';OUT;
    'DDR4_MA'<9>:'(0,0,0,0,0,0,DV59,0,0,0,0,0,0,0,0,0,0,0,0,0,0,0,0,0,0,0,0,0,0,~
0)';OUT;
    'DDR4_MA'<8>:'(0,0,0,0,0,0,DJ60,0,0,0,0,0,0,0,0,0,0,0,0,0,0,0,0,0,0,0,0,0,0,~
0)';OUT;
    'DDR4_MA'<7>:'(0,0,0,0,0,0,DK61,0,0,0,0,0,0,0,0,0,0,0,0,0,0,0,0,0,0,0,0,0,0,~
0)';OUT;
    'DDR4_MA'<6>:'(0,0,0,0,0,0,DM59,0,0,0,0,0,0,0,0,0,0,0,0,0,0,0,0,0,0,0,0,0,0,~
0)';OUT;
    'DDR4_MA'<5>:'(0,0,0,0,0,0,DN58,0,0,0,0,0,0,0,0,0,0,0,0,0,0,0,0,0,0,0,0,0,0,~
0)';OUT;
    'DDR4_MA'<4>:'(0,0,0,0,0,0,DT59,0,0,0,0,0,0,0,0,0,0,0,0,0,0,0,0,0,0,0,0,0,0,~
0)';OUT;
    'DDR4_MA'<3>:'(0,0,0,0,0,0,DR58,0,0,0,0,0,0,0,0,0,0,0,0,0,0,0,0,0,0,0,0,0,0,~
0)';OUT;
    'DDR4_MA'<2>:'(0,0,0,0,0,0,DV57,0,0,0,0,0,0,0,0,0,0,0,0,0,0,0,0,0,0,0,0,0,0,~
0)';OUT;
    'DDR4_MA'<1>:'(0,0,0,0,0,0,DW58,0,0,0,0,0,0,0,0,0,0,0,0,0,0,0,0,0,0,0,0,0,0,~
0)';OUT;
    'DDR4_MA'<0>:'(0,0,0,0,0,0,DW52,0,0,0,0,0,0,0,0,0,0,0,0,0,0,0,0,0,0,0,0,0,0,~
0)';OUT;
    'DDR4_ODT'<3>:'(0,0,0,0,0,0,DM47,0,0,0,0,0,0,0,0,0,0,0,0,0,0,0,0,0,0,0,0,0,0~
,0)';OUT;
    'DDR4_ODT'<2>:'(0,0,0,0,0,0,DT49,0,0,0,0,0,0,0,0,0,0,0,0,0,0,0,0,0,0,0,0,0,0~
,0)';OUT;
    'DDR4_ODT'<1>:'(0,0,0,0,0,0,DN48,0,0,0,0,0,0,0,0,0,0,0,0,0,0,0,0,0,0,0,0,0,0~
,0)';OUT;
    'DDR4_ODT'<0>:'(0,0,0,0,0,0,DR50,0,0,0,0,0,0,0,0,0,0,0,0,0,0,0,0,0,0,0,0,0,0~
,0)';OUT;
    'DDR4_PAR':'(0,0,0,0,0,0,DV53,0,0,0,0,0,0,0,0,0,0,0,0,0,0,0,0,0,0,0,0,0,0,0)~
';$S;OUT;
    'DDR5_ACT_N':'(0,0,0,0,0,0,0,DC62,0,0,0,0,0,0,0,0,0,0,0,0,0,0,0,0,0,0,0,0,0,~
0)';$S;OUT;
    'DDR5_ALERT_N':'(0,0,0,0,0,0,0,DD61,0,0,0,0,0,0,0,0,0,0,0,0,0,0,0,0,0,0,0,0,~
0,0)';$S;IN;
    'DDR5_BA'<1>:'(0,0,0,0,0,0,0,DC56,0,0,0,0,0,0,0,0,0,0,0,0,0,0,0,0,0,0,0,0,0,~
0)';OUT;
    'DDR5_BA'<0>:'(0,0,0,0,0,0,0,DJ52,0,0,0,0,0,0,0,0,0,0,0,0,0,0,0,0,0,0,0,0,0,~
0)';OUT;
    'DDR5_BG'<1>:'(0,0,0,0,0,0,0,DF61,0,0,0,0,0,0,0,0,0,0,0,0,0,0,0,0,0,0,0,0,0,~
0)';OUT;
    'DDR5_BG'<0>:'(0,0,0,0,0,0,0,DA62,0,0,0,0,0,0,0,0,0,0,0,0,0,0,0,0,0,0,0,0,0,~
0)';OUT;
    'DDR5_CAVREF':'(CV61,0,0,0,0,0,0,0,0,0,0,0,0,0,0,0,0,0,0,0,0,0,0,0,0,0,0,0,0~
,0)';$S;OUT;
    'DDR5_CID'<2>:'(0,0,0,0,0,0,0,DF45,0,0,0,0,0,0,0,0,0,0,0,0,0,0,0,0,0,0,0,0,0~
,0)';$S;OUT;
    'DDR5_CKE'<3>:'(0,0,0,0,0,0,0,DF63,0,0,0,0,0,0,0,0,0,0,0,0,0,0,0,0,0,0,0,0,0~
,0)';OUT;
    'DDR5_CKE'<2>:'(0,0,0,0,0,0,0,DK63,0,0,0,0,0,0,0,0,0,0,0,0,0,0,0,0,0,0,0,0,0~
,0)';OUT;
    'DDR5_CKE'<1>:'(0,0,0,0,0,0,0,DD63,0,0,0,0,0,0,0,0,0,0,0,0,0,0,0,0,0,0,0,0,0~
,0)';OUT;
    'DDR5_CKE'<0>:'(0,0,0,0,0,0,0,DG62,0,0,0,0,0,0,0,0,0,0,0,0,0,0,0,0,0,0,0,0,0~
,0)';OUT;
    'DDR5_CLK_DN'<3>:'(0,0,0,0,0,0,0,DF57,0,0,0,0,0,0,0,0,0,0,0,0,0,0,0,0,0,0,0,~
0,0,0)';OUT;
    'DDR5_CLK_DN'<2>:'(0,0,0,0,0,0,0,DK57,0,0,0,0,0,0,0,0,0,0,0,0,0,0,0,0,0,0,0,~
0,0,0)';OUT;
    'DDR5_CLK_DN'<1>:'(0,0,0,0,0,0,0,DF55,0,0,0,0,0,0,0,0,0,0,0,0,0,0,0,0,0,0,0,~
0,0,0)';OUT;
    'DDR5_CLK_DN'<0>:'(0,0,0,0,0,0,0,DK55,0,0,0,0,0,0,0,0,0,0,0,0,0,0,0,0,0,0,0,~
0,0,0)';OUT;
    'DDR5_CLK_DP'<3>:'(0,0,0,0,0,0,0,DG56,0,0,0,0,0,0,0,0,0,0,0,0,0,0,0,0,0,0,0,~
0,0,0)';OUT;
    'DDR5_CLK_DP'<2>:'(0,0,0,0,0,0,0,DJ56,0,0,0,0,0,0,0,0,0,0,0,0,0,0,0,0,0,0,0,~
0,0,0)';OUT;
    'DDR5_CLK_DP'<1>:'(0,0,0,0,0,0,0,DG54,0,0,0,0,0,0,0,0,0,0,0,0,0,0,0,0,0,0,0,~
0,0,0)';OUT;
    'DDR5_CLK_DP'<0>:'(0,0,0,0,0,0,0,DJ54,0,0,0,0,0,0,0,0,0,0,0,0,0,0,0,0,0,0,0,~
0,0,0)';OUT;
    'DDR5_CS_N'<7>:'(0,0,0,0,0,0,0,DK45,0,0,0,0,0,0,0,0,0,0,0,0,0,0,0,0,0,0,0,0,~
0,0)';OUT;
    'DDR5_CS_N'<6>:'(0,0,0,0,0,0,0,DM45,0,0,0,0,0,0,0,0,0,0,0,0,0,0,0,0,0,0,0,0,~
0,0)';OUT;
    'DDR5_CS_N'<5>:'(0,0,0,0,0,0,0,DJ48,0,0,0,0,0,0,0,0,0,0,0,0,0,0,0,0,0,0,0,0,~
0,0)';OUT;
    'DDR5_CS_N'<4>:'(0,0,0,0,0,0,0,DF51,0,0,0,0,0,0,0,0,0,0,0,0,0,0,0,0,0,0,0,0,~
0,0)';OUT;
    'DDR5_CS_N'<3>:'(0,0,0,0,0,0,0,DG46,0,0,0,0,0,0,0,0,0,0,0,0,0,0,0,0,0,0,0,0,~
0,0)';OUT;
    'DDR5_CS_N'<2>:'(0,0,0,0,0,0,0,DJ46,0,0,0,0,0,0,0,0,0,0,0,0,0,0,0,0,0,0,0,0,~
0,0)';OUT;
    'DDR5_CS_N'<1>:'(0,0,0,0,0,0,0,DF49,0,0,0,0,0,0,0,0,0,0,0,0,0,0,0,0,0,0,0,0,~
0,0)';OUT;
    'DDR5_CS_N'<0>:'(0,0,0,0,0,0,0,DK51,0,0,0,0,0,0,0,0,0,0,0,0,0,0,0,0,0,0,0,0,~
0,0)';OUT;
    'DDR5_DQ'<63>:'(0,0,0,0,0,0,0,DC28,0,0,0,0,0,0,0,0,0,0,0,0,0,0,0,0,0,0,0,0,0~
,0)';BIDI;
    'DDR5_DQ'<62>:'(0,0,0,0,0,0,0,CW28,0,0,0,0,0,0,0,0,0,0,0,0,0,0,0,0,0,0,0,0,0~
,0)';BIDI;
    'DDR5_DQ'<61>:'(0,0,0,0,0,0,0,DB31,0,0,0,0,0,0,0,0,0,0,0,0,0,0,0,0,0,0,0,0,0~
,0)';BIDI;
    'DDR5_DQ'<60>:'(0,0,0,0,0,0,0,CY31,0,0,0,0,0,0,0,0,0,0,0,0,0,0,0,0,0,0,0,0,0~
,0)';BIDI;
    'DDR5_DQ'<59>:'(0,0,0,0,0,0,0,DB27,0,0,0,0,0,0,0,0,0,0,0,0,0,0,0,0,0,0,0,0,0~
,0)';BIDI;
    'DDR5_DQ'<58>:'(0,0,0,0,0,0,0,CY27,0,0,0,0,0,0,0,0,0,0,0,0,0,0,0,0,0,0,0,0,0~
,0)';BIDI;
    'DDR5_DQ'<57>:'(0,0,0,0,0,0,0,DC30,0,0,0,0,0,0,0,0,0,0,0,0,0,0,0,0,0,0,0,0,0~
,0)';BIDI;
    'DDR5_DQ'<56>:'(0,0,0,0,0,0,0,CW30,0,0,0,0,0,0,0,0,0,0,0,0,0,0,0,0,0,0,0,0,0~
,0)';BIDI;
    'DDR5_DQ'<55>:'(0,0,0,0,0,0,0,DC34,0,0,0,0,0,0,0,0,0,0,0,0,0,0,0,0,0,0,0,0,0~
,0)';BIDI;
    'DDR5_DQ'<54>:'(0,0,0,0,0,0,0,CW34,0,0,0,0,0,0,0,0,0,0,0,0,0,0,0,0,0,0,0,0,0~
,0)';BIDI;
    'DDR5_DQ'<53>:'(0,0,0,0,0,0,0,DB37,0,0,0,0,0,0,0,0,0,0,0,0,0,0,0,0,0,0,0,0,0~
,0)';BIDI;
    'DDR5_DQ'<52>:'(0,0,0,0,0,0,0,CY37,0,0,0,0,0,0,0,0,0,0,0,0,0,0,0,0,0,0,0,0,0~
,0)';BIDI;
    'DDR5_DQ'<51>:'(0,0,0,0,0,0,0,DB33,0,0,0,0,0,0,0,0,0,0,0,0,0,0,0,0,0,0,0,0,0~
,0)';BIDI;
    'DDR5_DQ'<50>:'(0,0,0,0,0,0,0,CY33,0,0,0,0,0,0,0,0,0,0,0,0,0,0,0,0,0,0,0,0,0~
,0)';BIDI;
    'DDR5_DQ'<49>:'(0,0,0,0,0,0,0,DC36,0,0,0,0,0,0,0,0,0,0,0,0,0,0,0,0,0,0,0,0,0~
,0)';BIDI;
    'DDR5_DQ'<48>:'(0,0,0,0,0,0,0,CW36,0,0,0,0,0,0,0,0,0,0,0,0,0,0,0,0,0,0,0,0,0~
,0)';BIDI;
    'DDR5_DQ'<47>:'(0,0,0,0,0,0,0,DK31,0,0,0,0,0,0,0,0,0,0,0,0,0,0,0,0,0,0,0,0,0~
,0)';BIDI;
    'DDR5_DQ'<46>:'(0,0,0,0,0,0,0,DF31,0,0,0,0,0,0,0,0,0,0,0,0,0,0,0,0,0,0,0,0,0~
,0)';BIDI;
    'DDR5_DQ'<45>:'(0,0,0,0,0,0,0,DJ34,0,0,0,0,0,0,0,0,0,0,0,0,0,0,0,0,0,0,0,0,0~
,0)';BIDI;
    'DDR5_DQ'<44>:'(0,0,0,0,0,0,0,DG34,0,0,0,0,0,0,0,0,0,0,0,0,0,0,0,0,0,0,0,0,0~
,0)';BIDI;
    'DDR5_DQ'<43>:'(0,0,0,0,0,0,0,DJ30,0,0,0,0,0,0,0,0,0,0,0,0,0,0,0,0,0,0,0,0,0~
,0)';BIDI;
    'DDR5_DQ'<42>:'(0,0,0,0,0,0,0,DG30,0,0,0,0,0,0,0,0,0,0,0,0,0,0,0,0,0,0,0,0,0~
,0)';BIDI;
    'DDR5_DQ'<41>:'(0,0,0,0,0,0,0,DK33,0,0,0,0,0,0,0,0,0,0,0,0,0,0,0,0,0,0,0,0,0~
,0)';BIDI;
    'DDR5_DQ'<40>:'(0,0,0,0,0,0,0,DF33,0,0,0,0,0,0,0,0,0,0,0,0,0,0,0,0,0,0,0,0,0~
,0)';BIDI;
    'DDR5_DQ'<39>:'(0,0,0,0,0,0,0,DH39,0,0,0,0,0,0,0,0,0,0,0,0,0,0,0,0,0,0,0,0,0~
,0)';BIDI;
    'DDR5_DQ'<38>:'(0,0,0,0,0,0,0,DD39,0,0,0,0,0,0,0,0,0,0,0,0,0,0,0,0,0,0,0,0,0~
,0)';BIDI;
    'DDR5_DQ'<37>:'(0,0,0,0,0,0,0,DE42,0,0,0,0,0,0,0,0,0,0,0,0,0,0,0,0,0,0,0,0,0~
,0)';BIDI;
    'DDR5_DQ'<36>:'(0,0,0,0,0,0,0,DA42,0,0,0,0,0,0,0,0,0,0,0,0,0,0,0,0,0,0,0,0,0~
,0)';BIDI;
    'DDR5_DQ'<35>:'(0,0,0,0,0,0,0,DG38,0,0,0,0,0,0,0,0,0,0,0,0,0,0,0,0,0,0,0,0,0~
,0)';BIDI;
    'DDR5_DQ'<34>:'(0,0,0,0,0,0,0,DE38,0,0,0,0,0,0,0,0,0,0,0,0,0,0,0,0,0,0,0,0,0~
,0)';BIDI;
    'DDR5_DQ'<33>:'(0,0,0,0,0,0,0,DG42,0,0,0,0,0,0,0,0,0,0,0,0,0,0,0,0,0,0,0,0,0~
,0)';BIDI;
    'DDR5_DQ'<32>:'(0,0,0,0,0,0,0,DD41,0,0,0,0,0,0,0,0,0,0,0,0,0,0,0,0,0,0,0,0,0~
,0)';BIDI;
    'DDR5_DQ'<31>:'(0,0,0,0,0,0,0,CU64,0,0,0,0,0,0,0,0,0,0,0,0,0,0,0,0,0,0,0,0,0~
,0)';BIDI;
    'DDR5_DQ'<30>:'(0,0,0,0,0,0,0,CN64,0,0,0,0,0,0,0,0,0,0,0,0,0,0,0,0,0,0,0,0,0~
,0)';BIDI;
    'DDR5_DQ'<29>:'(0,0,0,0,0,0,0,CT67,0,0,0,0,0,0,0,0,0,0,0,0,0,0,0,0,0,0,0,0,0~
,0)';BIDI;
    'DDR5_DQ'<28>:'(0,0,0,0,0,0,0,CP67,0,0,0,0,0,0,0,0,0,0,0,0,0,0,0,0,0,0,0,0,0~
,0)';BIDI;
    'DDR5_DQ'<27>:'(0,0,0,0,0,0,0,CT63,0,0,0,0,0,0,0,0,0,0,0,0,0,0,0,0,0,0,0,0,0~
,0)';BIDI;
    'DDR5_DQ'<26>:'(0,0,0,0,0,0,0,CP63,0,0,0,0,0,0,0,0,0,0,0,0,0,0,0,0,0,0,0,0,0~
,0)';BIDI;
    'DDR5_DQ'<25>:'(0,0,0,0,0,0,0,CU66,0,0,0,0,0,0,0,0,0,0,0,0,0,0,0,0,0,0,0,0,0~
,0)';BIDI;
    'DDR5_DQ'<24>:'(0,0,0,0,0,0,0,CN66,0,0,0,0,0,0,0,0,0,0,0,0,0,0,0,0,0,0,0,0,0~
,0)';BIDI;
    'DDR5_DQ'<23>:'(0,0,0,0,0,0,0,DM71,0,0,0,0,0,0,0,0,0,0,0,0,0,0,0,0,0,0,0,0,0~
,0)';BIDI;
    'DDR5_DQ'<22>:'(0,0,0,0,0,0,0,DK69,0,0,0,0,0,0,0,0,0,0,0,0,0,0,0,0,0,0,0,0,0~
,0)';BIDI;
    'DDR5_DQ'<21>:'(0,0,0,0,0,0,0,DG72,0,0,0,0,0,0,0,0,0,0,0,0,0,0,0,0,0,0,0,0,0~
,0)';BIDI;
    'DDR5_DQ'<20>:'(0,0,0,0,0,0,0,DF71,0,0,0,0,0,0,0,0,0,0,0,0,0,0,0,0,0,0,0,0,0~
,0)';BIDI;
    'DDR5_DQ'<19>:'(0,0,0,0,0,0,0,DN70,0,0,0,0,0,0,0,0,0,0,0,0,0,0,0,0,0,0,0,0,0~
,0)';BIDI;
    'DDR5_DQ'<18>:'(0,0,0,0,0,0,0,DM69,0,0,0,0,0,0,0,0,0,0,0,0,0,0,0,0,0,0,0,0,0~
,0)';BIDI;
    'DDR5_DQ'<17>:'(0,0,0,0,0,0,0,DJ72,0,0,0,0,0,0,0,0,0,0,0,0,0,0,0,0,0,0,0,0,0~
,0)';BIDI;
    'DDR5_DQ'<16>:'(0,0,0,0,0,0,0,DG70,0,0,0,0,0,0,0,0,0,0,0,0,0,0,0,0,0,0,0,0,0~
,0)';BIDI;
    'DDR5_DQ'<15>:'(0,0,0,0,0,0,0,DH77,0,0,0,0,0,0,0,0,0,0,0,0,0,0,0,0,0,0,0,0,0~
,0)';BIDI;
    'DDR5_DQ'<14>:'(0,0,0,0,0,0,0,DF77,0,0,0,0,0,0,0,0,0,0,0,0,0,0,0,0,0,0,0,0,0~
,0)';BIDI;
    'DDR5_DQ'<13>:'(0,0,0,0,0,0,0,DB75,0,0,0,0,0,0,0,0,0,0,0,0,0,0,0,0,0,0,0,0,0~
,0)';BIDI;
    'DDR5_DQ'<12>:'(0,0,0,0,0,0,0,DC74,0,0,0,0,0,0,0,0,0,0,0,0,0,0,0,0,0,0,0,0,0~
,0)';BIDI;
    'DDR5_DQ'<11>:'(0,0,0,0,0,0,0,DJ76,0,0,0,0,0,0,0,0,0,0,0,0,0,0,0,0,0,0,0,0,0~
,0)';BIDI;
    'DDR5_DQ'<10>:'(0,0,0,0,0,0,0,DH75,0,0,0,0,0,0,0,0,0,0,0,0,0,0,0,0,0,0,0,0,0~
,0)';BIDI;
    'DDR5_DQ'<9>:'(0,0,0,0,0,0,0,DC76,0,0,0,0,0,0,0,0,0,0,0,0,0,0,0,0,0,0,0,0,0,~
0)';BIDI;
    'DDR5_DQ'<8>:'(0,0,0,0,0,0,0,DE74,0,0,0,0,0,0,0,0,0,0,0,0,0,0,0,0,0,0,0,0,0,~
0)';BIDI;
    'DDR5_DQ'<7>:'(0,0,0,0,0,0,0,CT77,0,0,0,0,0,0,0,0,0,0,0,0,0,0,0,0,0,0,0,0,0,~
0)';BIDI;
    'DDR5_DQ'<6>:'(0,0,0,0,0,0,0,CV75,0,0,0,0,0,0,0,0,0,0,0,0,0,0,0,0,0,0,0,0,0,~
0)';BIDI;
    'DDR5_DQ'<5>:'(0,0,0,0,0,0,0,CM75,0,0,0,0,0,0,0,0,0,0,0,0,0,0,0,0,0,0,0,0,0,~
0)';BIDI;
    'DDR5_DQ'<4>:'(0,0,0,0,0,0,0,CN74,0,0,0,0,0,0,0,0,0,0,0,0,0,0,0,0,0,0,0,0,0,~
0)';BIDI;
    'DDR5_DQ'<3>:'(0,0,0,0,0,0,0,CV77,0,0,0,0,0,0,0,0,0,0,0,0,0,0,0,0,0,0,0,0,0,~
0)';BIDI;
    'DDR5_DQ'<2>:'(0,0,0,0,0,0,0,CW76,0,0,0,0,0,0,0,0,0,0,0,0,0,0,0,0,0,0,0,0,0,~
0)';BIDI;
    'DDR5_DQ'<1>:'(0,0,0,0,0,0,0,CN76,0,0,0,0,0,0,0,0,0,0,0,0,0,0,0,0,0,0,0,0,0,~
0)';BIDI;
    'DDR5_DQ'<0>:'(0,0,0,0,0,0,0,CR74,0,0,0,0,0,0,0,0,0,0,0,0,0,0,0,0,0,0,0,0,0,~
0)';BIDI;
    'DDR5_DQS_DN'<17>:'(0,0,0,0,0,0,0,CJ70,0,0,0,0,0,0,0,0,0,0,0,0,0,0,0,0,0,0,0~
,0,0,0)';BIDI;
    'DDR5_DQS_DN'<16>:'(0,0,0,0,0,0,0,CY29,0,0,0,0,0,0,0,0,0,0,0,0,0,0,0,0,0,0,0~
,0,0,0)';BIDI;
    'DDR5_DQS_DN'<15>:'(0,0,0,0,0,0,0,CY35,0,0,0,0,0,0,0,0,0,0,0,0,0,0,0,0,0,0,0~
,0,0,0)';BIDI;
    'DDR5_DQS_DN'<14>:'(0,0,0,0,0,0,0,DG32,0,0,0,0,0,0,0,0,0,0,0,0,0,0,0,0,0,0,0~
,0,0,0)';BIDI;
    'DDR5_DQS_DN'<13>:'(0,0,0,0,0,0,0,DE40,0,0,0,0,0,0,0,0,0,0,0,0,0,0,0,0,0,0,0~
,0,0,0)';BIDI;
    'DDR5_DQS_DN'<12>:'(0,0,0,0,0,0,0,CP65,0,0,0,0,0,0,0,0,0,0,0,0,0,0,0,0,0,0,0~
,0,0,0)';BIDI;
    'DDR5_DQS_DN'<11>:'(0,0,0,0,0,0,0,DJ70,0,0,0,0,0,0,0,0,0,0,0,0,0,0,0,0,0,0,0~
,0,0,0)';BIDI;
    'DDR5_DQS_DN'<10>:'(0,0,0,0,0,0,0,DF75,0,0,0,0,0,0,0,0,0,0,0,0,0,0,0,0,0,0,0~
,0,0,0)';BIDI;
    'DDR5_DQS_DN'<9>:'(0,0,0,0,0,0,0,CT75,0,0,0,0,0,0,0,0,0,0,0,0,0,0,0,0,0,0,0,~
0,0,0)';BIDI;
    'DDR5_DQS_DN'<8>:'(0,0,0,0,0,0,0,CN70,0,0,0,0,0,0,0,0,0,0,0,0,0,0,0,0,0,0,0,~
0,0,0)';BIDI;
    'DDR5_DQS_DN'<7>:'(0,0,0,0,0,0,0,DD29,0,0,0,0,0,0,0,0,0,0,0,0,0,0,0,0,0,0,0,~
0,0,0)';BIDI;
    'DDR5_DQS_DN'<6>:'(0,0,0,0,0,0,0,DD35,0,0,0,0,0,0,0,0,0,0,0,0,0,0,0,0,0,0,0,~
0,0,0)';BIDI;
    'DDR5_DQS_DN'<5>:'(0,0,0,0,0,0,0,DL32,0,0,0,0,0,0,0,0,0,0,0,0,0,0,0,0,0,0,0,~
0,0,0)';BIDI;
    'DDR5_DQS_DN'<4>:'(0,0,0,0,0,0,0,DG40,0,0,0,0,0,0,0,0,0,0,0,0,0,0,0,0,0,0,0,~
0,0,0)';BIDI;
    'DDR5_DQS_DN'<3>:'(0,0,0,0,0,0,0,CV65,0,0,0,0,0,0,0,0,0,0,0,0,0,0,0,0,0,0,0,~
0,0,0)';BIDI;
    'DDR5_DQS_DN'<2>:'(0,0,0,0,0,0,0,DL72,0,0,0,0,0,0,0,0,0,0,0,0,0,0,0,0,0,0,0,~
0,0,0)';BIDI;
    'DDR5_DQS_DN'<1>:'(0,0,0,0,0,0,0,DD77,0,0,0,0,0,0,0,0,0,0,0,0,0,0,0,0,0,0,0,~
0,0,0)';BIDI;
    'DDR5_DQS_DN'<0>:'(0,0,0,0,0,0,0,CP77,0,0,0,0,0,0,0,0,0,0,0,0,0,0,0,0,0,0,0,~
0,0,0)';BIDI;
    'DDR5_DQS_DP'<17>:'(0,0,0,0,0,0,0,CG70,0,0,0,0,0,0,0,0,0,0,0,0,0,0,0,0,0,0,0~
,0,0,0)';BIDI;
    'DDR5_DQS_DP'<16>:'(0,0,0,0,0,0,0,CV29,0,0,0,0,0,0,0,0,0,0,0,0,0,0,0,0,0,0,0~
,0,0,0)';BIDI;
    'DDR5_DQS_DP'<15>:'(0,0,0,0,0,0,0,CV35,0,0,0,0,0,0,0,0,0,0,0,0,0,0,0,0,0,0,0~
,0,0,0)';BIDI;
    'DDR5_DQS_DP'<14>:'(0,0,0,0,0,0,0,DE32,0,0,0,0,0,0,0,0,0,0,0,0,0,0,0,0,0,0,0~
,0,0,0)';BIDI;
    'DDR5_DQS_DP'<13>:'(0,0,0,0,0,0,0,DC40,0,0,0,0,0,0,0,0,0,0,0,0,0,0,0,0,0,0,0~
,0,0,0)';BIDI;
    'DDR5_DQS_DP'<12>:'(0,0,0,0,0,0,0,CM65,0,0,0,0,0,0,0,0,0,0,0,0,0,0,0,0,0,0,0~
,0,0,0)';BIDI;
    'DDR5_DQS_DP'<11>:'(0,0,0,0,0,0,0,DH69,0,0,0,0,0,0,0,0,0,0,0,0,0,0,0,0,0,0,0~
,0,0,0)';BIDI;
    'DDR5_DQS_DP'<10>:'(0,0,0,0,0,0,0,DG74,0,0,0,0,0,0,0,0,0,0,0,0,0,0,0,0,0,0,0~
,0,0,0)';BIDI;
    'DDR5_DQS_DP'<9>:'(0,0,0,0,0,0,0,CU74,0,0,0,0,0,0,0,0,0,0,0,0,0,0,0,0,0,0,0,~
0,0,0)';BIDI;
    'DDR5_DQS_DP'<8>:'(0,0,0,0,0,0,0,CL70,0,0,0,0,0,0,0,0,0,0,0,0,0,0,0,0,0,0,0,~
0,0,0)';BIDI;
    'DDR5_DQS_DP'<7>:'(0,0,0,0,0,0,0,DB29,0,0,0,0,0,0,0,0,0,0,0,0,0,0,0,0,0,0,0,~
0,0,0)';BIDI;
    'DDR5_DQS_DP'<6>:'(0,0,0,0,0,0,0,DB35,0,0,0,0,0,0,0,0,0,0,0,0,0,0,0,0,0,0,0,~
0,0,0)';BIDI;
    'DDR5_DQS_DP'<5>:'(0,0,0,0,0,0,0,DJ32,0,0,0,0,0,0,0,0,0,0,0,0,0,0,0,0,0,0,0,~
0,0,0)';BIDI;
    'DDR5_DQS_DP'<4>:'(0,0,0,0,0,0,0,DJ40,0,0,0,0,0,0,0,0,0,0,0,0,0,0,0,0,0,0,0,~
0,0,0)';BIDI;
    'DDR5_DQS_DP'<3>:'(0,0,0,0,0,0,0,CT65,0,0,0,0,0,0,0,0,0,0,0,0,0,0,0,0,0,0,0,~
0,0,0)';BIDI;
    'DDR5_DQS_DP'<2>:'(0,0,0,0,0,0,0,DK71,0,0,0,0,0,0,0,0,0,0,0,0,0,0,0,0,0,0,0,~
0,0,0)';BIDI;
    'DDR5_DQS_DP'<1>:'(0,0,0,0,0,0,0,DE76,0,0,0,0,0,0,0,0,0,0,0,0,0,0,0,0,0,0,0,~
0,0,0)';BIDI;
    'DDR5_DQS_DP'<0>:'(0,0,0,0,0,0,0,CR76,0,0,0,0,0,0,0,0,0,0,0,0,0,0,0,0,0,0,0,~
0,0,0)';BIDI;
    'DDR5_ECC'<7>:'(0,0,0,0,0,0,0,CM69,0,0,0,0,0,0,0,0,0,0,0,0,0,0,0,0,0,0,0,0,0~
,0)';BIDI;
    'DDR5_ECC'<6>:'(0,0,0,0,0,0,0,CH69,0,0,0,0,0,0,0,0,0,0,0,0,0,0,0,0,0,0,0,0,0~
,0)';BIDI;
    'DDR5_ECC'<5>:'(0,0,0,0,0,0,0,CL72,0,0,0,0,0,0,0,0,0,0,0,0,0,0,0,0,0,0,0,0,0~
,0)';BIDI;
    'DDR5_ECC'<4>:'(0,0,0,0,0,0,0,CJ72,0,0,0,0,0,0,0,0,0,0,0,0,0,0,0,0,0,0,0,0,0~
,0)';BIDI;
    'DDR5_ECC'<3>:'(0,0,0,0,0,0,0,CL68,0,0,0,0,0,0,0,0,0,0,0,0,0,0,0,0,0,0,0,0,0~
,0)';BIDI;
    'DDR5_ECC'<2>:'(0,0,0,0,0,0,0,CJ68,0,0,0,0,0,0,0,0,0,0,0,0,0,0,0,0,0,0,0,0,0~
,0)';BIDI;
    'DDR5_ECC'<1>:'(0,0,0,0,0,0,0,CM71,0,0,0,0,0,0,0,0,0,0,0,0,0,0,0,0,0,0,0,0,0~
,0)';BIDI;
    'DDR5_ECC'<0>:'(0,0,0,0,0,0,0,CH71,0,0,0,0,0,0,0,0,0,0,0,0,0,0,0,0,0,0,0,0,0~
,0)';BIDI;
    'DDR5_MA'<17>:'(0,0,0,0,0,0,0,DE46,0,0,0,0,0,0,0,0,0,0,0,0,0,0,0,0,0,0,0,0,0~
,0)';OUT;
    'DDR5_MA'<16>:'(0,0,0,0,0,0,0,DG52,0,0,0,0,0,0,0,0,0,0,0,0,0,0,0,0,0,0,0,0,0~
,0)';OUT;
    'DDR5_MA'<15>:'(0,0,0,0,0,0,0,DC54,0,0,0,0,0,0,0,0,0,0,0,0,0,0,0,0,0,0,0,0,0~
,0)';OUT;
    'DDR5_MA'<14>:'(0,0,0,0,0,0,0,DJ50,0,0,0,0,0,0,0,0,0,0,0,0,0,0,0,0,0,0,0,0,0~
,0)';OUT;
    'DDR5_MA'<13>:'(0,0,0,0,0,0,0,DD53,0,0,0,0,0,0,0,0,0,0,0,0,0,0,0,0,0,0,0,0,0~
,0)';OUT;
    'DDR5_MA'<12>:'(0,0,0,0,0,0,0,DG60,0,0,0,0,0,0,0,0,0,0,0,0,0,0,0,0,0,0,0,0,0~
,0)';OUT;
    'DDR5_MA'<11>:'(0,0,0,0,0,0,0,DA60,0,0,0,0,0,0,0,0,0,0,0,0,0,0,0,0,0,0,0,0,0~
,0)';OUT;
    'DDR5_MA'<10>:'(0,0,0,0,0,0,0,DD55,0,0,0,0,0,0,0,0,0,0,0,0,0,0,0,0,0,0,0,0,0~
,0)';OUT;
    'DDR5_MA'<9>:'(0,0,0,0,0,0,0,DA58,0,0,0,0,0,0,0,0,0,0,0,0,0,0,0,0,0,0,0,0,0,~
0)';OUT;
    'DDR5_MA'<8>:'(0,0,0,0,0,0,0,DD59,0,0,0,0,0,0,0,0,0,0,0,0,0,0,0,0,0,0,0,0,0,~
0)';OUT;
    'DDR5_MA'<7>:'(0,0,0,0,0,0,0,DC60,0,0,0,0,0,0,0,0,0,0,0,0,0,0,0,0,0,0,0,0,0,~
0)';OUT;
    'DDR5_MA'<6>:'(0,0,0,0,0,0,0,DK59,0,0,0,0,0,0,0,0,0,0,0,0,0,0,0,0,0,0,0,0,0,~
0)';OUT;
    'DDR5_MA'<5>:'(0,0,0,0,0,0,0,DF59,0,0,0,0,0,0,0,0,0,0,0,0,0,0,0,0,0,0,0,0,0,~
0)';OUT;
    'DDR5_MA'<4>:'(0,0,0,0,0,0,0,DJ58,0,0,0,0,0,0,0,0,0,0,0,0,0,0,0,0,0,0,0,0,0,~
0)';OUT;
    'DDR5_MA'<3>:'(0,0,0,0,0,0,0,DG58,0,0,0,0,0,0,0,0,0,0,0,0,0,0,0,0,0,0,0,0,0,~
0)';OUT;
    'DDR5_MA'<2>:'(0,0,0,0,0,0,0,DD57,0,0,0,0,0,0,0,0,0,0,0,0,0,0,0,0,0,0,0,0,0,~
0)';OUT;
    'DDR5_MA'<1>:'(0,0,0,0,0,0,0,DC58,0,0,0,0,0,0,0,0,0,0,0,0,0,0,0,0,0,0,0,0,0,~
0)';OUT;
    'DDR5_MA'<0>:'(0,0,0,0,0,0,0,DF53,0,0,0,0,0,0,0,0,0,0,0,0,0,0,0,0,0,0,0,0,0,~
0)';OUT;
    'DDR5_ODT'<3>:'(0,0,0,0,0,0,0,DF47,0,0,0,0,0,0,0,0,0,0,0,0,0,0,0,0,0,0,0,0,0~
,0)';OUT;
    'DDR5_ODT'<2>:'(0,0,0,0,0,0,0,DK49,0,0,0,0,0,0,0,0,0,0,0,0,0,0,0,0,0,0,0,0,0~
,0)';OUT;
    'DDR5_ODT'<1>:'(0,0,0,0,0,0,0,DG48,0,0,0,0,0,0,0,0,0,0,0,0,0,0,0,0,0,0,0,0,0~
,0)';OUT;
    'DDR5_ODT'<0>:'(0,0,0,0,0,0,0,DG50,0,0,0,0,0,0,0,0,0,0,0,0,0,0,0,0,0,0,0,0,0~
,0)';OUT;
    'DDR5_PAR':'(0,0,0,0,0,0,0,DK53,0,0,0,0,0,0,0,0,0,0,0,0,0,0,0,0,0,0,0,0,0,0)~
';$S;OUT;
    'DEBUG_EN_N':'(0,AV21,0,0,0,0,0,0,0,0,0,0,0,0,0,0,0,0,0,0,0,0,0,0,0,0,0,0,0,~
0)';$S;BIDI;
    'DMIMODE_OVERRIDE':'(0,AW12,0,0,0,0,0,0,0,0,0,0,0,0,0,0,0,0,0,0,0,0,0,0,0,0,~
0,0,0,0)';$S;BIDI;
    'DMI_RX_DN'<3>:'(0,0,0,0,0,0,0,0,CT11,0,0,0,0,0,0,0,0,0,0,0,0,0,0,0,0,0,0,0,~
0,0)';IN;
    'DMI_RX_DN'<2>:'(0,0,0,0,0,0,0,0,CR12,0,0,0,0,0,0,0,0,0,0,0,0,0,0,0,0,0,0,0,~
0,0)';IN;
    'DMI_RX_DN'<1>:'(0,0,0,0,0,0,0,0,CM11,0,0,0,0,0,0,0,0,0,0,0,0,0,0,0,0,0,0,0,~
0,0)';IN;
    'DMI_RX_DN'<0>:'(0,0,0,0,0,0,0,0,CK9,0,0,0,0,0,0,0,0,0,0,0,0,0,0,0,0,0,0,0,0~
,0)';IN;
    'DMI_RX_DP'<3>:'(0,0,0,0,0,0,0,0,CV11,0,0,0,0,0,0,0,0,0,0,0,0,0,0,0,0,0,0,0,~
0,0)';IN;
    'DMI_RX_DP'<2>:'(0,0,0,0,0,0,0,0,CP11,0,0,0,0,0,0,0,0,0,0,0,0,0,0,0,0,0,0,0,~
0,0)';IN;
    'DMI_RX_DP'<1>:'(0,0,0,0,0,0,0,0,CN10,0,0,0,0,0,0,0,0,0,0,0,0,0,0,0,0,0,0,0,~
0,0)';IN;
    'DMI_RX_DP'<0>:'(0,0,0,0,0,0,0,0,CL10,0,0,0,0,0,0,0,0,0,0,0,0,0,0,0,0,0,0,0,~
0,0)';IN;
    'DMI_TX_DN'<3>:'(0,0,0,0,0,0,0,0,CP5,0,0,0,0,0,0,0,0,0,0,0,0,0,0,0,0,0,0,0,0~
,0)';OUT;
    'DMI_TX_DN'<2>:'(0,0,0,0,0,0,0,0,CN4,0,0,0,0,0,0,0,0,0,0,0,0,0,0,0,0,0,0,0,0~
,0)';OUT;
    'DMI_TX_DN'<1>:'(0,0,0,0,0,0,0,0,CJ4,0,0,0,0,0,0,0,0,0,0,0,0,0,0,0,0,0,0,0,0~
,0)';OUT;
    'DMI_TX_DN'<0>:'(0,0,0,0,0,0,0,0,CG4,0,0,0,0,0,0,0,0,0,0,0,0,0,0,0,0,0,0,0,0~
,0)';OUT;
    'DMI_TX_DP'<3>:'(0,0,0,0,0,0,0,0,CR4,0,0,0,0,0,0,0,0,0,0,0,0,0,0,0,0,0,0,0,0~
,0)';OUT;
    'DMI_TX_DP'<2>:'(0,0,0,0,0,0,0,0,CM3,0,0,0,0,0,0,0,0,0,0,0,0,0,0,0,0,0,0,0,0~
,0)';OUT;
    'DMI_TX_DP'<1>:'(0,0,0,0,0,0,0,0,CL4,0,0,0,0,0,0,0,0,0,0,0,0,0,0,0,0,0,0,0,0~
,0)';OUT;
    'DMI_TX_DP'<0>:'(0,0,0,0,0,0,0,0,CH5,0,0,0,0,0,0,0,0,0,0,0,0,0,0,0,0,0,0,0,0~
,0)';OUT;
    'EAR_N':'(AJ14,0,0,0,0,0,0,0,0,0,0,0,0,0,0,0,0,0,0,0,0,0,0,0,0,0,0,0,0,0)';$~
S;IN;
    'ERROR_N'<2>:'(AL12,0,0,0,0,0,0,0,0,0,0,0,0,0,0,0,0,0,0,0,0,0,0,0,0,0,0,0,0,~
0)';OUT;
    'ERROR_N'<1>:'(AK11,0,0,0,0,0,0,0,0,0,0,0,0,0,0,0,0,0,0,0,0,0,0,0,0,0,0,0,0,~
0)';OUT;
    'ERROR_N'<0>:'(AJ12,0,0,0,0,0,0,0,0,0,0,0,0,0,0,0,0,0,0,0,0,0,0,0,0,0,0,0,0,~
0)';OUT;
    'FIVR_FAULT':'(0,AU14,0,0,0,0,0,0,0,0,0,0,0,0,0,0,0,0,0,0,0,0,0,0,0,0,0,0,0,~
0)';$S;OUT;
    'FRMAGENT':'(AV17,0,0,0,0,0,0,0,0,0,0,0,0,0,0,0,0,0,0,0,0,0,0,0,0,0,0,0,0,0)~
';$S;IN;
    'LEGACY_SKT':'(AE20,0,0,0,0,0,0,0,0,0,0,0,0,0,0,0,0,0,0,0,0,0,0,0,0,0,0,0,0,~
0)';$S;IN;
    'MCP01_RBIAS'<1>:'(CT31,0,0,0,0,0,0,0,0,0,0,0,0,0,0,0,0,0,0,0,0,0,0,0,0,0,0,~
0,0,0)';BIDI;
    'MCP01_RBIAS'<0>:'(CU32,0,0,0,0,0,0,0,0,0,0,0,0,0,0,0,0,0,0,0,0,0,0,0,0,0,0,~
0,0,0)';BIDI;
    'MEM_HOT_C012_N':'(AH13,0,0,0,0,0,0,0,0,0,0,0,0,0,0,0,0,0,0,0,0,0,0,0,0,0,0,~
0,0,0)';$S;BIDI;
    'MEM_HOT_C345_N':'(AF13,0,0,0,0,0,0,0,0,0,0,0,0,0,0,0,0,0,0,0,0,0,0,0,0,0,0,~
0,0,0)';$S;BIDI;
    'MSMI_N':'(AN20,0,0,0,0,0,0,0,0,0,0,0,0,0,0,0,0,0,0,0,0,0,0,0,0,0,0,0,0,0)';~
$S;BIDI;
    'NMI':'(AP11,0,0,0,0,0,0,0,0,0,0,0,0,0,0,0,0,0,0,0,0,0,0,0,0,0,0,0,0,0)';$S;~
IN;
    'PE012_RBIAS'<1>:'(CL30,0,0,0,0,0,0,0,0,0,0,0,0,0,0,0,0,0,0,0,0,0,0,0,0,0,0,~
0,0,0)';BIDI;
    'PE012_RBIAS'<0>:'(CN30,0,0,0,0,0,0,0,0,0,0,0,0,0,0,0,0,0,0,0,0,0,0,0,0,0,0,~
0,0,0)';BIDI;
    'PE1_RX_DN'<15>:'(0,0,0,0,0,0,0,0,0,DU16,0,0,0,0,0,0,0,0,0,0,0,0,0,0,0,0,0,0~
,0,0)';IN;
    'PE1_RX_DN'<14>:'(0,0,0,0,0,0,0,0,0,DY15,0,0,0,0,0,0,0,0,0,0,0,0,0,0,0,0,0,0~
,0,0)';IN;
    'PE1_RX_DN'<13>:'(0,0,0,0,0,0,0,0,0,DW14,0,0,0,0,0,0,0,0,0,0,0,0,0,0,0,0,0,0~
,0,0)';IN;
    'PE1_RX_DN'<12>:'(0,0,0,0,0,0,0,0,0,DV13,0,0,0,0,0,0,0,0,0,0,0,0,0,0,0,0,0,0~
,0,0)';IN;
    'PE1_RX_DN'<11>:'(0,0,0,0,0,0,0,0,0,DT13,0,0,0,0,0,0,0,0,0,0,0,0,0,0,0,0,0,0~
,0,0)';IN;
    'PE1_RX_DN'<10>:'(0,0,0,0,0,0,0,0,0,DT11,0,0,0,0,0,0,0,0,0,0,0,0,0,0,0,0,0,0~
,0,0)';IN;
    'PE1_RX_DN'<9>:'(0,0,0,0,0,0,0,0,0,DP11,0,0,0,0,0,0,0,0,0,0,0,0,0,0,0,0,0,0,~
0,0)';IN;
    'PE1_RX_DN'<8>:'(0,0,0,0,0,0,0,0,0,DM11,0,0,0,0,0,0,0,0,0,0,0,0,0,0,0,0,0,0,~
0,0)';IN;
    'PE1_RX_DN'<7>:'(0,0,0,0,0,0,0,0,0,DM9,0,0,0,0,0,0,0,0,0,0,0,0,0,0,0,0,0,0,0~
,0)';IN;
    'PE1_RX_DN'<6>:'(0,0,0,0,0,0,0,0,0,DK9,0,0,0,0,0,0,0,0,0,0,0,0,0,0,0,0,0,0,0~
,0)';IN;
    'PE1_RX_DN'<5>:'(0,0,0,0,0,0,0,0,0,DH9,0,0,0,0,0,0,0,0,0,0,0,0,0,0,0,0,0,0,0~
,0)';IN;
    'PE1_RX_DN'<4>:'(0,0,0,0,0,0,0,0,0,DE10,0,0,0,0,0,0,0,0,0,0,0,0,0,0,0,0,0,0,~
0,0)';IN;
    'PE1_RX_DN'<3>:'(0,0,0,0,0,0,0,0,0,DC10,0,0,0,0,0,0,0,0,0,0,0,0,0,0,0,0,0,0,~
0,0)';IN;
    'PE1_RX_DN'<2>:'(0,0,0,0,0,0,0,0,0,DC8,0,0,0,0,0,0,0,0,0,0,0,0,0,0,0,0,0,0,0~
,0)';IN;
    'PE1_RX_DN'<1>:'(0,0,0,0,0,0,0,0,0,DA8,0,0,0,0,0,0,0,0,0,0,0,0,0,0,0,0,0,0,0~
,0)';IN;
    'PE1_RX_DN'<0>:'(0,0,0,0,0,0,0,0,0,CW8,0,0,0,0,0,0,0,0,0,0,0,0,0,0,0,0,0,0,0~
,0)';IN;
    'PE1_RX_DP'<15>:'(0,0,0,0,0,0,0,0,0,DT15,0,0,0,0,0,0,0,0,0,0,0,0,0,0,0,0,0,0~
,0,0)';IN;
    'PE1_RX_DP'<14>:'(0,0,0,0,0,0,0,0,0,DV15,0,0,0,0,0,0,0,0,0,0,0,0,0,0,0,0,0,0~
,0,0)';IN;
    'PE1_RX_DP'<13>:'(0,0,0,0,0,0,0,0,0,DY13,0,0,0,0,0,0,0,0,0,0,0,0,0,0,0,0,0,0~
,0,0)';IN;
    'PE1_RX_DP'<12>:'(0,0,0,0,0,0,0,0,0,DU12,0,0,0,0,0,0,0,0,0,0,0,0,0,0,0,0,0,0~
,0,0)';IN;
    'PE1_RX_DP'<11>:'(0,0,0,0,0,0,0,0,0,DP13,0,0,0,0,0,0,0,0,0,0,0,0,0,0,0,0,0,0~
,0,0)';IN;
    'PE1_RX_DP'<10>:'(0,0,0,0,0,0,0,0,0,DR12,0,0,0,0,0,0,0,0,0,0,0,0,0,0,0,0,0,0~
,0,0)';IN;
    'PE1_RX_DP'<9>:'(0,0,0,0,0,0,0,0,0,DN10,0,0,0,0,0,0,0,0,0,0,0,0,0,0,0,0,0,0,~
0,0)';IN;
    'PE1_RX_DP'<8>:'(0,0,0,0,0,0,0,0,0,DK11,0,0,0,0,0,0,0,0,0,0,0,0,0,0,0,0,0,0,~
0,0)';IN;
    'PE1_RX_DP'<7>:'(0,0,0,0,0,0,0,0,0,DL10,0,0,0,0,0,0,0,0,0,0,0,0,0,0,0,0,0,0,~
0,0)';IN;
    'PE1_RX_DP'<6>:'(0,0,0,0,0,0,0,0,0,DJ8,0,0,0,0,0,0,0,0,0,0,0,0,0,0,0,0,0,0,0~
,0)';IN;
    'PE1_RX_DP'<5>:'(0,0,0,0,0,0,0,0,0,DF9,0,0,0,0,0,0,0,0,0,0,0,0,0,0,0,0,0,0,0~
,0)';IN;
    'PE1_RX_DP'<4>:'(0,0,0,0,0,0,0,0,0,DD9,0,0,0,0,0,0,0,0,0,0,0,0,0,0,0,0,0,0,0~
,0)';IN;
    'PE1_RX_DP'<3>:'(0,0,0,0,0,0,0,0,0,DA10,0,0,0,0,0,0,0,0,0,0,0,0,0,0,0,0,0,0,~
0,0)';IN;
    'PE1_RX_DP'<2>:'(0,0,0,0,0,0,0,0,0,DB9,0,0,0,0,0,0,0,0,0,0,0,0,0,0,0,0,0,0,0~
,0)';IN;
    'PE1_RX_DP'<1>:'(0,0,0,0,0,0,0,0,0,CY7,0,0,0,0,0,0,0,0,0,0,0,0,0,0,0,0,0,0,0~
,0)';IN;
    'PE1_RX_DP'<0>:'(0,0,0,0,0,0,0,0,0,CU8,0,0,0,0,0,0,0,0,0,0,0,0,0,0,0,0,0,0,0~
,0)';IN;
    'PE1_TX_DN'<15>:'(0,0,0,0,0,0,0,0,0,ED9,0,0,0,0,0,0,0,0,0,0,0,0,0,0,0,0,0,0,~
0,0)';OUT;
    'PE1_TX_DN'<14>:'(0,0,0,0,0,0,0,0,0,EA8,0,0,0,0,0,0,0,0,0,0,0,0,0,0,0,0,0,0,~
0,0)';OUT;
    'PE1_TX_DN'<13>:'(0,0,0,0,0,0,0,0,0,DY7,0,0,0,0,0,0,0,0,0,0,0,0,0,0,0,0,0,0,~
0,0)';OUT;
    'PE1_TX_DN'<12>:'(0,0,0,0,0,0,0,0,0,DV7,0,0,0,0,0,0,0,0,0,0,0,0,0,0,0,0,0,0,~
0,0)';OUT;
    'PE1_TX_DN'<11>:'(0,0,0,0,0,0,0,0,0,DU6,0,0,0,0,0,0,0,0,0,0,0,0,0,0,0,0,0,0,~
0,0)';OUT;
    'PE1_TX_DN'<10>:'(0,0,0,0,0,0,0,0,0,DW4,0,0,0,0,0,0,0,0,0,0,0,0,0,0,0,0,0,0,~
0,0)';OUT;
    'PE1_TX_DN'<9>:'(0,0,0,0,0,0,0,0,0,DV3,0,0,0,0,0,0,0,0,0,0,0,0,0,0,0,0,0,0,0~
,0)';OUT;
    'PE1_TX_DN'<8>:'(0,0,0,0,0,0,0,0,0,DT5,0,0,0,0,0,0,0,0,0,0,0,0,0,0,0,0,0,0,0~
,0)';OUT;
    'PE1_TX_DN'<7>:'(0,0,0,0,0,0,0,0,0,DN4,0,0,0,0,0,0,0,0,0,0,0,0,0,0,0,0,0,0,0~
,0)';OUT;
    'PE1_TX_DN'<6>:'(0,0,0,0,0,0,0,0,0,DM3,0,0,0,0,0,0,0,0,0,0,0,0,0,0,0,0,0,0,0~
,0)';OUT;
    'PE1_TX_DN'<5>:'(0,0,0,0,0,0,0,0,0,DK3,0,0,0,0,0,0,0,0,0,0,0,0,0,0,0,0,0,0,0~
,0)';OUT;
    'PE1_TX_DN'<4>:'(0,0,0,0,0,0,0,0,0,DG4,0,0,0,0,0,0,0,0,0,0,0,0,0,0,0,0,0,0,0~
,0)';OUT;
    'PE1_TX_DN'<3>:'(0,0,0,0,0,0,0,0,0,DE4,0,0,0,0,0,0,0,0,0,0,0,0,0,0,0,0,0,0,0~
,0)';OUT;
    'PE1_TX_DN'<2>:'(0,0,0,0,0,0,0,0,0,DE2,0,0,0,0,0,0,0,0,0,0,0,0,0,0,0,0,0,0,0~
,0)';OUT;
    'PE1_TX_DN'<1>:'(0,0,0,0,0,0,0,0,0,DC2,0,0,0,0,0,0,0,0,0,0,0,0,0,0,0,0,0,0,0~
,0)';OUT;
    'PE1_TX_DN'<0>:'(0,0,0,0,0,0,0,0,0,DA2,0,0,0,0,0,0,0,0,0,0,0,0,0,0,0,0,0,0,0~
,0)';OUT;
    'PE1_TX_DP'<15>:'(0,0,0,0,0,0,0,0,0,EC8,0,0,0,0,0,0,0,0,0,0,0,0,0,0,0,0,0,0,~
0,0)';OUT;
    'PE1_TX_DP'<14>:'(0,0,0,0,0,0,0,0,0,EB7,0,0,0,0,0,0,0,0,0,0,0,0,0,0,0,0,0,0,~
0,0)';OUT;
    'PE1_TX_DP'<13>:'(0,0,0,0,0,0,0,0,0,DW6,0,0,0,0,0,0,0,0,0,0,0,0,0,0,0,0,0,0,~
0,0)';OUT;
    'PE1_TX_DP'<12>:'(0,0,0,0,0,0,0,0,0,DT7,0,0,0,0,0,0,0,0,0,0,0,0,0,0,0,0,0,0,~
0,0)';OUT;
    'PE1_TX_DP'<11>:'(0,0,0,0,0,0,0,0,0,DV5,0,0,0,0,0,0,0,0,0,0,0,0,0,0,0,0,0,0,~
0,0)';OUT;
    'PE1_TX_DP'<10>:'(0,0,0,0,0,0,0,0,0,DU4,0,0,0,0,0,0,0,0,0,0,0,0,0,0,0,0,0,0,~
0,0)';OUT;
    'PE1_TX_DP'<9>:'(0,0,0,0,0,0,0,0,0,DU2,0,0,0,0,0,0,0,0,0,0,0,0,0,0,0,0,0,0,0~
,0)';OUT;
    'PE1_TX_DP'<8>:'(0,0,0,0,0,0,0,0,0,DR4,0,0,0,0,0,0,0,0,0,0,0,0,0,0,0,0,0,0,0~
,0)';OUT;
    'PE1_TX_DP'<7>:'(0,0,0,0,0,0,0,0,0,DP3,0,0,0,0,0,0,0,0,0,0,0,0,0,0,0,0,0,0,0~
,0)';OUT;
    'PE1_TX_DP'<6>:'(0,0,0,0,0,0,0,0,0,DL2,0,0,0,0,0,0,0,0,0,0,0,0,0,0,0,0,0,0,0~
,0)';OUT;
    'PE1_TX_DP'<5>:'(0,0,0,0,0,0,0,0,0,DH3,0,0,0,0,0,0,0,0,0,0,0,0,0,0,0,0,0,0,0~
,0)';OUT;
    'PE1_TX_DP'<4>:'(0,0,0,0,0,0,0,0,0,DF3,0,0,0,0,0,0,0,0,0,0,0,0,0,0,0,0,0,0,0~
,0)';OUT;
    'PE1_TX_DP'<3>:'(0,0,0,0,0,0,0,0,0,DC4,0,0,0,0,0,0,0,0,0,0,0,0,0,0,0,0,0,0,0~
,0)';OUT;
    'PE1_TX_DP'<2>:'(0,0,0,0,0,0,0,0,0,DD3,0,0,0,0,0,0,0,0,0,0,0,0,0,0,0,0,0,0,0~
,0)';OUT;
    'PE1_TX_DP'<1>:'(0,0,0,0,0,0,0,0,0,DB1,0,0,0,0,0,0,0,0,0,0,0,0,0,0,0,0,0,0,0~
,0)';OUT;
    'PE1_TX_DP'<0>:'(0,0,0,0,0,0,0,0,0,CW2,0,0,0,0,0,0,0,0,0,0,0,0,0,0,0,0,0,0,0~
,0)';OUT;
    'PE2_RX_DN'<15>:'(0,0,0,0,0,0,0,0,0,0,BK9,0,0,0,0,0,0,0,0,0,0,0,0,0,0,0,0,0,~
0,0)';IN;
    'PE2_RX_DN'<14>:'(0,0,0,0,0,0,0,0,0,0,BL8,0,0,0,0,0,0,0,0,0,0,0,0,0,0,0,0,0,~
0,0)';IN;
    'PE2_RX_DN'<13>:'(0,0,0,0,0,0,0,0,0,0,BN8,0,0,0,0,0,0,0,0,0,0,0,0,0,0,0,0,0,~
0,0)';IN;
    'PE2_RX_DN'<12>:'(0,0,0,0,0,0,0,0,0,0,BR8,0,0,0,0,0,0,0,0,0,0,0,0,0,0,0,0,0,~
0,0)';IN;
    'PE2_RX_DN'<11>:'(0,0,0,0,0,0,0,0,0,0,BT7,0,0,0,0,0,0,0,0,0,0,0,0,0,0,0,0,0,~
0,0)';IN;
    'PE2_RX_DN'<10>:'(0,0,0,0,0,0,0,0,0,0,BV7,0,0,0,0,0,0,0,0,0,0,0,0,0,0,0,0,0,~
0,0)';IN;
    'PE2_RX_DN'<9>:'(0,0,0,0,0,0,0,0,0,0,BY7,0,0,0,0,0,0,0,0,0,0,0,0,0,0,0,0,0,0~
,0)';IN;
    'PE2_RX_DN'<8>:'(0,0,0,0,0,0,0,0,0,0,BY9,0,0,0,0,0,0,0,0,0,0,0,0,0,0,0,0,0,0~
,0)';IN;
    'PE2_RX_DN'<7>:'(0,0,0,0,0,0,0,0,0,0,CE8,0,0,0,0,0,0,0,0,0,0,0,0,0,0,0,0,0,0~
,0)';IN;
    'PE2_RX_DN'<6>:'(0,0,0,0,0,0,0,0,0,0,CE6,0,0,0,0,0,0,0,0,0,0,0,0,0,0,0,0,0,0~
,0)';IN;
    'PE2_RX_DN'<5>:'(0,0,0,0,0,0,0,0,0,0,CG8,0,0,0,0,0,0,0,0,0,0,0,0,0,0,0,0,0,0~
,0)';IN;
    'PE2_RX_DN'<4>:'(0,0,0,0,0,0,0,0,0,0,CK7,0,0,0,0,0,0,0,0,0,0,0,0,0,0,0,0,0,0~
,0)';IN;
    'PE2_RX_DN'<3>:'(0,0,0,0,0,0,0,0,0,0,CM7,0,0,0,0,0,0,0,0,0,0,0,0,0,0,0,0,0,0~
,0)';IN;
    'PE2_RX_DN'<2>:'(0,0,0,0,0,0,0,0,0,0,CP7,0,0,0,0,0,0,0,0,0,0,0,0,0,0,0,0,0,0~
,0)';IN;
    'PE2_RX_DN'<1>:'(0,0,0,0,0,0,0,0,0,0,CP9,0,0,0,0,0,0,0,0,0,0,0,0,0,0,0,0,0,0~
,0)';IN;
    'PE2_RX_DN'<0>:'(0,0,0,0,0,0,0,0,0,0,CT9,0,0,0,0,0,0,0,0,0,0,0,0,0,0,0,0,0,0~
,0)';IN;
    'PE2_RX_DP'<15>:'(0,0,0,0,0,0,0,0,0,0,BJ10,0,0,0,0,0,0,0,0,0,0,0,0,0,0,0,0,0~
,0,0)';IN;
    'PE2_RX_DP'<14>:'(0,0,0,0,0,0,0,0,0,0,BJ8,0,0,0,0,0,0,0,0,0,0,0,0,0,0,0,0,0,~
0,0)';IN;
    'PE2_RX_DP'<13>:'(0,0,0,0,0,0,0,0,0,0,BM7,0,0,0,0,0,0,0,0,0,0,0,0,0,0,0,0,0,~
0,0)';IN;
    'PE2_RX_DP'<12>:'(0,0,0,0,0,0,0,0,0,0,BP9,0,0,0,0,0,0,0,0,0,0,0,0,0,0,0,0,0,~
0,0)';IN;
    'PE2_RX_DP'<11>:'(0,0,0,0,0,0,0,0,0,0,BP7,0,0,0,0,0,0,0,0,0,0,0,0,0,0,0,0,0,~
0,0)';IN;
    'PE2_RX_DP'<10>:'(0,0,0,0,0,0,0,0,0,0,BU6,0,0,0,0,0,0,0,0,0,0,0,0,0,0,0,0,0,~
0,0)';IN;
    'PE2_RX_DP'<9>:'(0,0,0,0,0,0,0,0,0,0,BW8,0,0,0,0,0,0,0,0,0,0,0,0,0,0,0,0,0,0~
,0)';IN;
    'PE2_RX_DP'<8>:'(0,0,0,0,0,0,0,0,0,0,BV9,0,0,0,0,0,0,0,0,0,0,0,0,0,0,0,0,0,0~
,0)';IN;
    'PE2_RX_DP'<7>:'(0,0,0,0,0,0,0,0,0,0,CC8,0,0,0,0,0,0,0,0,0,0,0,0,0,0,0,0,0,0~
,0)';IN;
    'PE2_RX_DP'<6>:'(0,0,0,0,0,0,0,0,0,0,CD7,0,0,0,0,0,0,0,0,0,0,0,0,0,0,0,0,0,0~
,0)';IN;
    'PE2_RX_DP'<5>:'(0,0,0,0,0,0,0,0,0,0,CF7,0,0,0,0,0,0,0,0,0,0,0,0,0,0,0,0,0,0~
,0)';IN;
    'PE2_RX_DP'<4>:'(0,0,0,0,0,0,0,0,0,0,CH7,0,0,0,0,0,0,0,0,0,0,0,0,0,0,0,0,0,0~
,0)';IN;
    'PE2_RX_DP'<3>:'(0,0,0,0,0,0,0,0,0,0,CL6,0,0,0,0,0,0,0,0,0,0,0,0,0,0,0,0,0,0~
,0)';IN;
    'PE2_RX_DP'<2>:'(0,0,0,0,0,0,0,0,0,0,CN8,0,0,0,0,0,0,0,0,0,0,0,0,0,0,0,0,0,0~
,0)';IN;
    'PE2_RX_DP'<1>:'(0,0,0,0,0,0,0,0,0,0,CM9,0,0,0,0,0,0,0,0,0,0,0,0,0,0,0,0,0,0~
,0)';IN;
    'PE2_RX_DP'<0>:'(0,0,0,0,0,0,0,0,0,0,CR8,0,0,0,0,0,0,0,0,0,0,0,0,0,0,0,0,0,0~
,0)';IN;
    'PE2_TX_DN'<15>:'(0,0,0,0,0,0,0,0,0,0,BM5,0,0,0,0,0,0,0,0,0,0,0,0,0,0,0,0,0,~
0,0)';OUT;
    'PE2_TX_DN'<14>:'(0,0,0,0,0,0,0,0,0,0,BL4,0,0,0,0,0,0,0,0,0,0,0,0,0,0,0,0,0,~
0,0)';OUT;
    'PE2_TX_DN'<13>:'(0,0,0,0,0,0,0,0,0,0,BP5,0,0,0,0,0,0,0,0,0,0,0,0,0,0,0,0,0,~
0,0)';OUT;
    'PE2_TX_DN'<12>:'(0,0,0,0,0,0,0,0,0,0,BU4,0,0,0,0,0,0,0,0,0,0,0,0,0,0,0,0,0,~
0,0)';OUT;
    'PE2_TX_DN'<11>:'(0,0,0,0,0,0,0,0,0,0,BW4,0,0,0,0,0,0,0,0,0,0,0,0,0,0,0,0,0,~
0,0)';OUT;
    'PE2_TX_DN'<10>:'(0,0,0,0,0,0,0,0,0,0,CA4,0,0,0,0,0,0,0,0,0,0,0,0,0,0,0,0,0,~
0,0)';OUT;
    'PE2_TX_DN'<9>:'(0,0,0,0,0,0,0,0,0,0,CB3,0,0,0,0,0,0,0,0,0,0,0,0,0,0,0,0,0,0~
,0)';OUT;
    'PE2_TX_DN'<8>:'(0,0,0,0,0,0,0,0,0,0,CC2,0,0,0,0,0,0,0,0,0,0,0,0,0,0,0,0,0,0~
,0)';OUT;
    'PE2_TX_DN'<7>:'(0,0,0,0,0,0,0,0,0,0,CF3,0,0,0,0,0,0,0,0,0,0,0,0,0,0,0,0,0,0~
,0)';OUT;
    'PE2_TX_DN'<6>:'(0,0,0,0,0,0,0,0,0,0,CG2,0,0,0,0,0,0,0,0,0,0,0,0,0,0,0,0,0,0~
,0)';OUT;
    'PE2_TX_DN'<5>:'(0,0,0,0,0,0,0,0,0,0,CL2,0,0,0,0,0,0,0,0,0,0,0,0,0,0,0,0,0,0~
,0)';OUT;
    'PE2_TX_DN'<4>:'(0,0,0,0,0,0,0,0,0,0,CM1,0,0,0,0,0,0,0,0,0,0,0,0,0,0,0,0,0,0~
,0)';OUT;
    'PE2_TX_DN'<3>:'(0,0,0,0,0,0,0,0,0,0,CT3,0,0,0,0,0,0,0,0,0,0,0,0,0,0,0,0,0,0~
,0)';OUT;
    'PE2_TX_DN'<2>:'(0,0,0,0,0,0,0,0,0,0,CT1,0,0,0,0,0,0,0,0,0,0,0,0,0,0,0,0,0,0~
,0)';OUT;
    'PE2_TX_DN'<1>:'(0,0,0,0,0,0,0,0,0,0,CV3,0,0,0,0,0,0,0,0,0,0,0,0,0,0,0,0,0,0~
,0)';OUT;
    'PE2_TX_DN'<0>:'(0,0,0,0,0,0,0,0,0,0,CY3,0,0,0,0,0,0,0,0,0,0,0,0,0,0,0,0,0,0~
,0)';OUT;
    'PE2_TX_DP'<15>:'(0,0,0,0,0,0,0,0,0,0,BK5,0,0,0,0,0,0,0,0,0,0,0,0,0,0,0,0,0,~
0,0)';OUT;
    'PE2_TX_DP'<14>:'(0,0,0,0,0,0,0,0,0,0,BM3,0,0,0,0,0,0,0,0,0,0,0,0,0,0,0,0,0,~
0,0)';OUT;
    'PE2_TX_DP'<13>:'(0,0,0,0,0,0,0,0,0,0,BN4,0,0,0,0,0,0,0,0,0,0,0,0,0,0,0,0,0,~
0,0)';OUT;
    'PE2_TX_DP'<12>:'(0,0,0,0,0,0,0,0,0,0,BR4,0,0,0,0,0,0,0,0,0,0,0,0,0,0,0,0,0,~
0,0)';OUT;
    'PE2_TX_DP'<11>:'(0,0,0,0,0,0,0,0,0,0,BV3,0,0,0,0,0,0,0,0,0,0,0,0,0,0,0,0,0,~
0,0)';OUT;
    'PE2_TX_DP'<10>:'(0,0,0,0,0,0,0,0,0,0,BY5,0,0,0,0,0,0,0,0,0,0,0,0,0,0,0,0,0,~
0,0)';OUT;
    'PE2_TX_DP'<9>:'(0,0,0,0,0,0,0,0,0,0,BY3,0,0,0,0,0,0,0,0,0,0,0,0,0,0,0,0,0,0~
,0)';OUT;
    'PE2_TX_DP'<8>:'(0,0,0,0,0,0,0,0,0,0,CD3,0,0,0,0,0,0,0,0,0,0,0,0,0,0,0,0,0,0~
,0)';OUT;
    'PE2_TX_DP'<7>:'(0,0,0,0,0,0,0,0,0,0,CE4,0,0,0,0,0,0,0,0,0,0,0,0,0,0,0,0,0,0~
,0)';OUT;
    'PE2_TX_DP'<6>:'(0,0,0,0,0,0,0,0,0,0,CE2,0,0,0,0,0,0,0,0,0,0,0,0,0,0,0,0,0,0~
,0)';OUT;
    'PE2_TX_DP'<5>:'(0,0,0,0,0,0,0,0,0,0,CK3,0,0,0,0,0,0,0,0,0,0,0,0,0,0,0,0,0,0~
,0)';OUT;
    'PE2_TX_DP'<4>:'(0,0,0,0,0,0,0,0,0,0,CK1,0,0,0,0,0,0,0,0,0,0,0,0,0,0,0,0,0,0~
,0)';OUT;
    'PE2_TX_DP'<3>:'(0,0,0,0,0,0,0,0,0,0,CP3,0,0,0,0,0,0,0,0,0,0,0,0,0,0,0,0,0,0~
,0)';OUT;
    'PE2_TX_DP'<2>:'(0,0,0,0,0,0,0,0,0,0,CR2,0,0,0,0,0,0,0,0,0,0,0,0,0,0,0,0,0,0~
,0)';OUT;
    'PE2_TX_DP'<1>:'(0,0,0,0,0,0,0,0,0,0,CU2,0,0,0,0,0,0,0,0,0,0,0,0,0,0,0,0,0,0~
,0)';OUT;
    'PE2_TX_DP'<0>:'(0,0,0,0,0,0,0,0,0,0,CW4,0,0,0,0,0,0,0,0,0,0,0,0,0,0,0,0,0,0~
,0)';OUT;
    'PE3_RBIAS'<1>:'(CR30,0,0,0,0,0,0,0,0,0,0,0,0,0,0,0,0,0,0,0,0,0,0,0,0,0,0,0,~
0,0)';IN;
    'PE3_RBIAS'<0>:'(CP29,0,0,0,0,0,0,0,0,0,0,0,0,0,0,0,0,0,0,0,0,0,0,0,0,0,0,0,~
0,0)';IN;
    'PE3_RX_DN'<15>:'(0,0,0,0,0,0,0,0,0,0,0,CV9,0,0,0,0,0,0,0,0,0,0,0,0,0,0,0,0,~
0,0)';IN;
    'PE3_RX_DN'<14>:'(0,0,0,0,0,0,0,0,0,0,0,CY11,0,0,0,0,0,0,0,0,0,0,0,0,0,0,0,0~
,0,0)';IN;
    'PE3_RX_DN'<13>:'(0,0,0,0,0,0,0,0,0,0,0,DB11,0,0,0,0,0,0,0,0,0,0,0,0,0,0,0,0~
,0,0)';IN;
    'PE3_RX_DN'<12>:'(0,0,0,0,0,0,0,0,0,0,0,DD13,0,0,0,0,0,0,0,0,0,0,0,0,0,0,0,0~
,0,0)';IN;
    'PE3_RX_DN'<11>:'(0,0,0,0,0,0,0,0,0,0,0,DG10,0,0,0,0,0,0,0,0,0,0,0,0,0,0,0,0~
,0,0)';IN;
    'PE3_RX_DN'<10>:'(0,0,0,0,0,0,0,0,0,0,0,DG12,0,0,0,0,0,0,0,0,0,0,0,0,0,0,0,0~
,0,0)';IN;
    'PE3_RX_DN'<9>:'(0,0,0,0,0,0,0,0,0,0,0,DJ12,0,0,0,0,0,0,0,0,0,0,0,0,0,0,0,0,~
0,0)';IN;
    'PE3_RX_DN'<8>:'(0,0,0,0,0,0,0,0,0,0,0,DL12,0,0,0,0,0,0,0,0,0,0,0,0,0,0,0,0,~
0,0)';IN;
    'PE3_RX_DN'<7>:'(0,0,0,0,0,0,0,0,0,0,0,DL14,0,0,0,0,0,0,0,0,0,0,0,0,0,0,0,0,~
0,0)';IN;
    'PE3_RX_DN'<6>:'(0,0,0,0,0,0,0,0,0,0,0,DN14,0,0,0,0,0,0,0,0,0,0,0,0,0,0,0,0,~
0,0)';IN;
    'PE3_RX_DN'<5>:'(0,0,0,0,0,0,0,0,0,0,0,DR14,0,0,0,0,0,0,0,0,0,0,0,0,0,0,0,0,~
0,0)';IN;
    'PE3_RX_DN'<4>:'(0,0,0,0,0,0,0,0,0,0,0,DR16,0,0,0,0,0,0,0,0,0,0,0,0,0,0,0,0,~
0,0)';IN;
    'PE3_RX_DN'<3>:'(0,0,0,0,0,0,0,0,0,0,0,DT19,0,0,0,0,0,0,0,0,0,0,0,0,0,0,0,0,~
0,0)';IN;
    'PE3_RX_DN'<2>:'(0,0,0,0,0,0,0,0,0,0,0,DW16,0,0,0,0,0,0,0,0,0,0,0,0,0,0,0,0,~
0,0)';IN;
    'PE3_RX_DN'<1>:'(0,0,0,0,0,0,0,0,0,0,0,DW18,0,0,0,0,0,0,0,0,0,0,0,0,0,0,0,0,~
0,0)';IN;
    'PE3_RX_DN'<0>:'(0,0,0,0,0,0,0,0,0,0,0,EA18,0,0,0,0,0,0,0,0,0,0,0,0,0,0,0,0,~
0,0)';IN;
    'PE3_RX_DP'<15>:'(0,0,0,0,0,0,0,0,0,0,0,CU10,0,0,0,0,0,0,0,0,0,0,0,0,0,0,0,0~
,0,0)';IN;
    'PE3_RX_DP'<14>:'(0,0,0,0,0,0,0,0,0,0,0,CW10,0,0,0,0,0,0,0,0,0,0,0,0,0,0,0,0~
,0,0)';IN;
    'PE3_RX_DP'<13>:'(0,0,0,0,0,0,0,0,0,0,0,DA12,0,0,0,0,0,0,0,0,0,0,0,0,0,0,0,0~
,0,0)';IN;
    'PE3_RX_DP'<12>:'(0,0,0,0,0,0,0,0,0,0,0,DC12,0,0,0,0,0,0,0,0,0,0,0,0,0,0,0,0~
,0,0)';IN;
    'PE3_RX_DP'<11>:'(0,0,0,0,0,0,0,0,0,0,0,DF11,0,0,0,0,0,0,0,0,0,0,0,0,0,0,0,0~
,0,0)';IN;
    'PE3_RX_DP'<10>:'(0,0,0,0,0,0,0,0,0,0,0,DE12,0,0,0,0,0,0,0,0,0,0,0,0,0,0,0,0~
,0,0)';IN;
    'PE3_RX_DP'<9>:'(0,0,0,0,0,0,0,0,0,0,0,DH11,0,0,0,0,0,0,0,0,0,0,0,0,0,0,0,0,~
0,0)';IN;
    'PE3_RX_DP'<8>:'(0,0,0,0,0,0,0,0,0,0,0,DK13,0,0,0,0,0,0,0,0,0,0,0,0,0,0,0,0,~
0,0)';IN;
    'PE3_RX_DP'<7>:'(0,0,0,0,0,0,0,0,0,0,0,DJ14,0,0,0,0,0,0,0,0,0,0,0,0,0,0,0,0,~
0,0)';IN;
    'PE3_RX_DP'<6>:'(0,0,0,0,0,0,0,0,0,0,0,DM13,0,0,0,0,0,0,0,0,0,0,0,0,0,0,0,0,~
0,0)';IN;
    'PE3_RX_DP'<5>:'(0,0,0,0,0,0,0,0,0,0,0,DP15,0,0,0,0,0,0,0,0,0,0,0,0,0,0,0,0,~
0,0)';IN;
    'PE3_RX_DP'<4>:'(0,0,0,0,0,0,0,0,0,0,0,DN16,0,0,0,0,0,0,0,0,0,0,0,0,0,0,0,0,~
0,0)';IN;
    'PE3_RX_DP'<3>:'(0,0,0,0,0,0,0,0,0,0,0,DR18,0,0,0,0,0,0,0,0,0,0,0,0,0,0,0,0,~
0,0)';IN;
    'PE3_RX_DP'<2>:'(0,0,0,0,0,0,0,0,0,0,0,DV17,0,0,0,0,0,0,0,0,0,0,0,0,0,0,0,0,~
0,0)';IN;
    'PE3_RX_DP'<1>:'(0,0,0,0,0,0,0,0,0,0,0,DU18,0,0,0,0,0,0,0,0,0,0,0,0,0,0,0,0,~
0,0)';IN;
    'PE3_RX_DP'<0>:'(0,0,0,0,0,0,0,0,0,0,0,DY17,0,0,0,0,0,0,0,0,0,0,0,0,0,0,0,0,~
0,0)';IN;
    'PE3_TX_DN'<15>:'(0,0,0,0,0,0,0,0,0,0,0,CY5,0,0,0,0,0,0,0,0,0,0,0,0,0,0,0,0,~
0,0)';OUT;
    'PE3_TX_DN'<14>:'(0,0,0,0,0,0,0,0,0,0,0,DB5,0,0,0,0,0,0,0,0,0,0,0,0,0,0,0,0,~
0,0)';OUT;
    'PE3_TX_DN'<13>:'(0,0,0,0,0,0,0,0,0,0,0,DD5,0,0,0,0,0,0,0,0,0,0,0,0,0,0,0,0,~
0,0)';OUT;
    'PE3_TX_DN'<12>:'(0,0,0,0,0,0,0,0,0,0,0,DJ6,0,0,0,0,0,0,0,0,0,0,0,0,0,0,0,0,~
0,0)';OUT;
    'PE3_TX_DN'<11>:'(0,0,0,0,0,0,0,0,0,0,0,DJ4,0,0,0,0,0,0,0,0,0,0,0,0,0,0,0,0,~
0,0)';OUT;
    'PE3_TX_DN'<10>:'(0,0,0,0,0,0,0,0,0,0,0,DL6,0,0,0,0,0,0,0,0,0,0,0,0,0,0,0,0,~
0,0)';OUT;
    'PE3_TX_DN'<9>:'(0,0,0,0,0,0,0,0,0,0,0,DP5,0,0,0,0,0,0,0,0,0,0,0,0,0,0,0,0,0~
,0)';OUT;
    'PE3_TX_DN'<8>:'(0,0,0,0,0,0,0,0,0,0,0,DM7,0,0,0,0,0,0,0,0,0,0,0,0,0,0,0,0,0~
,0)';OUT;
    'PE3_TX_DN'<7>:'(0,0,0,0,0,0,0,0,0,0,0,DR8,0,0,0,0,0,0,0,0,0,0,0,0,0,0,0,0,0~
,0)';OUT;
    'PE3_TX_DN'<6>:'(0,0,0,0,0,0,0,0,0,0,0,DU8,0,0,0,0,0,0,0,0,0,0,0,0,0,0,0,0,0~
,0)';OUT;
    'PE3_TX_DN'<5>:'(0,0,0,0,0,0,0,0,0,0,0,DW10,0,0,0,0,0,0,0,0,0,0,0,0,0,0,0,0,~
0,0)';OUT;
    'PE3_TX_DN'<4>:'(0,0,0,0,0,0,0,0,0,0,0,EB9,0,0,0,0,0,0,0,0,0,0,0,0,0,0,0,0,0~
,0)';OUT;
    'PE3_TX_DN'<3>:'(0,0,0,0,0,0,0,0,0,0,0,DY11,0,0,0,0,0,0,0,0,0,0,0,0,0,0,0,0,~
0,0)';OUT;
    'PE3_TX_DN'<2>:'(0,0,0,0,0,0,0,0,0,0,0,EC12,0,0,0,0,0,0,0,0,0,0,0,0,0,0,0,0,~
0,0)';OUT;
    'PE3_TX_DN'<1>:'(0,0,0,0,0,0,0,0,0,0,0,EE12,0,0,0,0,0,0,0,0,0,0,0,0,0,0,0,0,~
0,0)';OUT;
    'PE3_TX_DN'<0>:'(0,0,0,0,0,0,0,0,0,0,0,EE14,0,0,0,0,0,0,0,0,0,0,0,0,0,0,0,0,~
0,0)';OUT;
    'PE3_TX_DP'<15>:'(0,0,0,0,0,0,0,0,0,0,0,CV5,0,0,0,0,0,0,0,0,0,0,0,0,0,0,0,0,~
0,0)';OUT;
    'PE3_TX_DP'<14>:'(0,0,0,0,0,0,0,0,0,0,0,DA4,0,0,0,0,0,0,0,0,0,0,0,0,0,0,0,0,~
0,0)';OUT;
    'PE3_TX_DP'<13>:'(0,0,0,0,0,0,0,0,0,0,0,DC6,0,0,0,0,0,0,0,0,0,0,0,0,0,0,0,0,~
0,0)';OUT;
    'PE3_TX_DP'<12>:'(0,0,0,0,0,0,0,0,0,0,0,DG6,0,0,0,0,0,0,0,0,0,0,0,0,0,0,0,0,~
0,0)';OUT;
    'PE3_TX_DP'<11>:'(0,0,0,0,0,0,0,0,0,0,0,DH5,0,0,0,0,0,0,0,0,0,0,0,0,0,0,0,0,~
0,0)';OUT;
    'PE3_TX_DP'<10>:'(0,0,0,0,0,0,0,0,0,0,0,DK5,0,0,0,0,0,0,0,0,0,0,0,0,0,0,0,0,~
0,0)';OUT;
    'PE3_TX_DP'<9>:'(0,0,0,0,0,0,0,0,0,0,0,DM5,0,0,0,0,0,0,0,0,0,0,0,0,0,0,0,0,0~
,0)';OUT;
    'PE3_TX_DP'<8>:'(0,0,0,0,0,0,0,0,0,0,0,DN6,0,0,0,0,0,0,0,0,0,0,0,0,0,0,0,0,0~
,0)';OUT;
    'PE3_TX_DP'<7>:'(0,0,0,0,0,0,0,0,0,0,0,DP7,0,0,0,0,0,0,0,0,0,0,0,0,0,0,0,0,0~
,0)';OUT;
    'PE3_TX_DP'<6>:'(0,0,0,0,0,0,0,0,0,0,0,DT9,0,0,0,0,0,0,0,0,0,0,0,0,0,0,0,0,0~
,0)';OUT;
    'PE3_TX_DP'<5>:'(0,0,0,0,0,0,0,0,0,0,0,DV9,0,0,0,0,0,0,0,0,0,0,0,0,0,0,0,0,0~
,0)';OUT;
    'PE3_TX_DP'<4>:'(0,0,0,0,0,0,0,0,0,0,0,DY9,0,0,0,0,0,0,0,0,0,0,0,0,0,0,0,0,0~
,0)';OUT;
    'PE3_TX_DP'<3>:'(0,0,0,0,0,0,0,0,0,0,0,EA10,0,0,0,0,0,0,0,0,0,0,0,0,0,0,0,0,~
0,0)';OUT;
    'PE3_TX_DP'<2>:'(0,0,0,0,0,0,0,0,0,0,0,EB11,0,0,0,0,0,0,0,0,0,0,0,0,0,0,0,0,~
0,0)';OUT;
    'PE3_TX_DP'<1>:'(0,0,0,0,0,0,0,0,0,0,0,ED13,0,0,0,0,0,0,0,0,0,0,0,0,0,0,0,0,~
0,0)';OUT;
    'PE3_TX_DP'<0>:'(0,0,0,0,0,0,0,0,0,0,0,EC14,0,0,0,0,0,0,0,0,0,0,0,0,0,0,0,0,~
0,0)';OUT;
    'PECI':'(AU12,0,0,0,0,0,0,0,0,0,0,0,0,0,0,0,0,0,0,0,0,0,0,0,0,0,0,0,0,0)';$S~
;BIDI;
    'PE_HP_SCL':'(AM19,0,0,0,0,0,0,0,0,0,0,0,0,0,0,0,0,0,0,0,0,0,0,0,0,0,0,0,0,0~
)';$S;BIDI;
    'PE_HP_SDA':'(AL18,0,0,0,0,0,0,0,0,0,0,0,0,0,0,0,0,0,0,0,0,0,0,0,0,0,0,0,0,0~
)';$S;BIDI;
    'PIROM_ADDR'<2>:'(CW56,0,0,0,0,0,0,0,0,0,0,0,0,0,0,0,0,0,0,0,0,0,0,0,0,0,0,0~
,0,0)';BIDI;
    'PIROM_ADDR'<1>:'(CV57,0,0,0,0,0,0,0,0,0,0,0,0,0,0,0,0,0,0,0,0,0,0,0,0,0,0,0~
,0,0)';BIDI;
    'PIROM_ADDR'<0>:'(CU58,0,0,0,0,0,0,0,0,0,0,0,0,0,0,0,0,0,0,0,0,0,0,0,0,0,0,0~
,0,0)';BIDI;
    'PKGID'<2>:'(DA72,0,0,0,0,0,0,0,0,0,0,0,0,0,0,0,0,0,0,0,0,0,0,0,0,0,0,0,0,0)~
';BIDI;
    'PKGID'<1>:'(CW72,0,0,0,0,0,0,0,0,0,0,0,0,0,0,0,0,0,0,0,0,0,0,0,0,0,0,0,0,0)~
';BIDI;
    'PKGID'<0>:'(DC72,0,0,0,0,0,0,0,0,0,0,0,0,0,0,0,0,0,0,0,0,0,0,0,0,0,0,0,0,0)~
';BIDI;
    'PMSYNC':'(AR14,0,0,0,0,0,0,0,0,0,0,0,0,0,0,0,0,0,0,0,0,0,0,0,0,0,0,0,0,0)';~
$S;IN;
    'PMSYNC_CLK':'(AT19,0,0,0,0,0,0,0,0,0,0,0,0,0,0,0,0,0,0,0,0,0,0,0,0,0,0,0,0,~
0)';$S;IN;
    'PM_FAST_WAKE_N':'(AF15,0,0,0,0,0,0,0,0,0,0,0,0,0,0,0,0,0,0,0,0,0,0,0,0,0,0,~
0,0,0)';$S;BIDI;
    'PRDY_N':'(AG16,0,0,0,0,0,0,0,0,0,0,0,0,0,0,0,0,0,0,0,0,0,0,0,0,0,0,0,0,0)';~
$S;OUT;
    'PREQ_N':'(AR12,0,0,0,0,0,0,0,0,0,0,0,0,0,0,0,0,0,0,0,0,0,0,0,0,0,0,0,0,0)';~
$S;IN;
    'PROCDIS_N':'(AB17,0,0,0,0,0,0,0,0,0,0,0,0,0,0,0,0,0,0,0,0,0,0,0,0,0,0,0,0,0~
)';$S;IN;
    'PROCHOT_N':'(AC16,0,0,0,0,0,0,0,0,0,0,0,0,0,0,0,0,0,0,0,0,0,0,0,0,0,0,0,0,0~
)';$S;BIDI;
    'PROC_ID'<1>:'(DB71,0,0,0,0,0,0,0,0,0,0,0,0,0,0,0,0,0,0,0,0,0,0,0,0,0,0,0,0,~
0)';OUT;
    'PROC_ID'<0>:'(CY71,0,0,0,0,0,0,0,0,0,0,0,0,0,0,0,0,0,0,0,0,0,0,0,0,0,0,0,0,~
0)';OUT;
    'PWRGOOD':'(BC24,0,0,0,0,0,0,0,0,0,0,0,0,0,0,0,0,0,0,0,0,0,0,0,0,0,0,0,0,0)';$S;IN;
    'PWR_DEBUG_N':'(0,AP17,0,0,0,0,0,0,0,0,0,0,0,0,0,0,0,0,0,0,0,0,0,0,0,0,0,0,0~
,0)';$S;IN;
    'RESET_N':'(AP21,0,0,0,0,0,0,0,0,0,0,0,0,0,0,0,0,0,0,0,0,0,0,0,0,0,0,0,0,0)';$S;IN;
    'RSVD'<304>:'(0,A4,0,0,0,0,0,0,0,0,0,0,0,0,0,0,0,0,0,0,0,0,0,0,0,0,0,0,0,0)';BIDI;
    'RSVD'<303>:'(0,A6,0,0,0,0,0,0,0,0,0,0,0,0,0,0,0,0,0,0,0,0,0,0,0,0,0,0,0,0)';BIDI;
    'RSVD'<302>:'(0,A14,0,0,0,0,0,0,0,0,0,0,0,0,0,0,0,0,0,0,0,0,0,0,0,0,0,0,0,0)~
';BIDI;
    'RSVD'<301>:'(0,A16,0,0,0,0,0,0,0,0,0,0,0,0,0,0,0,0,0,0,0,0,0,0,0,0,0,0,0,0)~
';BIDI;
    'RSVD'<300>:'(0,A24,0,0,0,0,0,0,0,0,0,0,0,0,0,0,0,0,0,0,0,0,0,0,0,0,0,0,0,0)~
';BIDI;
    'RSVD'<299>:'(0,B3,0,0,0,0,0,0,0,0,0,0,0,0,0,0,0,0,0,0,0,0,0,0,0,0,0,0,0,0)';BIDI;
    'RSVD'<298>:'(0,B7,0,0,0,0,0,0,0,0,0,0,0,0,0,0,0,0,0,0,0,0,0,0,0,0,0,0,0,0)';BIDI;
    'RSVD'<296>:'(0,B13,0,0,0,0,0,0,0,0,0,0,0,0,0,0,0,0,0,0,0,0,0,0,0,0,0,0,0,0)~
';BIDI;
    'RSVD'<295>:'(0,B15,0,0,0,0,0,0,0,0,0,0,0,0,0,0,0,0,0,0,0,0,0,0,0,0,0,0,0,0)~
';BIDI;
    'RSVD'<294>:'(0,B17,0,0,0,0,0,0,0,0,0,0,0,0,0,0,0,0,0,0,0,0,0,0,0,0,0,0,0,0)~
';BIDI;
    'RSVD'<293>:'(0,B77,0,0,0,0,0,0,0,0,0,0,0,0,0,0,0,0,0,0,0,0,0,0,0,0,0,0,0,0)~
';BIDI;
    'RSVD'<292>:'(0,B81,0,0,0,0,0,0,0,0,0,0,0,0,0,0,0,0,0,0,0,0,0,0,0,0,0,0,0,0)~
';BIDI;
    'RSVD'<291>:'(0,C6,0,0,0,0,0,0,0,0,0,0,0,0,0,0,0,0,0,0,0,0,0,0,0,0,0,0,0,0)';BIDI;
    'RSVD'<290>:'(0,C18,0,0,0,0,0,0,0,0,0,0,0,0,0,0,0,0,0,0,0,0,0,0,0,0,0,0,0,0)~
';BIDI;
    'RSVD'<289>:'(0,C24,0,0,0,0,0,0,0,0,0,0,0,0,0,0,0,0,0,0,0,0,0,0,0,0,0,0,0,0)~
';BIDI;
    'RSVD'<288>:'(0,C82,0,0,0,0,0,0,0,0,0,0,0,0,0,0,0,0,0,0,0,0,0,0,0,0,0,0,0,0)~
';BIDI;
    'RSVD'<287>:'(0,D5,0,0,0,0,0,0,0,0,0,0,0,0,0,0,0,0,0,0,0,0,0,0,0,0,0,0,0,0)';BIDI;
    'RSVD'<286>:'(0,D17,0,0,0,0,0,0,0,0,0,0,0,0,0,0,0,0,0,0,0,0,0,0,0,0,0,0,0,0)~
';BIDI;
    'RSVD'<285>:'(0,D65,0,0,0,0,0,0,0,0,0,0,0,0,0,0,0,0,0,0,0,0,0,0,0,0,0,0,0,0)~
';BIDI;
    'RSVD'<284>:'(0,D83,0,0,0,0,0,0,0,0,0,0,0,0,0,0,0,0,0,0,0,0,0,0,0,0,0,0,0,0)~
';BIDI;
    'RSVD'<283>:'(0,E2,0,0,0,0,0,0,0,0,0,0,0,0,0,0,0,0,0,0,0,0,0,0,0,0,0,0,0,0)';BIDI;
    'RSVD'<282>:'(0,E4,0,0,0,0,0,0,0,0,0,0,0,0,0,0,0,0,0,0,0,0,0,0,0,0,0,0,0,0)';BIDI;
    'RSVD'<281>:'(0,E24,0,0,0,0,0,0,0,0,0,0,0,0,0,0,0,0,0,0,0,0,0,0,0,0,0,0,0,0)~
';BIDI;
    'RSVD'<280>:'(0,E84,0,0,0,0,0,0,0,0,0,0,0,0,0,0,0,0,0,0,0,0,0,0,0,0,0,0,0,0)~
';BIDI;
    'RSVD'<279>:'(0,F3,0,0,0,0,0,0,0,0,0,0,0,0,0,0,0,0,0,0,0,0,0,0,0,0,0,0,0,0)';BIDI;
    'RSVD'<278>:'(0,F23,0,0,0,0,0,0,0,0,0,0,0,0,0,0,0,0,0,0,0,0,0,0,0,0,0,0,0,0)~
';BIDI;
    'RSVD'<277>:'(0,F65,0,0,0,0,0,0,0,0,0,0,0,0,0,0,0,0,0,0,0,0,0,0,0,0,0,0,0,0)~
';BIDI;
    'RSVD'<276>:'(0,F83,0,0,0,0,0,0,0,0,0,0,0,0,0,0,0,0,0,0,0,0,0,0,0,0,0,0,0,0)~
';BIDI;
    'RSVD'<275>:'(0,G2,0,0,0,0,0,0,0,0,0,0,0,0,0,0,0,0,0,0,0,0,0,0,0,0,0,0,0,0)';BIDI;
    'RSVD'<274>:'(0,G64,0,0,0,0,0,0,0,0,0,0,0,0,0,0,0,0,0,0,0,0,0,0,0,0,0,0,0,0)~
';BIDI;
    'RSVD'<273>:'(0,G84,0,0,0,0,0,0,0,0,0,0,0,0,0,0,0,0,0,0,0,0,0,0,0,0,0,0,0,0)~
';BIDI;
    'RSVD'<272>:'(0,H1,0,0,0,0,0,0,0,0,0,0,0,0,0,0,0,0,0,0,0,0,0,0,0,0,0,0,0,0)';BIDI;
    'RSVD'<271>:'(0,H83,0,0,0,0,0,0,0,0,0,0,0,0,0,0,0,0,0,0,0,0,0,0,0,0,0,0,0,0)~
';BIDI;
    'RSVD'<270>:'(0,H85,0,0,0,0,0,0,0,0,0,0,0,0,0,0,0,0,0,0,0,0,0,0,0,0,0,0,0,0)~
';BIDI;
    'RSVD'<269>:'(0,J46,0,0,0,0,0,0,0,0,0,0,0,0,0,0,0,0,0,0,0,0,0,0,0,0,0,0,0,0)~
';BIDI;
    'RSVD'<268>:'(0,J62,0,0,0,0,0,0,0,0,0,0,0,0,0,0,0,0,0,0,0,0,0,0,0,0,0,0,0,0)~
';BIDI;
    'RSVD'<267>:'(0,K61,0,0,0,0,0,0,0,0,0,0,0,0,0,0,0,0,0,0,0,0,0,0,0,0,0,0,0,0)~
';BIDI;
    'RSVD'<266>:'(0,M63,0,0,0,0,0,0,0,0,0,0,0,0,0,0,0,0,0,0,0,0,0,0,0,0,0,0,0,0)~
';BIDI;
    'RSVD'<265>:'(0,P65,0,0,0,0,0,0,0,0,0,0,0,0,0,0,0,0,0,0,0,0,0,0,0,0,0,0,0,0)~
';BIDI;
    'RSVD'<264>:'(0,R62,0,0,0,0,0,0,0,0,0,0,0,0,0,0,0,0,0,0,0,0,0,0,0,0,0,0,0,0)~
';BIDI;
    'RSVD'<263>:'(0,R66,0,0,0,0,0,0,0,0,0,0,0,0,0,0,0,0,0,0,0,0,0,0,0,0,0,0,0,0)~
';BIDI;
    'RSVD'<262>:'(0,T67,0,0,0,0,0,0,0,0,0,0,0,0,0,0,0,0,0,0,0,0,0,0,0,0,0,0,0,0)~
';BIDI;
    'RSVD'<261>:'(0,U66,0,0,0,0,0,0,0,0,0,0,0,0,0,0,0,0,0,0,0,0,0,0,0,0,0,0,0,0)~
';BIDI;
    'RSVD'<260>:'(0,V65,0,0,0,0,0,0,0,0,0,0,0,0,0,0,0,0,0,0,0,0,0,0,0,0,0,0,0,0)~
';BIDI;
    'RSVD'<259>:'(0,V67,0,0,0,0,0,0,0,0,0,0,0,0,0,0,0,0,0,0,0,0,0,0,0,0,0,0,0,0)~
';BIDI;
    'RSVD'<258>:'(0,W66,0,0,0,0,0,0,0,0,0,0,0,0,0,0,0,0,0,0,0,0,0,0,0,0,0,0,0,0)~
';BIDI;
    'RSVD'<257>:'(0,Y23,0,0,0,0,0,0,0,0,0,0,0,0,0,0,0,0,0,0,0,0,0,0,0,0,0,0,0,0)~
';BIDI;
    'RSVD'<256>:'(0,Y65,0,0,0,0,0,0,0,0,0,0,0,0,0,0,0,0,0,0,0,0,0,0,0,0,0,0,0,0)~
';BIDI;
    'RSVD'<255>:'(0,0,0,0,0,0,0,0,0,0,0,0,0,0,0,AY83,0,0,0,0,0,0,0,0,0,0,0,0,0,0~
)';BIDI;
    'RSVD'<254>:'(0,AD47,0,0,0,0,0,0,0,0,0,0,0,0,0,0,0,0,0,0,0,0,0,0,0,0,0,0,0,0~
)';BIDI;
    'RSVD'<253>:'(0,AD49,0,0,0,0,0,0,0,0,0,0,0,0,0,0,0,0,0,0,0,0,0,0,0,0,0,0,0,0~
)';BIDI;
    'RSVD'<252>:'(0,AD51,0,0,0,0,0,0,0,0,0,0,0,0,0,0,0,0,0,0,0,0,0,0,0,0,0,0,0,0~
)';BIDI;
    'RSVD'<251>:'(0,AE46,0,0,0,0,0,0,0,0,0,0,0,0,0,0,0,0,0,0,0,0,0,0,0,0,0,0,0,0~
)';BIDI;
    'RSVD'<250>:'(0,AE48,0,0,0,0,0,0,0,0,0,0,0,0,0,0,0,0,0,0,0,0,0,0,0,0,0,0,0,0~
)';BIDI;
    'RSVD'<249>:'(0,AE50,0,0,0,0,0,0,0,0,0,0,0,0,0,0,0,0,0,0,0,0,0,0,0,0,0,0,0,0~
)';BIDI;
    'RSVD'<248>:'(0,AE52,0,0,0,0,0,0,0,0,0,0,0,0,0,0,0,0,0,0,0,0,0,0,0,0,0,0,0,0~
)';BIDI;
    'RSVD'<247>:'(0,AE72,0,0,0,0,0,0,0,0,0,0,0,0,0,0,0,0,0,0,0,0,0,0,0,0,0,0,0,0~
)';BIDI;
    'RSVD'<246>:'(0,AF19,0,0,0,0,0,0,0,0,0,0,0,0,0,0,0,0,0,0,0,0,0,0,0,0,0,0,0,0~
)';BIDI;
    'RSVD'<245>:'(0,AF47,0,0,0,0,0,0,0,0,0,0,0,0,0,0,0,0,0,0,0,0,0,0,0,0,0,0,0,0~
)';BIDI;
    'RSVD'<244>:'(0,AF49,0,0,0,0,0,0,0,0,0,0,0,0,0,0,0,0,0,0,0,0,0,0,0,0,0,0,0,0~
)';BIDI;
    'RSVD'<243>:'(0,AF51,0,0,0,0,0,0,0,0,0,0,0,0,0,0,0,0,0,0,0,0,0,0,0,0,0,0,0,0~
)';BIDI;
    'RSVD'<242>:'(0,AF53,0,0,0,0,0,0,0,0,0,0,0,0,0,0,0,0,0,0,0,0,0,0,0,0,0,0,0,0~
)';BIDI;
    'RSVD'<241>:'(0,AF71,0,0,0,0,0,0,0,0,0,0,0,0,0,0,0,0,0,0,0,0,0,0,0,0,0,0,0,0~
)';BIDI;
    'RSVD'<240>:'(0,AG20,0,0,0,0,0,0,0,0,0,0,0,0,0,0,0,0,0,0,0,0,0,0,0,0,0,0,0,0~
)';BIDI;
    'RSVD'<239>:'(0,AG48,0,0,0,0,0,0,0,0,0,0,0,0,0,0,0,0,0,0,0,0,0,0,0,0,0,0,0,0~
)';BIDI;
    'RSVD'<238>:'(0,AG50,0,0,0,0,0,0,0,0,0,0,0,0,0,0,0,0,0,0,0,0,0,0,0,0,0,0,0,0~
)';BIDI;
    'RSVD'<237>:'(0,AG52,0,0,0,0,0,0,0,0,0,0,0,0,0,0,0,0,0,0,0,0,0,0,0,0,0,0,0,0~
)';BIDI;
    'RSVD'<236>:'(0,AG54,0,0,0,0,0,0,0,0,0,0,0,0,0,0,0,0,0,0,0,0,0,0,0,0,0,0,0,0~
)';BIDI;
    'RSVD'<235>:'(0,AG56,0,0,0,0,0,0,0,0,0,0,0,0,0,0,0,0,0,0,0,0,0,0,0,0,0,0,0,0~
)';BIDI;
    'RSVD'<234>:'(0,AG72,0,0,0,0,0,0,0,0,0,0,0,0,0,0,0,0,0,0,0,0,0,0,0,0,0,0,0,0~
)';BIDI;
    'RSVD'<233>:'(0,AH15,0,0,0,0,0,0,0,0,0,0,0,0,0,0,0,0,0,0,0,0,0,0,0,0,0,0,0,0~
)';BIDI;
    'RSVD'<232>:'(0,AH19,0,0,0,0,0,0,0,0,0,0,0,0,0,0,0,0,0,0,0,0,0,0,0,0,0,0,0,0~
)';BIDI;
    'RSVD'<231>:'(0,AH55,0,0,0,0,0,0,0,0,0,0,0,0,0,0,0,0,0,0,0,0,0,0,0,0,0,0,0,0~
)';BIDI;
    'RSVD'<230>:'(0,AH57,0,0,0,0,0,0,0,0,0,0,0,0,0,0,0,0,0,0,0,0,0,0,0,0,0,0,0,0~
)';BIDI;
    'RSVD'<229>:'(0,AH71,0,0,0,0,0,0,0,0,0,0,0,0,0,0,0,0,0,0,0,0,0,0,0,0,0,0,0,0~
)';BIDI;
    'RSVD'<228>:'(0,AH73,0,0,0,0,0,0,0,0,0,0,0,0,0,0,0,0,0,0,0,0,0,0,0,0,0,0,0,0~
)';BIDI;
    'RSVD'<227>:'(0,AJ20,0,0,0,0,0,0,0,0,0,0,0,0,0,0,0,0,0,0,0,0,0,0,0,0,0,0,0,0~
)';BIDI;
    'RSVD'<226>:'(0,AJ56,0,0,0,0,0,0,0,0,0,0,0,0,0,0,0,0,0,0,0,0,0,0,0,0,0,0,0,0~
)';BIDI;
    'RSVD'<225>:'(0,AJ58,0,0,0,0,0,0,0,0,0,0,0,0,0,0,0,0,0,0,0,0,0,0,0,0,0,0,0,0~
)';BIDI;
    'RSVD'<224>:'(0,AJ60,0,0,0,0,0,0,0,0,0,0,0,0,0,0,0,0,0,0,0,0,0,0,0,0,0,0,0,0~
)';BIDI;
    'RSVD'<223>:'(0,AJ62,0,0,0,0,0,0,0,0,0,0,0,0,0,0,0,0,0,0,0,0,0,0,0,0,0,0,0,0~
)';BIDI;
    'RSVD'<222>:'(0,AJ70,0,0,0,0,0,0,0,0,0,0,0,0,0,0,0,0,0,0,0,0,0,0,0,0,0,0,0,0~
)';BIDI;
    'RSVD'<221>:'(0,AK21,0,0,0,0,0,0,0,0,0,0,0,0,0,0,0,0,0,0,0,0,0,0,0,0,0,0,0,0~
)';BIDI;
    'RSVD'<220>:'(0,AK27,0,0,0,0,0,0,0,0,0,0,0,0,0,0,0,0,0,0,0,0,0,0,0,0,0,0,0,0~
)';BIDI;
    'RSVD'<219>:'(0,AK57,0,0,0,0,0,0,0,0,0,0,0,0,0,0,0,0,0,0,0,0,0,0,0,0,0,0,0,0~
)';BIDI;
    'RSVD'<218>:'(0,AK59,0,0,0,0,0,0,0,0,0,0,0,0,0,0,0,0,0,0,0,0,0,0,0,0,0,0,0,0~
)';BIDI;
    'RSVD'<217>:'(0,AK61,0,0,0,0,0,0,0,0,0,0,0,0,0,0,0,0,0,0,0,0,0,0,0,0,0,0,0,0~
)';BIDI;
    'RSVD'<216>:'(0,AK69,0,0,0,0,0,0,0,0,0,0,0,0,0,0,0,0,0,0,0,0,0,0,0,0,0,0,0,0~
)';BIDI;
    'RSVD'<215>:'(0,AL20,0,0,0,0,0,0,0,0,0,0,0,0,0,0,0,0,0,0,0,0,0,0,0,0,0,0,0,0~
)';BIDI;
    'RSVD'<214>:'(0,AL22,0,0,0,0,0,0,0,0,0,0,0,0,0,0,0,0,0,0,0,0,0,0,0,0,0,0,0,0~
)';BIDI;
    'RSVD'<213>:'(0,AL26,0,0,0,0,0,0,0,0,0,0,0,0,0,0,0,0,0,0,0,0,0,0,0,0,0,0,0,0~
)';BIDI;
    'RSVD'<212>:'(0,AL58,0,0,0,0,0,0,0,0,0,0,0,0,0,0,0,0,0,0,0,0,0,0,0,0,0,0,0,0~
)';BIDI;
    'RSVD'<211>:'(0,AL60,0,0,0,0,0,0,0,0,0,0,0,0,0,0,0,0,0,0,0,0,0,0,0,0,0,0,0,0~
)';BIDI;
    'RSVD'<210>:'(0,AL62,0,0,0,0,0,0,0,0,0,0,0,0,0,0,0,0,0,0,0,0,0,0,0,0,0,0,0,0~
)';BIDI;
    'RSVD'<209>:'(0,AM21,0,0,0,0,0,0,0,0,0,0,0,0,0,0,0,0,0,0,0,0,0,0,0,0,0,0,0,0~
)';BIDI;
    'RSVD'<208>:'(0,AM23,0,0,0,0,0,0,0,0,0,0,0,0,0,0,0,0,0,0,0,0,0,0,0,0,0,0,0,0~
)';BIDI;
    'RSVD'<207>:'(0,AM25,0,0,0,0,0,0,0,0,0,0,0,0,0,0,0,0,0,0,0,0,0,0,0,0,0,0,0,0~
)';BIDI;
    'RSVD'<206>:'(0,AM27,0,0,0,0,0,0,0,0,0,0,0,0,0,0,0,0,0,0,0,0,0,0,0,0,0,0,0,0~
)';BIDI;
    'RSVD'<205>:'(0,AM59,0,0,0,0,0,0,0,0,0,0,0,0,0,0,0,0,0,0,0,0,0,0,0,0,0,0,0,0~
)';BIDI;
    'RSVD'<204>:'(0,AM61,0,0,0,0,0,0,0,0,0,0,0,0,0,0,0,0,0,0,0,0,0,0,0,0,0,0,0,0~
)';BIDI;
    'RSVD'<203>:'(0,AN18,0,0,0,0,0,0,0,0,0,0,0,0,0,0,0,0,0,0,0,0,0,0,0,0,0,0,0,0~
)';BIDI;
    'RSVD'<202>:'(0,AN22,0,0,0,0,0,0,0,0,0,0,0,0,0,0,0,0,0,0,0,0,0,0,0,0,0,0,0,0~
)';BIDI;
    'RSVD'<201>:'(0,AN24,0,0,0,0,0,0,0,0,0,0,0,0,0,0,0,0,0,0,0,0,0,0,0,0,0,0,0,0~
)';BIDI;
    'RSVD'<200>:'(0,AN26,0,0,0,0,0,0,0,0,0,0,0,0,0,0,0,0,0,0,0,0,0,0,0,0,0,0,0,0~
)';BIDI;
    'RSVD'<199>:'(0,AN60,0,0,0,0,0,0,0,0,0,0,0,0,0,0,0,0,0,0,0,0,0,0,0,0,0,0,0,0~
)';BIDI;
    'RSVD'<198>:'(0,AN62,0,0,0,0,0,0,0,0,0,0,0,0,0,0,0,0,0,0,0,0,0,0,0,0,0,0,0,0~
)';BIDI;
    'RSVD'<197>:'(0,AP23,0,0,0,0,0,0,0,0,0,0,0,0,0,0,0,0,0,0,0,0,0,0,0,0,0,0,0,0~
)';BIDI;
    'RSVD'<196>:'(0,AP25,0,0,0,0,0,0,0,0,0,0,0,0,0,0,0,0,0,0,0,0,0,0,0,0,0,0,0,0~
)';BIDI;
    'RSVD'<195>:'(0,AP27,0,0,0,0,0,0,0,0,0,0,0,0,0,0,0,0,0,0,0,0,0,0,0,0,0,0,0,0~
)';BIDI;
    'RSVD'<194>:'(0,AP61,0,0,0,0,0,0,0,0,0,0,0,0,0,0,0,0,0,0,0,0,0,0,0,0,0,0,0,0~
)';BIDI;
    'RSVD'<193>:'(0,0,0,0,0,0,0,0,AR20,0,0,0,0,0,0,0,0,0,0,0,0,0,0,0,0,0,0,0,0,0~
)';BIDI;
    'RSVD'<192>:'(0,0,0,0,0,0,0,0,AR22,0,0,0,0,0,0,0,0,0,0,0,0,0,0,0,0,0,0,0,0,0~
)';BIDI;
    'RSVD'<191>:'(0,0,0,0,0,0,0,0,AR26,0,0,0,0,0,0,0,0,0,0,0,0,0,0,0,0,0,0,0,0,0~
)';BIDI;
    'RSVD'<190>:'(0,0,0,0,0,0,0,0,AR62,0,0,0,0,0,0,0,0,0,0,0,0,0,0,0,0,0,0,0,0,0~
)';BIDI;
    'RSVD'<189>:'(0,0,0,0,0,0,0,0,AT13,0,0,0,0,0,0,0,0,0,0,0,0,0,0,0,0,0,0,0,0,0~
)';BIDI;
    'RSVD'<188>:'(0,0,0,0,0,0,0,0,AT23,0,0,0,0,0,0,0,0,0,0,0,0,0,0,0,0,0,0,0,0,0~
)';BIDI;
    'RSVD'<187>:'(0,0,0,0,0,0,0,0,AT25,0,0,0,0,0,0,0,0,0,0,0,0,0,0,0,0,0,0,0,0,0~
)';BIDI;
    'RSVD'<186>:'(0,0,0,0,0,0,0,0,AV77,0,0,0,0,0,0,0,0,0,0,0,0,0,0,0,0,0,0,0,0,0~
)';BIDI;
    'RSVD'<184>:'(0,0,0,0,0,0,0,0,AW64,0,0,0,0,0,0,0,0,0,0,0,0,0,0,0,0,0,0,0,0,0~
)';BIDI;
    'RSVD'<183>:'(0,0,0,0,0,0,0,0,AW76,0,0,0,0,0,0,0,0,0,0,0,0,0,0,0,0,0,0,0,0,0~
)';BIDI;
    'RSVD'<182>:'(0,0,0,0,0,0,0,0,AY65,0,0,0,0,0,0,0,0,0,0,0,0,0,0,0,0,0,0,0,0,0~
)';BIDI;
    'RSVD'<181>:'(0,0,0,0,0,0,0,0,AY67,0,0,0,0,0,0,0,0,0,0,0,0,0,0,0,0,0,0,0,0,0~
)';BIDI;
    'RSVD'<180>:'(0,0,0,0,0,0,0,0,AY75,0,0,0,0,0,0,0,0,0,0,0,0,0,0,0,0,0,0,0,0,0~
)';BIDI;
    'RSVD'<179>:'(0,0,0,0,0,0,0,0,AY77,0,0,0,0,0,0,0,0,0,0,0,0,0,0,0,0,0,0,0,0,0~
)';BIDI;
    'RSVD'<178>:'(0,0,0,0,0,0,0,0,BA14,0,0,0,0,0,0,0,0,0,0,0,0,0,0,0,0,0,0,0,0,0~
)';BIDI;
    'RSVD'<177>:'(0,0,0,0,0,0,0,0,BA16,0,0,0,0,0,0,0,0,0,0,0,0,0,0,0,0,0,0,0,0,0~
)';BIDI;
    'RSVD'<176>:'(0,0,0,0,0,0,0,0,BA18,0,0,0,0,0,0,0,0,0,0,0,0,0,0,0,0,0,0,0,0,0~
)';BIDI;
    'RSVD'<175>:'(0,0,0,0,0,0,0,0,BA22,0,0,0,0,0,0,0,0,0,0,0,0,0,0,0,0,0,0,0,0,0~
)';BIDI;
    'RSVD'<174>:'(0,0,0,0,0,0,0,0,BA64,0,0,0,0,0,0,0,0,0,0,0,0,0,0,0,0,0,0,0,0,0~
)';BIDI;
    'RSVD'<173>:'(0,0,0,0,0,0,0,0,BA66,0,0,0,0,0,0,0,0,0,0,0,0,0,0,0,0,0,0,0,0,0~
)';BIDI;
    'RSVD'<172>:'(0,0,0,0,0,0,0,0,BA76,0,0,0,0,0,0,0,0,0,0,0,0,0,0,0,0,0,0,0,0,0~
)';BIDI;
    'RSVD'<171>:'(0,0,0,0,0,0,0,0,0,0,0,0,0,0,0,BA78,0,0,0,0,0,0,0,0,0,0,0,0,0,0~
)';BIDI;
    'RSVD'<170>:'(0,0,0,0,0,0,0,0,0,0,0,0,0,0,0,BA82,0,0,0,0,0,0,0,0,0,0,0,0,0,0~
)';BIDI;
    'RSVD'<169>:'(0,0,0,0,0,0,0,0,0,0,0,0,0,0,0,BB13,0,0,0,0,0,0,0,0,0,0,0,0,0,0~
)';BIDI;
    'RSVD'<168>:'(0,0,0,0,0,0,0,0,0,0,0,0,0,0,0,BB15,0,0,0,0,0,0,0,0,0,0,0,0,0,0~
)';BIDI;
    'RSVD'<167>:'(0,0,0,0,0,0,0,0,0,0,0,0,0,0,0,BB17,0,0,0,0,0,0,0,0,0,0,0,0,0,0~
)';BIDI;
    'RSVD'<166>:'(0,0,0,0,0,0,0,0,0,0,0,0,0,0,0,BB21,0,0,0,0,0,0,0,0,0,0,0,0,0,0~
)';BIDI;
    'RSVD'<165>:'(0,0,0,0,0,0,0,0,0,0,0,0,0,0,0,BB25,0,0,0,0,0,0,0,0,0,0,0,0,0,0~
)';BIDI;
    'RSVD'<164>:'(0,0,0,0,0,0,0,0,0,0,0,0,0,0,0,BB65,0,0,0,0,0,0,0,0,0,0,0,0,0,0~
)';BIDI;
    'RSVD'<163>:'(0,0,0,0,0,0,0,0,0,0,0,0,0,0,0,BB67,0,0,0,0,0,0,0,0,0,0,0,0,0,0~
)';BIDI;
    'RSVD'<162>:'(0,0,0,0,0,0,0,0,0,0,0,0,0,0,0,BC14,0,0,0,0,0,0,0,0,0,0,0,0,0,0~
)';BIDI;
    'RSVD'<161>:'(0,0,0,0,0,0,0,0,0,0,0,0,0,0,0,BC18,0,0,0,0,0,0,0,0,0,0,0,0,0,0~
)';BIDI;
    'RSVD'<160>:'(0,0,0,0,0,0,0,0,0,0,0,0,0,0,0,BC20,0,0,0,0,0,0,0,0,0,0,0,0,0,0~
)';BIDI;
    'RSVD'<159>:'(0,0,0,0,0,0,0,0,0,0,0,0,0,0,0,BC22,0,0,0,0,0,0,0,0,0,0,0,0,0,0~
)';BIDI;
    'RSVD'<158>:'(0,0,0,0,0,0,0,0,0,0,0,0,0,0,0,BC64,0,0,0,0,0,0,0,0,0,0,0,0,0,0~
)';BIDI;
    'RSVD'<157>:'(0,0,0,0,0,0,0,0,0,0,0,0,0,0,0,BC66,0,0,0,0,0,0,0,0,0,0,0,0,0,0~
)';BIDI;
    'RSVD'<156>:'(0,0,0,0,0,0,0,0,0,0,0,0,0,0,0,BC68,0,0,0,0,0,0,0,0,0,0,0,0,0,0~
)';BIDI;
    'RSVD'<155>:'(0,0,0,0,0,0,0,0,0,0,0,0,0,0,0,BD17,0,0,0,0,0,0,0,0,0,0,0,0,0,0~
)';BIDI;
    'RSVD'<154>:'(0,0,0,0,0,0,0,0,0,0,0,0,0,0,0,BD19,0,0,0,0,0,0,0,0,0,0,0,0,0,0~
)';BIDI;
    'RSVD'<153>:'(0,0,0,0,0,0,0,0,0,0,0,0,0,0,0,BD25,0,0,0,0,0,0,0,0,0,0,0,0,0,0~
)';BIDI;
    'RSVD'<152>:'(0,0,0,0,0,0,0,0,0,0,0,0,0,0,0,BD65,0,0,0,0,0,0,0,0,0,0,0,0,0,0~
)';BIDI;
    'RSVD'<151>:'(0,0,0,0,0,0,0,0,0,0,0,0,0,0,0,BD67,0,0,0,0,0,0,0,0,0,0,0,0,0,0~
)';BIDI;
    'RSVD'<150>:'(0,0,0,0,0,0,0,0,0,0,0,0,0,0,0,BD69,0,0,0,0,0,0,0,0,0,0,0,0,0,0~
)';BIDI;
    'RSVD'<149>:'(0,0,0,0,0,0,0,0,0,0,0,0,0,0,0,BE18,0,0,0,0,0,0,0,0,0,0,0,0,0,0~
)';BIDI;
    'RSVD'<148>:'(0,0,0,0,0,0,0,0,0,0,0,0,0,0,0,BE20,0,0,0,0,0,0,0,0,0,0,0,0,0,0~
)';BIDI;
    'RSVD'<147>:'(0,0,0,0,0,0,0,0,0,0,0,0,0,0,0,BE22,0,0,0,0,0,0,0,0,0,0,0,0,0,0~
)';BIDI;
    'RSVD'<146>:'(0,0,0,0,0,0,0,0,0,0,0,0,0,0,0,BF21,0,0,0,0,0,0,0,0,0,0,0,0,0,0~
)';BIDI;
    'RSVD'<145>:'(0,0,0,0,0,0,0,0,0,0,0,0,0,0,0,BG18,0,0,0,0,0,0,0,0,0,0,0,0,0,0~
)';BIDI;
    'RSVD'<144>:'(0,0,0,0,0,0,0,0,0,0,0,0,0,0,0,BG20,0,0,0,0,0,0,0,0,0,0,0,0,0,0~
)';BIDI;
    'RSVD'<143>:'(0,0,0,0,0,0,0,0,0,0,0,0,0,0,0,BH19,0,0,0,0,0,0,0,0,0,0,0,0,0,0~
)';BIDI;
    'RSVD'<142>:'(0,0,0,0,0,0,0,0,0,0,0,0,0,0,0,BJ16,0,0,0,0,0,0,0,0,0,0,0,0,0,0~
)';BIDI;
    'RSVD'<141>:'(0,0,0,0,0,0,0,0,0,0,0,0,0,0,0,BJ18,0,0,0,0,0,0,0,0,0,0,0,0,0,0~
)';BIDI;
    'RSVD'<140>:'(0,0,0,0,0,0,0,0,0,0,0,0,0,0,0,BJ20,0,0,0,0,0,0,0,0,0,0,0,0,0,0~
)';BIDI;
    'RSVD'<139>:'(0,0,0,0,0,0,0,0,0,0,0,0,0,0,0,BK17,0,0,0,0,0,0,0,0,0,0,0,0,0,0~
)';BIDI;
    'RSVD'<138>:'(0,0,0,0,0,0,0,0,0,0,0,0,0,0,0,BL18,0,0,0,0,0,0,0,0,0,0,0,0,0,0~
)';BIDI;
    'RSVD'<137>:'(0,0,0,0,0,0,0,0,0,0,0,0,0,0,0,BL20,0,0,0,0,0,0,0,0,0,0,0,0,0,0~
)';BIDI;
    'RSVD'<136>:'(0,0,0,0,0,0,0,0,0,0,0,0,0,0,0,BM17,0,0,0,0,0,0,0,0,0,0,0,0,0,0~
)';BIDI;
    'RSVD'<135>:'(0,0,0,0,0,0,0,0,0,0,0,0,0,0,0,BM19,0,0,0,0,0,0,0,0,0,0,0,0,0,0~
)';BIDI;
    'RSVD'<134>:'(0,0,0,0,0,0,0,0,0,0,0,0,0,0,0,BN18,0,0,0,0,0,0,0,0,0,0,0,0,0,0~
)';BIDI;
    'RSVD'<133>:'(0,0,0,0,0,0,0,0,0,0,0,0,0,0,0,BP17,0,0,0,0,0,0,0,0,0,0,0,0,0,0~
)';BIDI;
    'RSVD'<132>:'(0,0,0,0,0,0,0,0,0,0,0,0,0,0,0,BP21,0,0,0,0,0,0,0,0,0,0,0,0,0,0~
)';BIDI;
    'RSVD'<131>:'(0,0,0,0,0,0,0,0,0,0,0,0,0,0,0,BR22,0,0,0,0,0,0,0,0,0,0,0,0,0,0~
)';BIDI;
    'RSVD'<130>:'(0,0,0,0,0,0,0,0,0,0,0,0,0,0,0,BR24,0,0,0,0,0,0,0,0,0,0,0,0,0,0~
)';BIDI;
    'RSVD'<129>:'(0,0,0,0,0,0,0,0,0,0,0,0,0,0,0,BU18,0,0,0,0,0,0,0,0,0,0,0,0,0,0~
)';BIDI;
    'RSVD'<128>:'(0,0,0,0,0,0,0,0,0,0,0,0,0,0,0,BU20,0,0,0,0,0,0,0,0,0,0,0,0,0,0~
)';BIDI;
    'RSVD'<127>:'(0,0,0,0,0,0,0,0,0,0,0,0,0,0,0,BU22,0,0,0,0,0,0,0,0,0,0,0,0,0,0~
)';BIDI;
    'RSVD'<126>:'(0,0,0,0,0,0,0,0,0,0,0,0,0,0,0,BV19,0,0,0,0,0,0,0,0,0,0,0,0,0,0~
)';BIDI;
    'RSVD'<125>:'(0,0,0,0,0,0,0,0,0,0,0,0,0,0,0,BV21,0,0,0,0,0,0,0,0,0,0,0,0,0,0~
)';BIDI;
    'RSVD'<124>:'(0,0,0,0,0,0,0,0,0,0,0,0,0,0,0,BV23,0,0,0,0,0,0,0,0,0,0,0,0,0,0~
)';BIDI;
    'RSVD'<123>:'(0,0,0,0,0,0,0,0,0,0,0,0,0,0,0,BW10,0,0,0,0,0,0,0,0,0,0,0,0,0,0~
)';BIDI;
    'RSVD'<122>:'(0,0,0,0,0,0,0,0,0,0,0,0,0,0,0,BW20,0,0,0,0,0,0,0,0,0,0,0,0,0,0~
)';BIDI;
    'RSVD'<121>:'(0,0,0,0,0,0,0,0,0,0,0,0,0,0,0,BW22,0,0,0,0,0,0,0,0,0,0,0,0,0,0~
)';BIDI;
    'RSVD'<120>:'(0,0,0,0,0,0,0,0,0,0,0,0,0,0,0,BY19,0,0,0,0,0,0,0,0,0,0,0,0,0,0~
)';BIDI;
    'RSVD'<119>:'(0,0,0,0,0,0,0,0,0,0,0,0,0,0,0,BY25,0,0,0,0,0,0,0,0,0,0,0,0,0,0~
)';BIDI;
    'RSVD'<118>:'(0,0,0,0,0,0,0,0,0,0,0,0,0,0,0,CA22,0,0,0,0,0,0,0,0,0,0,0,0,0,0~
)';BIDI;
    'RSVD'<117>:'(0,0,0,0,0,0,0,0,0,0,0,0,0,0,0,CA24,0,0,0,0,0,0,0,0,0,0,0,0,0,0~
)';BIDI;
    'RSVD'<116>:'(0,0,0,0,0,0,0,0,0,0,0,0,0,0,0,CB19,0,0,0,0,0,0,0,0,0,0,0,0,0,0~
)';BIDI;
    'RSVD'<115>:'(0,0,0,0,0,0,0,0,0,0,0,0,0,0,0,CB21,0,0,0,0,0,0,0,0,0,0,0,0,0,0~
)';BIDI;
    'RSVD'<114>:'(0,0,0,0,0,0,0,0,0,0,0,0,0,0,0,CB25,0,0,0,0,0,0,0,0,0,0,0,0,0,0~
)';BIDI;
    'RSVD'<113>:'(0,0,0,0,0,0,0,0,0,0,0,0,0,0,0,CB5,0,0,0,0,0,0,0,0,0,0,0,0,0,0)~
';BIDI;
    'RSVD'<112>:'(0,0,0,0,0,0,0,0,0,0,0,0,0,0,0,CC20,0,0,0,0,0,0,0,0,0,0,0,0,0,0~
)';BIDI;
    'RSVD'<111>:'(0,0,0,0,0,0,0,0,0,0,0,0,0,0,0,CC6,0,0,0,0,0,0,0,0,0,0,0,0,0,0)~
';BIDI;
    'RSVD'<110>:'(0,0,0,0,0,0,0,0,0,0,0,0,0,0,0,CD19,0,0,0,0,0,0,0,0,0,0,0,0,0,0~
)';BIDI;
    'RSVD'<109>:'(0,0,0,0,0,0,0,0,0,0,0,0,0,0,0,CD21,0,0,0,0,0,0,0,0,0,0,0,0,0,0~
)';BIDI;
    'RSVD'<108>:'(0,0,0,0,0,0,0,0,0,0,0,0,0,0,0,CD25,0,0,0,0,0,0,0,0,0,0,0,0,0,0~
)';BIDI;
    'RSVD'<107>:'(0,0,0,0,0,0,0,0,0,0,0,0,0,0,0,CE22,0,0,0,0,0,0,0,0,0,0,0,0,0,0~
)';BIDI;
    'RSVD'<106>:'(0,0,0,0,0,0,0,0,0,0,0,0,0,0,0,CE78,0,0,0,0,0,0,0,0,0,0,0,0,0,0~
)';BIDI;
    'RSVD'<105>:'(0,0,0,0,0,0,0,0,0,0,0,0,0,0,0,CE80,0,0,0,0,0,0,0,0,0,0,0,0,0,0~
)';BIDI;
    'RSVD'<104>:'(0,0,0,0,0,0,0,0,0,0,0,0,0,0,0,CF19,0,0,0,0,0,0,0,0,0,0,0,0,0,0~
)';BIDI;
    'RSVD'<103>:'(0,0,0,0,0,0,0,0,0,0,0,0,0,0,0,CF21,0,0,0,0,0,0,0,0,0,0,0,0,0,0~
)';BIDI;
    'RSVD'<102>:'(0,0,0,0,0,0,0,0,0,0,0,0,0,0,0,CF23,0,0,0,0,0,0,0,0,0,0,0,0,0,0~
)';BIDI;
    'RSVD'<101>:'(0,0,0,0,0,0,0,0,0,0,0,0,0,0,0,CF79,0,0,0,0,0,0,0,0,0,0,0,0,0,0~
)';BIDI;
    'RSVD'<100>:'(0,0,0,0,0,0,0,0,0,0,0,0,0,0,0,CF81,0,0,0,0,0,0,0,0,0,0,0,0,0,0~
)';BIDI;
    'RSVD'<99>:'(0,0,0,0,0,0,0,0,0,0,0,0,0,0,0,CG10,0,0,0,0,0,0,0,0,0,0,0,0,0,0)~
';BIDI;
    'RSVD'<98>:'(0,0,0,0,0,0,0,0,0,0,0,0,0,0,0,CG20,0,0,0,0,0,0,0,0,0,0,0,0,0,0)~
';BIDI;
    'RSVD'<97>:'(0,0,0,0,0,0,0,0,0,0,0,0,0,0,0,CG24,0,0,0,0,0,0,0,0,0,0,0,0,0,0)~
';BIDI;
    'RSVD'<96>:'(0,0,0,0,0,0,0,0,0,0,0,0,0,0,0,CG26,0,0,0,0,0,0,0,0,0,0,0,0,0,0)~
';BIDI;
    'RSVD'<95>:'(0,0,0,0,0,0,0,0,0,0,0,0,0,0,0,CG78,0,0,0,0,0,0,0,0,0,0,0,0,0,0)~
';BIDI;
    'RSVD'<94>:'(0,0,0,0,0,0,0,0,0,0,0,0,0,0,0,CG82,0,0,0,0,0,0,0,0,0,0,0,0,0,0)~
';BIDI;
    'RSVD'<93>:'(0,0,0,0,0,0,0,0,0,0,0,0,0,0,0,CH21,0,0,0,0,0,0,0,0,0,0,0,0,0,0)~
';BIDI;
    'RSVD'<92>:'(0,0,0,0,0,0,0,0,0,0,0,0,0,0,0,CH23,0,0,0,0,0,0,0,0,0,0,0,0,0,0)~
';BIDI;
    'RSVD'<91>:'(0,0,0,0,0,0,0,0,0,0,0,0,0,0,0,0,CH25,0,0,0,0,0,0,0,0,0,0,0,0,0)~
';BIDI;
    'RSVD'<90>:'(0,0,0,0,0,0,0,0,0,0,0,0,0,0,0,0,CH77,0,0,0,0,0,0,0,0,0,0,0,0,0)~
';BIDI;
    'RSVD'<89>:'(0,0,0,0,0,0,0,0,0,0,0,0,0,0,0,0,CJ20,0,0,0,0,0,0,0,0,0,0,0,0,0)~
';BIDI;
    'RSVD'<88>:'(0,0,0,0,0,0,0,0,0,0,0,0,0,0,0,0,CJ22,0,0,0,0,0,0,0,0,0,0,0,0,0)~
';BIDI;
    'RSVD'<87>:'(0,0,0,0,0,0,0,0,0,0,0,0,0,0,0,0,CJ24,0,0,0,0,0,0,0,0,0,0,0,0,0)~
';BIDI;
    'RSVD'<86>:'(0,0,0,0,0,0,0,0,0,0,0,0,0,0,0,0,CJ26,0,0,0,0,0,0,0,0,0,0,0,0,0)~
';BIDI;
    'RSVD'<85>:'(0,0,0,0,0,0,0,0,0,0,0,0,0,0,0,0,CK19,0,0,0,0,0,0,0,0,0,0,0,0,0)~
';BIDI;
    'RSVD'<84>:'(0,0,0,0,0,0,0,0,0,0,0,0,0,0,0,0,CK23,0,0,0,0,0,0,0,0,0,0,0,0,0)~
';BIDI;
    'RSVD'<83>:'(0,0,0,0,0,0,0,0,0,0,0,0,0,0,0,0,CK25,0,0,0,0,0,0,0,0,0,0,0,0,0)~
';BIDI;
    'RSVD'<82>:'(0,0,0,0,0,0,0,0,0,0,0,0,0,0,0,0,CK77,0,0,0,0,0,0,0,0,0,0,0,0,0)~
';BIDI;
    'RSVD'<81>:'(0,0,0,0,0,0,0,0,0,0,0,0,0,0,0,0,CL24,0,0,0,0,0,0,0,0,0,0,0,0,0)~
';BIDI;
    'RSVD'<80>:'(0,0,0,0,0,0,0,0,0,0,0,0,0,0,0,0,0,0,0,0,0,CL26,0,0,0,0,0,0,0,0)~
';BIDI;
    'RSVD'<79>:'(0,0,0,0,0,0,0,0,0,0,0,0,0,0,0,0,0,0,0,0,0,CM23,0,0,0,0,0,0,0,0)~
';BIDI;
    'RSVD'<78>:'(0,0,0,0,0,0,0,0,0,0,0,0,0,0,0,0,0,0,0,0,0,CM25,0,0,0,0,0,0,0,0)~
';BIDI;
    'RSVD'<77>:'(0,0,0,0,0,0,0,0,0,0,0,0,0,0,0,0,0,0,0,0,0,CN22,0,0,0,0,0,0,0,0)~
';BIDI;
    'RSVD'<76>:'(0,0,0,0,0,0,0,0,0,0,0,0,0,0,0,0,0,0,0,0,0,CN24,0,0,0,0,0,0,0,0)~
';BIDI;
    'RSVD'<75>:'(0,0,0,0,0,0,0,0,0,0,0,0,0,0,0,0,0,0,0,0,0,CN28,0,0,0,0,0,0,0,0)~
';BIDI;
    'RSVD'<74>:'(0,0,0,0,0,0,0,0,0,0,0,0,0,0,0,0,0,0,0,0,0,CP23,0,0,0,0,0,0,0,0)~
';BIDI;
    'RSVD'<73>:'(0,0,0,0,0,0,0,0,0,0,0,0,0,0,0,0,0,0,0,0,0,CP31,0,0,0,0,0,0,0,0)~
';BIDI;
    'RSVD'<72>:'(0,0,0,0,0,0,0,0,0,0,0,0,0,0,0,0,0,0,0,0,0,CR60,0,0,0,0,0,0,0,0)~
';BIDI;
    'RSVD'<71>:'(0,0,0,0,0,0,0,0,0,0,0,0,0,0,0,0,0,0,0,0,0,CT23,0,0,0,0,0,0,0,0)~
';BIDI;
    'RSVD'<70>:'(0,0,0,0,0,0,0,0,0,0,0,0,0,0,0,0,0,0,0,0,0,CT5,0,0,0,0,0,0,0,0)';BIDI;
    'RSVD'<69>:'(0,0,0,0,0,0,0,0,0,0,0,0,0,0,0,0,0,0,0,0,0,CT69,0,0,0,0,0,0,0,0)~
';BIDI;
    'RSVD'<68>:'(0,0,0,0,0,0,0,0,0,0,0,0,0,0,0,0,0,0,0,0,0,CU24,0,0,0,0,0,0,0,0)~
';BIDI;
    'RSVD'<67>:'(0,0,0,0,0,0,0,0,0,0,0,0,0,0,0,0,0,0,0,0,0,CU6,0,0,0,0,0,0,0,0)';BIDI;
    'RSVD'<66>:'(0,0,0,0,0,0,0,0,0,0,0,0,0,0,0,0,0,0,0,0,0,CU60,0,0,0,0,0,0,0,0)~
';BIDI;
    'RSVD'<65>:'(0,0,0,0,0,0,0,0,0,0,0,0,0,0,0,0,0,0,0,0,0,CV23,0,0,0,0,0,0,0,0)~
';BIDI;
    'RSVD'<64>:'(0,0,0,0,0,0,0,0,0,0,0,0,0,0,0,0,0,0,0,0,0,CV69,0,0,0,0,0,0,0,0)~
';BIDI;
    'RSVD'<63>:'(0,0,0,0,0,0,0,0,0,0,0,0,0,0,0,0,0,0,0,0,0,CW22,0,0,0,0,0,0,0,0)~
';BIDI;
    'RSVD'<62>:'(0,0,0,0,0,0,0,0,0,0,0,0,0,0,0,0,0,0,0,0,0,CW24,0,0,0,0,0,0,0,0)~
';BIDI;
    'RSVD'<61>:'(0,0,0,0,0,0,0,0,0,0,0,0,0,0,0,0,0,0,0,0,0,CW60,0,0,0,0,0,0,0,0)~
';BIDI;
    'RSVD'<60>:'(0,0,0,0,0,0,0,0,0,0,0,0,0,0,0,0,0,0,0,0,0,CW62,0,0,0,0,0,0,0,0)~
';BIDI;
    'RSVD'<59>:'(0,0,0,0,0,0,0,0,0,0,0,0,0,0,0,0,0,0,0,0,0,CY23,0,0,0,0,0,0,0,0)~
';BIDI;
    'RSVD'<58>:'(0,0,0,0,0,0,0,0,0,0,0,0,0,0,0,0,0,0,0,0,0,CY25,0,0,0,0,0,0,0,0)~
';BIDI;
    'RSVD'<57>:'(0,0,0,0,0,0,0,0,0,0,0,0,0,0,0,0,0,0,0,0,0,CY39,0,0,0,0,0,0,0,0)~
';BIDI;
    'RSVD'<56>:'(0,0,0,0,0,0,0,0,0,0,0,0,0,0,0,0,0,0,0,0,0,CY53,0,0,0,0,0,0,0,0)~
';BIDI;
    'RSVD'<55>:'(0,0,0,0,0,0,0,0,0,0,0,0,0,0,0,0,0,0,0,0,0,CY57,0,0,0,0,0,0,0,0)~
';BIDI;
    'RSVD'<54>:'(0,0,0,0,0,0,0,0,0,0,0,0,0,0,0,0,0,0,0,0,0,CY63,0,0,0,0,0,0,0,0)~
';BIDI;
    'RSVD'<53>:'(0,0,0,0,0,0,0,0,0,0,0,0,0,0,0,0,0,0,0,0,0,CY73,0,0,0,0,0,0,0,0)~
';BIDI;
    'RSVD'<52>:'(0,0,0,0,0,0,0,0,0,0,0,0,0,0,0,0,0,0,0,0,0,DA24,0,0,0,0,0,0,0,0)~
';BIDI;
    'RSVD'<51>:'(0,0,0,0,0,0,0,0,0,0,0,0,0,0,0,0,0,0,0,0,0,DA40,0,0,0,0,0,0,0,0)~
';BIDI;
    'RSVD'<50>:'(0,0,0,0,0,0,0,0,0,0,0,0,0,0,0,0,0,0,0,0,0,DA52,0,0,0,0,0,0,0,0)~
';BIDI;
    'RSVD'<49>:'(0,0,0,0,0,0,0,0,0,0,0,0,0,0,0,0,0,0,0,0,0,DA54,0,0,0,0,0,0,0,0)~
';BIDI;
    'RSVD'<48>:'(0,0,0,0,0,0,0,0,0,0,0,0,0,0,0,0,0,0,0,0,0,DA56,0,0,0,0,0,0,0,0)~
';BIDI;
    'RSVD'<47>:'(0,0,0,0,0,0,0,0,0,0,0,0,0,0,0,0,0,0,0,0,0,DC46,0,0,0,0,0,0,0,0)~
';BIDI;
    'RSVD'<46>:'(0,0,0,0,0,0,0,0,0,0,0,0,0,0,0,0,0,0,0,0,0,DC52,0,0,0,0,0,0,0,0)~
';BIDI;
    'RSVD'<45>:'(0,0,0,0,0,0,0,0,0,0,0,0,0,0,0,0,0,0,0,0,0,DD51,0,0,0,0,0,0,0,0)~
';BIDI;
    'RSVD'<44>:'(0,0,0,0,0,0,0,0,0,0,0,0,0,0,0,0,0,0,0,0,0,DG36,0,0,0,0,0,0,0,0)~
';BIDI;
    'RSVD'<43>:'(0,0,0,0,0,0,0,0,0,0,0,0,0,0,0,0,0,0,0,0,0,DG64,0,0,0,0,0,0,0,0)~
';BIDI;
    'RSVD'<42>:'(0,0,0,0,0,0,0,0,0,0,0,0,0,0,0,0,0,0,0,0,0,DH65,0,0,0,0,0,0,0,0)~
';BIDI;
    'RSVD'<41>:'(0,0,0,0,0,0,0,0,0,0,0,0,0,0,0,0,0,0,0,0,0,DJ36,0,0,0,0,0,0,0,0)~
';BIDI;
    'RSVD'<40>:'(0,0,0,0,0,0,0,0,0,0,0,0,0,0,0,0,0,0,0,0,0,DJ66,0,0,0,0,0,0,0,0)~
';BIDI;
    'RSVD'<39>:'(0,0,0,0,0,0,0,0,0,0,0,0,0,0,0,0,0,0,0,0,0,DK15,0,0,0,0,0,0,0,0)~
';BIDI;
    'RSVD'<38>:'(0,0,0,0,0,0,0,0,0,0,0,0,0,0,0,0,0,0,0,0,0,DK37,0,0,0,0,0,0,0,0)~
';BIDI;
    'RSVD'<37>:'(0,0,0,0,0,0,0,0,0,0,0,0,0,0,0,0,0,0,0,0,0,DK65,0,0,0,0,0,0,0,0)~
';BIDI;
    'RSVD'<36>:'(0,0,0,0,0,0,0,0,0,0,0,0,0,0,0,0,0,0,0,0,0,DK67,0,0,0,0,0,0,0,0)~
';BIDI;
    'RSVD'<35>:'(0,0,0,0,0,0,0,0,0,0,0,0,0,0,0,0,0,0,0,0,0,DL38,0,0,0,0,0,0,0,0)~
';BIDI;
    'RSVD'<34>:'(0,0,0,0,0,0,0,0,0,0,0,0,0,0,0,0,0,0,0,0,0,DL66,0,0,0,0,0,0,0,0)~
';BIDI;
    'RSVD'<33>:'(0,0,0,0,0,0,0,0,0,0,0,0,0,0,0,0,0,0,0,0,0,DM67,0,0,0,0,0,0,0,0)~
';BIDI;
    'RSVD'<32>:'(0,0,0,0,0,0,0,0,0,0,0,0,0,0,0,0,0,0,0,0,0,DN62,0,0,0,0,0,0,0,0)~
';BIDI;
    'RSVD'<31>:'(0,0,0,0,0,0,0,0,0,0,0,0,0,0,0,0,0,0,0,0,0,DN66,0,0,0,0,0,0,0,0)~
';BIDI;
    'RSVD'<30>:'(0,0,0,0,0,0,0,0,0,0,0,0,0,0,0,0,0,0,0,0,0,DP17,0,0,0,0,0,0,0,0)~
';BIDI;
    'RSVD'<29>:'(0,0,0,0,0,0,0,0,0,0,0,0,0,0,0,0,0,0,0,0,0,DP65,0,0,0,0,0,0,0,0)~
';BIDI;
    'RSVD'<28>:'(0,0,0,0,0,0,0,0,0,0,0,0,0,0,0,0,0,0,0,0,0,DR44,0,0,0,0,0,0,0,0)~
';BIDI;
    'RSVD'<27>:'(0,0,0,0,0,0,0,0,0,0,0,0,0,0,0,0,0,0,0,0,0,DT71,0,0,0,0,0,0,0,0)~
';BIDI;
    'RSVD'<26>:'(0,0,0,0,0,0,0,0,0,0,0,0,0,0,0,0,0,0,0,0,0,DU44,0,0,0,0,0,0,0,0)~
';BIDI;
    'RSVD'<25>:'(0,0,0,0,0,0,0,0,0,0,0,0,0,0,0,0,0,0,0,0,0,DV61,0,0,0,0,0,0,0,0)~
';BIDI;
    'RSVD'<24>:'(0,0,0,0,0,0,0,0,0,0,0,0,0,0,0,0,0,0,0,0,0,DV71,0,0,0,0,0,0,0,0)~
';BIDI;
    'RSVD'<23>:'(0,0,0,0,0,0,0,0,0,0,0,0,0,0,0,0,0,0,0,0,0,DW44,0,0,0,0,0,0,0,0)~
';BIDI;
    'RSVD'<22>:'(0,0,0,0,0,0,0,0,0,0,0,0,0,0,0,0,0,0,0,0,0,DW46,0,0,0,0,0,0,0,0)~
';BIDI;
    'RSVD'<21>:'(0,0,0,0,0,0,0,0,0,0,0,0,0,0,0,0,0,0,0,0,0,DY3,0,0,0,0,0,0,0,0)';BIDI;
    'RSVD'<20>:'(0,0,0,0,0,0,0,0,0,0,0,0,0,0,0,0,0,0,0,0,0,EA4,0,0,0,0,0,0,0,0)';BIDI;
    'RSVD'<19>:'(0,0,0,0,0,0,0,0,0,0,0,0,0,0,0,0,0,0,0,0,0,EA44,0,0,0,0,0,0,0,0)~
';BIDI;
    'RSVD'<18>:'(0,0,0,0,0,0,0,0,0,0,0,0,0,0,0,0,0,0,0,0,0,EB3,0,0,0,0,0,0,0,0)';BIDI;
    'RSVD'<17>:'(0,0,0,0,0,0,0,0,0,0,0,0,0,0,0,0,0,0,0,0,0,EB5,0,0,0,0,0,0,0,0)';BIDI;
    'RSVD'<16>:'(0,0,0,0,0,0,0,0,0,0,0,0,0,0,0,0,0,0,0,0,0,EB85,0,0,0,0,0,0,0,0)~
';BIDI;
    'RSVD'<15>:'(0,0,0,0,0,0,0,0,0,0,0,0,0,0,0,0,0,0,0,0,0,EC16,0,0,0,0,0,0,0,0)~
';BIDI;
    'RSVD'<14>:'(0,0,0,0,0,0,0,0,0,0,0,0,0,0,0,0,0,0,0,0,0,EC4,0,0,0,0,0,0,0,0)';BIDI;
    'RSVD'<13>:'(0,0,0,0,0,0,0,0,0,0,0,0,0,0,0,0,0,0,0,0,0,EC44,0,0,0,0,0,0,0,0)~
';BIDI;
    'RSVD'<12>:'(0,0,0,0,0,0,0,0,0,0,0,0,0,0,0,0,0,0,0,0,0,EC84,0,0,0,0,0,0,0,0)~
';BIDI;
    'RSVD'<11>:'(0,0,0,0,0,0,0,0,0,0,0,0,0,0,0,0,0,0,0,0,0,ED45,0,0,0,0,0,0,0,0)~
';BIDI;
    'RSVD'<10>:'(0,0,0,0,0,0,0,0,0,0,0,0,0,0,0,0,0,0,0,0,0,ED5,0,0,0,0,0,0,0,0)';BIDI;
    'RSVD'<9>:'(0,0,0,0,0,0,0,0,0,0,0,0,0,0,0,0,0,0,0,0,0,ED83,0,0,0,0,0,0,0,0)';BIDI;
    'RSVD'<8>:'(0,0,0,0,0,0,0,0,0,0,0,0,0,0,0,0,0,0,0,0,0,EE16,0,0,0,0,0,0,0,0)';BIDI;
    'RSVD'<7>:'(0,0,0,0,0,0,0,0,0,0,0,0,0,0,0,0,0,0,0,0,0,EE46,0,0,0,0,0,0,0,0)';BIDI;
    'RSVD'<6>:'(0,0,0,0,0,0,0,0,0,0,0,0,0,0,0,0,0,0,0,0,0,EE6,0,0,0,0,0,0,0,0)';~
BIDI;
    'RSVD'<5>:'(0,0,0,0,0,0,0,0,0,0,0,0,0,0,0,0,0,0,0,0,0,EE82,0,0,0,0,0,0,0,0)';BIDI;
    'RSVD'<4>:'(0,0,0,0,0,0,0,0,0,0,0,0,0,0,0,0,0,0,0,0,0,EE84,0,0,0,0,0,0,0,0)';BIDI;
    'RSVD'<3>:'(0,0,0,0,0,0,0,0,0,0,0,0,0,0,0,0,0,0,0,0,0,EF47,0,0,0,0,0,0,0,0)';BIDI;
    'RSVD'<2>:'(0,0,0,0,0,0,0,0,0,0,0,0,0,0,0,0,0,0,0,0,0,EF77,0,0,0,0,0,0,0,0)';BIDI;
    'RSVD'<1>:'(0,0,0,0,0,0,0,0,0,0,0,0,0,0,0,0,0,0,0,0,0,EF81,0,0,0,0,0,0,0,0)';BIDI;
    'RSVD'<0>:'(0,0,0,0,0,0,0,0,0,0,0,0,0,0,0,0,0,0,0,0,0,EF83,0,0,0,0,0,0,0,0)';BIDI;
    'SAFE_MODE_BOOT':'(AR18,0,0,0,0,0,0,0,0,0,0,0,0,0,0,0,0,0,0,0,0,0,0,0,0,0,0,~
0,0,0)';$S;IN;
    'SKTOCC_N':'(AB13,0,0,0,0,0,0,0,0,0,0,0,0,0,0,0,0,0,0,0,0,0,0,0,0,0,0,0,0,0)~
';$S;OUT;
    'SMBCLK':'(CT59,0,0,0,0,0,0,0,0,0,0,0,0,0,0,0,0,0,0,0,0,0,0,0,0,0,0,0,0,0)';~
$S;BIDI;
    'SMBDAT':'(CW58,0,0,0,0,0,0,0,0,0,0,0,0,0,0,0,0,0,0,0,0,0,0,0,0,0,0,0,0,0)';~
$S;BIDI;
    'SM_WP':'(CV59,0,0,0,0,0,0,0,0,0,0,0,0,0,0,0,0,0,0,0,0,0,0,0,0,0,0,0,0,0)';$~
S;IN;
    'SOCKET_ID'<2>:'(AU20,0,0,0,0,0,0,0,0,0,0,0,0,0,0,0,0,0,0,0,0,0,0,0,0,0,0,0,~
0,0)';IN;
    'SOCKET_ID'<1>:'(AU16,0,0,0,0,0,0,0,0,0,0,0,0,0,0,0,0,0,0,0,0,0,0,0,0,0,0,0,~
0,0)';IN;
    'SOCKET_ID'<0>:'(AU22,0,0,0,0,0,0,0,0,0,0,0,0,0,0,0,0,0,0,0,0,0,0,0,0,0,0,0,~
0,0)';IN;
    'SVIDALERT_N'<1>:'(DL44,0,0,0,0,0,0,0,0,0,0,0,0,0,0,0,0,0,0,0,0,0,0,0,0,0,0,~
0,0,0)';IN;
    'SVIDALERT_N'<0>:'(DE44,0,0,0,0,0,0,0,0,0,0,0,0,0,0,0,0,0,0,0,0,0,0,0,0,0,0,~
0,0,0)';IN;
    'SVIDCLK'<1>:'(DG44,0,0,0,0,0,0,0,0,0,0,0,0,0,0,0,0,0,0,0,0,0,0,0,0,0,0,0,0,~
0)';OUT;
    'SVIDCLK'<0>:'(DC44,0,0,0,0,0,0,0,0,0,0,0,0,0,0,0,0,0,0,0,0,0,0,0,0,0,0,0,0,~
0)';OUT;
    'SVIDDATA'<1>:'(DJ44,0,0,0,0,0,0,0,0,0,0,0,0,0,0,0,0,0,0,0,0,0,0,0,0,0,0,0,0~
,0)';BIDI;
    'SVIDDATA'<0>:'(DB45,0,0,0,0,0,0,0,0,0,0,0,0,0,0,0,0,0,0,0,0,0,0,0,0,0,0,0,0~
,0)';BIDI;
    'TCK':'(AA14,0,0,0,0,0,0,0,0,0,0,0,0,0,0,0,0,0,0,0,0,0,0,0,0,0,0,0,0,0)';$S;~
IN;
    'TDI':'(AC14,0,0,0,0,0,0,0,0,0,0,0,0,0,0,0,0,0,0,0,0,0,0,0,0,0,0,0,0,0)';$S;~
IN;
    'TDO':'(AE14,0,0,0,0,0,0,0,0,0,0,0,0,0,0,0,0,0,0,0,0,0,0,0,0,0,0,0,0,0)';$S;~
OUT;
    'TEST_1':'(0,AF45,0,0,0,0,0,0,0,0,0,0,0,0,0,0,0,0,0,0,0,0,0,0,0,0,0,0,0,0)';~
$S;BIDI;
    'TEST_10':'(0,0,0,0,0,0,0,0,0,0,0,0,0,0,0,0,AW22,0,0,0,0,0,0,0,0,0,0,0,0,0)';$S;BIDI;
    'TEST_11':'(0,AY13,0,0,0,0,0,0,0,0,0,0,0,0,0,0,0,0,0,0,0,0,0,0,0,0,0,0,0,0)';$S;BIDI;
    'TEST_12':'(AY19,0,0,0,0,0,0,0,0,0,0,0,0,0,0,0,0,0,0,0,0,0,0,0,0,0,0,0,0,0)';$S;BIDI;
    'TEST_13':'(DB51,0,0,0,0,0,0,0,0,0,0,0,0,0,0,0,0,0,0,0,0,0,0,0,0,0,0,0,0,0)';$S;BIDI;
    'TEST_14':'(DC50,0,0,0,0,0,0,0,0,0,0,0,0,0,0,0,0,0,0,0,0,0,0,0,0,0,0,0,0,0)';$S;BIDI;
    'TEST_15':'(AW14,0,0,0,0,0,0,0,0,0,0,0,0,0,0,0,0,0,0,0,0,0,0,0,0,0,0,0,0,0)';$S;BIDI;
    'TEST_2':'(0,AG46,0,0,0,0,0,0,0,0,0,0,0,0,0,0,0,0,0,0,0,0,0,0,0,0,0,0,0,0)';~
$S;BIDI;
    'TEST_3':'(0,AM13,0,0,0,0,0,0,0,0,0,0,0,0,0,0,0,0,0,0,0,0,0,0,0,0,0,0,0,0)';~
$S;BIDI;
    'TEST_4':'(0,AN12,0,0,0,0,0,0,0,0,0,0,0,0,0,0,0,0,0,0,0,0,0,0,0,0,0,0,0,0)';~
$S;BIDI;
    'TEST_5':'(0,AN14,0,0,0,0,0,0,0,0,0,0,0,0,0,0,0,0,0,0,0,0,0,0,0,0,0,0,0,0)';~
$S;BIDI;
    'TEST_6':'(0,0,0,0,0,0,0,0,0,0,0,0,0,0,0,0,AR16,0,0,0,0,0,0,0,0,0,0,0,0,0)';~
$S;BIDI;
    'TEST_7':'(0,0,0,0,0,0,0,0,0,0,0,0,0,0,0,0,AU18,0,0,0,0,0,0,0,0,0,0,0,0,0)';~
$S;BIDI;
    'TEST_8':'(0,0,0,0,0,0,0,0,0,0,0,0,0,0,0,0,AW16,0,0,0,0,0,0,0,0,0,0,0,0,0)';~
$S;BIDI;
    'TEST_9':'(0,0,0,0,0,0,0,0,0,0,0,0,0,0,0,0,AW20,0,0,0,0,0,0,0,0,0,0,0,0,0)';~
$S;BIDI;
    'THERMTRIP_N':'(AB15,0,0,0,0,0,0,0,0,0,0,0,0,0,0,0,0,0,0,0,0,0,0,0,0,0,0,0,0~
,0)';$S;OUT;
    'TMS':'(W14,0,0,0,0,0,0,0,0,0,0,0,0,0,0,0,0,0,0,0,0,0,0,0,0,0,0,0,0,0)';$S;I~
N;
    'TRST_N':'(Y13,0,0,0,0,0,0,0,0,0,0,0,0,0,0,0,0,0,0,0,0,0,0,0,0,0,0,0,0,0)';$~
S;IN;
    'TSC_SYNC':'(AM11,0,0,0,0,0,0,0,0,0,0,0,0,0,0,0,0,0,0,0,0,0,0,0,0,0,0,0,0,0)~
';$S;BIDI;
    'TXT_AGENT':'(AW18,0,0,0,0,0,0,0,0,0,0,0,0,0,0,0,0,0,0,0,0,0,0,0,0,0,0,0,0,0~
)';$S;IN;
    'TXT_PLTEN':'(AV15,0,0,0,0,0,0,0,0,0,0,0,0,0,0,0,0,0,0,0,0,0,0,0,0,0,0,0,0,0~
)';$S;IN;
    'UPI01_RBIAS'<1>:'(AP29,0,0,0,0,0,0,0,0,0,0,0,0,0,0,0,0,0,0,0,0,0,0,0,0,0,0,~
0,0,0)';IN;
    'UPI01_RBIAS'<0>:'(AT29,0,0,0,0,0,0,0,0,0,0,0,0,0,0,0,0,0,0,0,0,0,0,0,0,0,0,~
0,0,0)';IN;
    'UPI0_RX_DN'<19>:'(0,0,0,0,0,0,0,0,0,0,0,0,BB11,0,0,0,0,0,0,0,0,0,0,0,0,0,0,~
0,0,0)';IN;
    'UPI0_RX_DN'<18>:'(0,0,0,0,0,0,0,0,0,0,0,0,BD9,0,0,0,0,0,0,0,0,0,0,0,0,0,0,0~
,0,0)';IN;
    'UPI0_RX_DN'<17>:'(0,0,0,0,0,0,0,0,0,0,0,0,AY9,0,0,0,0,0,0,0,0,0,0,0,0,0,0,0~
,0,0)';IN;
    'UPI0_RX_DN'<16>:'(0,0,0,0,0,0,0,0,0,0,0,0,AW8,0,0,0,0,0,0,0,0,0,0,0,0,0,0,0~
,0,0)';IN;
    'UPI0_RX_DN'<15>:'(0,0,0,0,0,0,0,0,0,0,0,0,BD7,0,0,0,0,0,0,0,0,0,0,0,0,0,0,0~
,0,0)';IN;
    'UPI0_RX_DN'<14>:'(0,0,0,0,0,0,0,0,0,0,0,0,BC6,0,0,0,0,0,0,0,0,0,0,0,0,0,0,0~
,0,0)';IN;
    'UPI0_RX_DN'<13>:'(0,0,0,0,0,0,0,0,0,0,0,0,BA8,0,0,0,0,0,0,0,0,0,0,0,0,0,0,0~
,0,0)';IN;
    'UPI0_RX_DN'<12>:'(0,0,0,0,0,0,0,0,0,0,0,0,AU10,0,0,0,0,0,0,0,0,0,0,0,0,0,0,~
0,0,0)';IN;
    'UPI0_RX_DN'<11>:'(0,0,0,0,0,0,0,0,0,0,0,0,AR8,0,0,0,0,0,0,0,0,0,0,0,0,0,0,0~
,0,0)';IN;
    'UPI0_RX_DN'<10>:'(0,0,0,0,0,0,0,0,0,0,0,0,AP7,0,0,0,0,0,0,0,0,0,0,0,0,0,0,0~
,0,0)';IN;
    'UPI0_RX_DN'<9>:'(0,0,0,0,0,0,0,0,0,0,0,0,AM9,0,0,0,0,0,0,0,0,0,0,0,0,0,0,0,~
0,0)';IN;
    'UPI0_RX_DN'<8>:'(0,0,0,0,0,0,0,0,0,0,0,0,AK7,0,0,0,0,0,0,0,0,0,0,0,0,0,0,0,~
0,0)';IN;
    'UPI0_RX_DN'<7>:'(0,0,0,0,0,0,0,0,0,0,0,0,AL6,0,0,0,0,0,0,0,0,0,0,0,0,0,0,0,~
0,0)';IN;
    'UPI0_RX_DN'<6>:'(0,0,0,0,0,0,0,0,0,0,0,0,AJ6,0,0,0,0,0,0,0,0,0,0,0,0,0,0,0,~
0,0)';IN;
    'UPI0_RX_DN'<5>:'(0,0,0,0,0,0,0,0,0,0,0,0,AG8,0,0,0,0,0,0,0,0,0,0,0,0,0,0,0,~
0,0)';IN;
    'UPI0_RX_DN'<4>:'(0,0,0,0,0,0,0,0,0,0,0,0,AE6,0,0,0,0,0,0,0,0,0,0,0,0,0,0,0,~
0,0)';IN;
    'UPI0_RX_DN'<3>:'(0,0,0,0,0,0,0,0,0,0,0,0,AD5,0,0,0,0,0,0,0,0,0,0,0,0,0,0,0,~
0,0)';IN;
    'UPI0_RX_DN'<2>:'(0,0,0,0,0,0,0,0,0,0,0,0,AB7,0,0,0,0,0,0,0,0,0,0,0,0,0,0,0,~
0,0)';IN;
    'UPI0_RX_DN'<1>:'(0,0,0,0,0,0,0,0,0,0,0,0,AA8,0,0,0,0,0,0,0,0,0,0,0,0,0,0,0,~
0,0)';IN;
    'UPI0_RX_DN'<0>:'(0,0,0,0,0,0,0,0,0,0,0,0,AC10,0,0,0,0,0,0,0,0,0,0,0,0,0,0,0~
,0,0)';IN;
    'UPI0_RX_DP'<19>:'(0,0,0,0,0,0,0,0,0,0,0,0,BA10,0,0,0,0,0,0,0,0,0,0,0,0,0,0,~
0,0,0)';IN;
    'UPI0_RX_DP'<18>:'(0,0,0,0,0,0,0,0,0,0,0,0,BC10,0,0,0,0,0,0,0,0,0,0,0,0,0,0,~
0,0,0)';IN;
    'UPI0_RX_DP'<17>:'(0,0,0,0,0,0,0,0,0,0,0,0,BB9,0,0,0,0,0,0,0,0,0,0,0,0,0,0,0~
,0,0)';IN;
    'UPI0_RX_DP'<16>:'(0,0,0,0,0,0,0,0,0,0,0,0,AV9,0,0,0,0,0,0,0,0,0,0,0,0,0,0,0~
,0,0)';IN;
    'UPI0_RX_DP'<15>:'(0,0,0,0,0,0,0,0,0,0,0,0,BF7,0,0,0,0,0,0,0,0,0,0,0,0,0,0,0~
,0,0)';IN;
    'UPI0_RX_DP'<14>:'(0,0,0,0,0,0,0,0,0,0,0,0,BB7,0,0,0,0,0,0,0,0,0,0,0,0,0,0,0~
,0,0)';IN;
    'UPI0_RX_DP'<13>:'(0,0,0,0,0,0,0,0,0,0,0,0,AY7,0,0,0,0,0,0,0,0,0,0,0,0,0,0,0~
,0,0)';IN;
    'UPI0_RX_DP'<12>:'(0,0,0,0,0,0,0,0,0,0,0,0,AT9,0,0,0,0,0,0,0,0,0,0,0,0,0,0,0~
,0,0)';IN;
    'UPI0_RX_DP'<11>:'(0,0,0,0,0,0,0,0,0,0,0,0,AU8,0,0,0,0,0,0,0,0,0,0,0,0,0,0,0~
,0,0)';IN;
    'UPI0_RX_DP'<10>:'(0,0,0,0,0,0,0,0,0,0,0,0,AN8,0,0,0,0,0,0,0,0,0,0,0,0,0,0,0~
,0,0)';IN;
    'UPI0_RX_DP'<9>:'(0,0,0,0,0,0,0,0,0,0,0,0,AL8,0,0,0,0,0,0,0,0,0,0,0,0,0,0,0,~
0,0)';IN;
    'UPI0_RX_DP'<8>:'(0,0,0,0,0,0,0,0,0,0,0,0,AM7,0,0,0,0,0,0,0,0,0,0,0,0,0,0,0,~
0,0)';IN;
    'UPI0_RX_DP'<7>:'(0,0,0,0,0,0,0,0,0,0,0,0,AK5,0,0,0,0,0,0,0,0,0,0,0,0,0,0,0,~
0,0)';IN;
    'UPI0_RX_DP'<6>:'(0,0,0,0,0,0,0,0,0,0,0,0,AH7,0,0,0,0,0,0,0,0,0,0,0,0,0,0,0,~
0,0)';IN;
    'UPI0_RX_DP'<5>:'(0,0,0,0,0,0,0,0,0,0,0,0,AF7,0,0,0,0,0,0,0,0,0,0,0,0,0,0,0,~
0,0)';IN;
    'UPI0_RX_DP'<4>:'(0,0,0,0,0,0,0,0,0,0,0,0,AG6,0,0,0,0,0,0,0,0,0,0,0,0,0,0,0,~
0,0)';IN;
    'UPI0_RX_DP'<3>:'(0,0,0,0,0,0,0,0,0,0,0,0,AC6,0,0,0,0,0,0,0,0,0,0,0,0,0,0,0,~
0,0)';IN;
    'UPI0_RX_DP'<2>:'(0,0,0,0,0,0,0,0,0,0,0,0,AA6,0,0,0,0,0,0,0,0,0,0,0,0,0,0,0,~
0,0)';IN;
    'UPI0_RX_DP'<1>:'(0,0,0,0,0,0,0,0,0,0,0,0,AC8,0,0,0,0,0,0,0,0,0,0,0,0,0,0,0,~
0,0)';IN;
    'UPI0_RX_DP'<0>:'(0,0,0,0,0,0,0,0,0,0,0,0,AB9,0,0,0,0,0,0,0,0,0,0,0,0,0,0,0,~
0,0)';IN;
    'UPI0_TX_DN'<19>:'(0,0,0,0,0,0,0,0,0,0,0,0,BG4,0,0,0,0,0,0,0,0,0,0,0,0,0,0,0~
,0,0)';OUT;
    'UPI0_TX_DN'<18>:'(0,0,0,0,0,0,0,0,0,0,0,0,BF3,0,0,0,0,0,0,0,0,0,0,0,0,0,0,0~
,0,0)';OUT;
    'UPI0_TX_DN'<17>:'(0,0,0,0,0,0,0,0,0,0,0,0,BB3,0,0,0,0,0,0,0,0,0,0,0,0,0,0,0~
,0,0)';OUT;
    'UPI0_TX_DN'<16>:'(0,0,0,0,0,0,0,0,0,0,0,0,BA4,0,0,0,0,0,0,0,0,0,0,0,0,0,0,0~
,0,0)';OUT;
    'UPI0_TX_DN'<15>:'(0,0,0,0,0,0,0,0,0,0,0,0,AV5,0,0,0,0,0,0,0,0,0,0,0,0,0,0,0~
,0,0)';OUT;
    'UPI0_TX_DN'<14>:'(0,0,0,0,0,0,0,0,0,0,0,0,AU4,0,0,0,0,0,0,0,0,0,0,0,0,0,0,0~
,0,0)';OUT;
    'UPI0_TX_DN'<13>:'(0,0,0,0,0,0,0,0,0,0,0,0,AT3,0,0,0,0,0,0,0,0,0,0,0,0,0,0,0~
,0,0)';OUT;
    'UPI0_TX_DN'<12>:'(0,0,0,0,0,0,0,0,0,0,0,0,AT1,0,0,0,0,0,0,0,0,0,0,0,0,0,0,0~
,0,0)';OUT;
    'UPI0_TX_DN'<11>:'(0,0,0,0,0,0,0,0,0,0,0,0,AN4,0,0,0,0,0,0,0,0,0,0,0,0,0,0,0~
,0,0)';OUT;
    'UPI0_TX_DN'<10>:'(0,0,0,0,0,0,0,0,0,0,0,0,AM3,0,0,0,0,0,0,0,0,0,0,0,0,0,0,0~
,0,0)';OUT;
    'UPI0_TX_DN'<9>:'(0,0,0,0,0,0,0,0,0,0,0,0,AL2,0,0,0,0,0,0,0,0,0,0,0,0,0,0,0,~
0,0)';OUT;
    'UPI0_TX_DN'<8>:'(0,0,0,0,0,0,0,0,0,0,0,0,AH3,0,0,0,0,0,0,0,0,0,0,0,0,0,0,0,~
0,0)';OUT;
    'UPI0_TX_DN'<7>:'(0,0,0,0,0,0,0,0,0,0,0,0,AE2,0,0,0,0,0,0,0,0,0,0,0,0,0,0,0,~
0,0)';OUT;
    'UPI0_TX_DN'<6>:'(0,0,0,0,0,0,0,0,0,0,0,0,AG4,0,0,0,0,0,0,0,0,0,0,0,0,0,0,0,~
0,0)';OUT;
    'UPI0_TX_DN'<5>:'(0,0,0,0,0,0,0,0,0,0,0,0,AC2,0,0,0,0,0,0,0,0,0,0,0,0,0,0,0,~
0,0)';OUT;
    'UPI0_TX_DN'<4>:'(0,0,0,0,0,0,0,0,0,0,0,0,AB3,0,0,0,0,0,0,0,0,0,0,0,0,0,0,0,~
0,0)';OUT;
    'UPI0_TX_DN'<3>:'(0,0,0,0,0,0,0,0,0,0,0,0,Y1,0,0,0,0,0,0,0,0,0,0,0,0,0,0,0,0~
,0)';OUT;
    'UPI0_TX_DN'<2>:'(0,0,0,0,0,0,0,0,0,0,0,0,V3,0,0,0,0,0,0,0,0,0,0,0,0,0,0,0,0~
,0)';OUT;
    'UPI0_TX_DN'<1>:'(0,0,0,0,0,0,0,0,0,0,0,0,P1,0,0,0,0,0,0,0,0,0,0,0,0,0,0,0,0~
,0)';OUT;
    'UPI0_TX_DN'<0>:'(0,0,0,0,0,0,0,0,0,0,0,0,N2,0,0,0,0,0,0,0,0,0,0,0,0,0,0,0,0~
,0)';OUT;
    'UPI0_TX_DP'<19>:'(0,0,0,0,0,0,0,0,0,0,0,0,BH3,0,0,0,0,0,0,0,0,0,0,0,0,0,0,0~
,0,0)';OUT;
    'UPI0_TX_DP'<18>:'(0,0,0,0,0,0,0,0,0,0,0,0,BD3,0,0,0,0,0,0,0,0,0,0,0,0,0,0,0~
,0,0)';OUT;
    'UPI0_TX_DP'<17>:'(0,0,0,0,0,0,0,0,0,0,0,0,BC2,0,0,0,0,0,0,0,0,0,0,0,0,0,0,0~
,0,0)';OUT;
    'UPI0_TX_DP'<16>:'(0,0,0,0,0,0,0,0,0,0,0,0,AY3,0,0,0,0,0,0,0,0,0,0,0,0,0,0,0~
,0,0)';OUT;
    'UPI0_TX_DP'<15>:'(0,0,0,0,0,0,0,0,0,0,0,0,AW4,0,0,0,0,0,0,0,0,0,0,0,0,0,0,0~
,0,0)';OUT;
    'UPI0_TX_DP'<14>:'(0,0,0,0,0,0,0,0,0,0,0,0,AR4,0,0,0,0,0,0,0,0,0,0,0,0,0,0,0~
,0,0)';OUT;
    'UPI0_TX_DP'<13>:'(0,0,0,0,0,0,0,0,0,0,0,0,AR2,0,0,0,0,0,0,0,0,0,0,0,0,0,0,0~
,0,0)';OUT;
    'UPI0_TX_DP'<12>:'(0,0,0,0,0,0,0,0,0,0,0,0,AP1,0,0,0,0,0,0,0,0,0,0,0,0,0,0,0~
,0,0)';OUT;
    'UPI0_TX_DP'<11>:'(0,0,0,0,0,0,0,0,0,0,0,0,AP3,0,0,0,0,0,0,0,0,0,0,0,0,0,0,0~
,0,0)';OUT;
    'UPI0_TX_DP'<10>:'(0,0,0,0,0,0,0,0,0,0,0,0,AK3,0,0,0,0,0,0,0,0,0,0,0,0,0,0,0~
,0,0)';OUT;
    'UPI0_TX_DP'<9>:'(0,0,0,0,0,0,0,0,0,0,0,0,AK1,0,0,0,0,0,0,0,0,0,0,0,0,0,0,0,~
0,0)';OUT;
    'UPI0_TX_DP'<8>:'(0,0,0,0,0,0,0,0,0,0,0,0,AJ2,0,0,0,0,0,0,0,0,0,0,0,0,0,0,0,~
0,0)';OUT;
    'UPI0_TX_DP'<7>:'(0,0,0,0,0,0,0,0,0,0,0,0,AG2,0,0,0,0,0,0,0,0,0,0,0,0,0,0,0,~
0,0)';OUT;
    'UPI0_TX_DP'<6>:'(0,0,0,0,0,0,0,0,0,0,0,0,AF3,0,0,0,0,0,0,0,0,0,0,0,0,0,0,0,~
0,0)';OUT;
    'UPI0_TX_DP'<5>:'(0,0,0,0,0,0,0,0,0,0,0,0,AD1,0,0,0,0,0,0,0,0,0,0,0,0,0,0,0,~
0,0)';OUT;
    'UPI0_TX_DP'<4>:'(0,0,0,0,0,0,0,0,0,0,0,0,AA2,0,0,0,0,0,0,0,0,0,0,0,0,0,0,0,~
0,0)';OUT;
    'UPI0_TX_DP'<3>:'(0,0,0,0,0,0,0,0,0,0,0,0,W2,0,0,0,0,0,0,0,0,0,0,0,0,0,0,0,0~
,0)';OUT;
    'UPI0_TX_DP'<2>:'(0,0,0,0,0,0,0,0,0,0,0,0,Y3,0,0,0,0,0,0,0,0,0,0,0,0,0,0,0,0~
,0)';OUT;
    'UPI0_TX_DP'<1>:'(0,0,0,0,0,0,0,0,0,0,0,0,T1,0,0,0,0,0,0,0,0,0,0,0,0,0,0,0,0~
,0)';OUT;
    'UPI0_TX_DP'<0>:'(0,0,0,0,0,0,0,0,0,0,0,0,M1,0,0,0,0,0,0,0,0,0,0,0,0,0,0,0,0~
,0)';OUT;
    'UPI1_RX_DN'<19>:'(0,0,0,0,0,0,0,0,0,0,0,0,0,AB19,0,0,0,0,0,0,0,0,0,0,0,0,0,~
0,0,0)';IN;
    'UPI1_RX_DN'<18>:'(0,0,0,0,0,0,0,0,0,0,0,0,0,Y21,0,0,0,0,0,0,0,0,0,0,0,0,0,0~
,0,0)';IN;
    'UPI1_RX_DN'<17>:'(0,0,0,0,0,0,0,0,0,0,0,0,0,V19,0,0,0,0,0,0,0,0,0,0,0,0,0,0~
,0,0)';IN;
    'UPI1_RX_DN'<16>:'(0,0,0,0,0,0,0,0,0,0,0,0,0,P21,0,0,0,0,0,0,0,0,0,0,0,0,0,0~
,0,0)';IN;
    'UPI1_RX_DN'<15>:'(0,0,0,0,0,0,0,0,0,0,0,0,0,U18,0,0,0,0,0,0,0,0,0,0,0,0,0,0~
,0,0)';IN;
    'UPI1_RX_DN'<14>:'(0,0,0,0,0,0,0,0,0,0,0,0,0,R20,0,0,0,0,0,0,0,0,0,0,0,0,0,0~
,0,0)';IN;
    'UPI1_RX_DN'<13>:'(0,0,0,0,0,0,0,0,0,0,0,0,0,W18,0,0,0,0,0,0,0,0,0,0,0,0,0,0~
,0,0)';IN;
    'UPI1_RX_DN'<12>:'(0,0,0,0,0,0,0,0,0,0,0,0,0,U16,0,0,0,0,0,0,0,0,0,0,0,0,0,0~
,0,0)';IN;
    'UPI1_RX_DN'<11>:'(0,0,0,0,0,0,0,0,0,0,0,0,0,P17,0,0,0,0,0,0,0,0,0,0,0,0,0,0~
,0,0)';IN;
    'UPI1_RX_DN'<10>:'(0,0,0,0,0,0,0,0,0,0,0,0,0,R16,0,0,0,0,0,0,0,0,0,0,0,0,0,0~
,0,0)';IN;
    'UPI1_RX_DN'<9>:'(0,0,0,0,0,0,0,0,0,0,0,0,0,R12,0,0,0,0,0,0,0,0,0,0,0,0,0,0,~
0,0)';IN;
    'UPI1_RX_DN'<8>:'(0,0,0,0,0,0,0,0,0,0,0,0,0,N14,0,0,0,0,0,0,0,0,0,0,0,0,0,0,~
0,0)';IN;
    'UPI1_RX_DN'<7>:'(0,0,0,0,0,0,0,0,0,0,0,0,0,L12,0,0,0,0,0,0,0,0,0,0,0,0,0,0,~
0,0)';IN;
    'UPI1_RX_DN'<6>:'(0,0,0,0,0,0,0,0,0,0,0,0,0,U12,0,0,0,0,0,0,0,0,0,0,0,0,0,0,~
0,0)';IN;
    'UPI1_RX_DN'<5>:'(0,0,0,0,0,0,0,0,0,0,0,0,0,R10,0,0,0,0,0,0,0,0,0,0,0,0,0,0,~
0,0)';IN;
    'UPI1_RX_DN'<4>:'(0,0,0,0,0,0,0,0,0,0,0,0,0,P9,0,0,0,0,0,0,0,0,0,0,0,0,0,0,0~
,0)';IN;
    'UPI1_RX_DN'<3>:'(0,0,0,0,0,0,0,0,0,0,0,0,0,T9,0,0,0,0,0,0,0,0,0,0,0,0,0,0,0~
,0)';IN;
    'UPI1_RX_DN'<2>:'(0,0,0,0,0,0,0,0,0,0,0,0,0,V7,0,0,0,0,0,0,0,0,0,0,0,0,0,0,0~
,0)';IN;
    'UPI1_RX_DN'<1>:'(0,0,0,0,0,0,0,0,0,0,0,0,0,P7,0,0,0,0,0,0,0,0,0,0,0,0,0,0,0~
,0)';IN;
    'UPI1_RX_DN'<0>:'(0,0,0,0,0,0,0,0,0,0,0,0,0,T5,0,0,0,0,0,0,0,0,0,0,0,0,0,0,0~
,0)';IN;
    'UPI1_RX_DP'<19>:'(0,0,0,0,0,0,0,0,0,0,0,0,0,AA20,0,0,0,0,0,0,0,0,0,0,0,0,0,~
0,0,0)';IN;
    'UPI1_RX_DP'<18>:'(0,0,0,0,0,0,0,0,0,0,0,0,0,W20,0,0,0,0,0,0,0,0,0,0,0,0,0,0~
,0,0)';IN;
    'UPI1_RX_DP'<17>:'(0,0,0,0,0,0,0,0,0,0,0,0,0,Y19,0,0,0,0,0,0,0,0,0,0,0,0,0,0~
,0,0)';IN;
    'UPI1_RX_DP'<16>:'(0,0,0,0,0,0,0,0,0,0,0,0,0,T21,0,0,0,0,0,0,0,0,0,0,0,0,0,0~
,0,0)';IN;
    'UPI1_RX_DP'<15>:'(0,0,0,0,0,0,0,0,0,0,0,0,0,T19,0,0,0,0,0,0,0,0,0,0,0,0,0,0~
,0,0)';IN;
    'UPI1_RX_DP'<14>:'(0,0,0,0,0,0,0,0,0,0,0,0,0,P19,0,0,0,0,0,0,0,0,0,0,0,0,0,0~
,0,0)';IN;
    'UPI1_RX_DP'<13>:'(0,0,0,0,0,0,0,0,0,0,0,0,0,V17,0,0,0,0,0,0,0,0,0,0,0,0,0,0~
,0,0)';IN;
    'UPI1_RX_DP'<12>:'(0,0,0,0,0,0,0,0,0,0,0,0,0,W16,0,0,0,0,0,0,0,0,0,0,0,0,0,0~
,0,0)';IN;
    'UPI1_RX_DP'<11>:'(0,0,0,0,0,0,0,0,0,0,0,0,0,N16,0,0,0,0,0,0,0,0,0,0,0,0,0,0~
,0,0)';IN;
    'UPI1_RX_DP'<10>:'(0,0,0,0,0,0,0,0,0,0,0,0,0,T15,0,0,0,0,0,0,0,0,0,0,0,0,0,0~
,0,0)';IN;
    'UPI1_RX_DP'<9>:'(0,0,0,0,0,0,0,0,0,0,0,0,0,P13,0,0,0,0,0,0,0,0,0,0,0,0,0,0,~
0,0)';IN;
    'UPI1_RX_DP'<8>:'(0,0,0,0,0,0,0,0,0,0,0,0,0,M13,0,0,0,0,0,0,0,0,0,0,0,0,0,0,~
0,0)';IN;
    'UPI1_RX_DP'<7>:'(0,0,0,0,0,0,0,0,0,0,0,0,0,N12,0,0,0,0,0,0,0,0,0,0,0,0,0,0,~
0,0)';IN;
    'UPI1_RX_DP'<6>:'(0,0,0,0,0,0,0,0,0,0,0,0,0,T11,0,0,0,0,0,0,0,0,0,0,0,0,0,0,~
0,0)';IN;
    'UPI1_RX_DP'<5>:'(0,0,0,0,0,0,0,0,0,0,0,0,0,U10,0,0,0,0,0,0,0,0,0,0,0,0,0,0,~
0,0)';IN;
    'UPI1_RX_DP'<4>:'(0,0,0,0,0,0,0,0,0,0,0,0,0,N10,0,0,0,0,0,0,0,0,0,0,0,0,0,0,~
0,0)';IN;
    'UPI1_RX_DP'<3>:'(0,0,0,0,0,0,0,0,0,0,0,0,0,R8,0,0,0,0,0,0,0,0,0,0,0,0,0,0,0~
,0)';IN;
    'UPI1_RX_DP'<2>:'(0,0,0,0,0,0,0,0,0,0,0,0,0,U8,0,0,0,0,0,0,0,0,0,0,0,0,0,0,0~
,0)';IN;
    'UPI1_RX_DP'<1>:'(0,0,0,0,0,0,0,0,0,0,0,0,0,T7,0,0,0,0,0,0,0,0,0,0,0,0,0,0,0~
,0)';IN;
    'UPI1_RX_DP'<0>:'(0,0,0,0,0,0,0,0,0,0,0,0,0,R6,0,0,0,0,0,0,0,0,0,0,0,0,0,0,0~
,0)';IN;
    'UPI1_TX_DN'<19>:'(0,0,0,0,0,0,0,0,0,0,0,0,0,H21,0,0,0,0,0,0,0,0,0,0,0,0,0,0~
,0,0)';OUT;
    'UPI1_TX_DN'<18>:'(0,0,0,0,0,0,0,0,0,0,0,0,0,F21,0,0,0,0,0,0,0,0,0,0,0,0,0,0~
,0,0)';OUT;
    'UPI1_TX_DN'<17>:'(0,0,0,0,0,0,0,0,0,0,0,0,0,J20,0,0,0,0,0,0,0,0,0,0,0,0,0,0~
,0,0)';OUT;
    'UPI1_TX_DN'<16>:'(0,0,0,0,0,0,0,0,0,0,0,0,0,G18,0,0,0,0,0,0,0,0,0,0,0,0,0,0~
,0,0)';OUT;
    'UPI1_TX_DN'<15>:'(0,0,0,0,0,0,0,0,0,0,0,0,0,K19,0,0,0,0,0,0,0,0,0,0,0,0,0,0~
,0,0)';OUT;
    'UPI1_TX_DN'<14>:'(0,0,0,0,0,0,0,0,0,0,0,0,0,H17,0,0,0,0,0,0,0,0,0,0,0,0,0,0~
,0,0)';OUT;
    'UPI1_TX_DN'<13>:'(0,0,0,0,0,0,0,0,0,0,0,0,0,F15,0,0,0,0,0,0,0,0,0,0,0,0,0,0~
,0,0)';OUT;
    'UPI1_TX_DN'<12>:'(0,0,0,0,0,0,0,0,0,0,0,0,0,D15,0,0,0,0,0,0,0,0,0,0,0,0,0,0~
,0,0)';OUT;
    'UPI1_TX_DN'<11>:'(0,0,0,0,0,0,0,0,0,0,0,0,0,G14,0,0,0,0,0,0,0,0,0,0,0,0,0,0~
,0,0)';OUT;
    'UPI1_TX_DN'<10>:'(0,0,0,0,0,0,0,0,0,0,0,0,0,E12,0,0,0,0,0,0,0,0,0,0,0,0,0,0~
,0,0)';OUT;
    'UPI1_TX_DN'<9>:'(0,0,0,0,0,0,0,0,0,0,0,0,0,G10,0,0,0,0,0,0,0,0,0,0,0,0,0,0,~
0,0)';OUT;
    'UPI1_TX_DN'<8>:'(0,0,0,0,0,0,0,0,0,0,0,0,0,F11,0,0,0,0,0,0,0,0,0,0,0,0,0,0,~
0,0)';OUT;
    'UPI1_TX_DN'<7>:'(0,0,0,0,0,0,0,0,0,0,0,0,0,D9,0,0,0,0,0,0,0,0,0,0,0,0,0,0,0~
,0)';OUT;
    'UPI1_TX_DN'<6>:'(0,0,0,0,0,0,0,0,0,0,0,0,0,K9,0,0,0,0,0,0,0,0,0,0,0,0,0,0,0~
,0)';OUT;
    'UPI1_TX_DN'<5>:'(0,0,0,0,0,0,0,0,0,0,0,0,0,H7,0,0,0,0,0,0,0,0,0,0,0,0,0,0,0~
,0)';OUT;
    'UPI1_TX_DN'<4>:'(0,0,0,0,0,0,0,0,0,0,0,0,0,G6,0,0,0,0,0,0,0,0,0,0,0,0,0,0,0~
,0)';OUT;
    'UPI1_TX_DN'<3>:'(0,0,0,0,0,0,0,0,0,0,0,0,0,J6,0,0,0,0,0,0,0,0,0,0,0,0,0,0,0~
,0)';OUT;
    'UPI1_TX_DN'<2>:'(0,0,0,0,0,0,0,0,0,0,0,0,0,K5,0,0,0,0,0,0,0,0,0,0,0,0,0,0,0~
,0)';OUT;
    'UPI1_TX_DN'<1>:'(0,0,0,0,0,0,0,0,0,0,0,0,0,L4,0,0,0,0,0,0,0,0,0,0,0,0,0,0,0~
,0)';OUT;
    'UPI1_TX_DN'<0>:'(0,0,0,0,0,0,0,0,0,0,0,0,0,M3,0,0,0,0,0,0,0,0,0,0,0,0,0,0,0~
,0)';OUT;
    'UPI1_TX_DP'<19>:'(0,0,0,0,0,0,0,0,0,0,0,0,0,K21,0,0,0,0,0,0,0,0,0,0,0,0,0,0~
,0,0)';OUT;
    'UPI1_TX_DP'<18>:'(0,0,0,0,0,0,0,0,0,0,0,0,0,G20,0,0,0,0,0,0,0,0,0,0,0,0,0,0~
,0,0)';OUT;
    'UPI1_TX_DP'<17>:'(0,0,0,0,0,0,0,0,0,0,0,0,0,H19,0,0,0,0,0,0,0,0,0,0,0,0,0,0~
,0,0)';OUT;
    'UPI1_TX_DP'<16>:'(0,0,0,0,0,0,0,0,0,0,0,0,0,J18,0,0,0,0,0,0,0,0,0,0,0,0,0,0~
,0,0)';OUT;
    'UPI1_TX_DP'<15>:'(0,0,0,0,0,0,0,0,0,0,0,0,0,L18,0,0,0,0,0,0,0,0,0,0,0,0,0,0~
,0,0)';OUT;
    'UPI1_TX_DP'<14>:'(0,0,0,0,0,0,0,0,0,0,0,0,0,G16,0,0,0,0,0,0,0,0,0,0,0,0,0,0~
,0,0)';OUT;
    'UPI1_TX_DP'<13>:'(0,0,0,0,0,0,0,0,0,0,0,0,0,H15,0,0,0,0,0,0,0,0,0,0,0,0,0,0~
,0,0)';OUT;
    'UPI1_TX_DP'<12>:'(0,0,0,0,0,0,0,0,0,0,0,0,0,E14,0,0,0,0,0,0,0,0,0,0,0,0,0,0~
,0,0)';OUT;
    'UPI1_TX_DP'<11>:'(0,0,0,0,0,0,0,0,0,0,0,0,0,F13,0,0,0,0,0,0,0,0,0,0,0,0,0,0~
,0,0)';OUT;
    'UPI1_TX_DP'<10>:'(0,0,0,0,0,0,0,0,0,0,0,0,0,G12,0,0,0,0,0,0,0,0,0,0,0,0,0,0~
,0,0)';OUT;
    'UPI1_TX_DP'<9>:'(0,0,0,0,0,0,0,0,0,0,0,0,0,H9,0,0,0,0,0,0,0,0,0,0,0,0,0,0,0~
,0)';OUT;
    'UPI1_TX_DP'<8>:'(0,0,0,0,0,0,0,0,0,0,0,0,0,E10,0,0,0,0,0,0,0,0,0,0,0,0,0,0,~
0,0)';OUT;
    'UPI1_TX_DP'<7>:'(0,0,0,0,0,0,0,0,0,0,0,0,0,F9,0,0,0,0,0,0,0,0,0,0,0,0,0,0,0~
,0)';OUT;
    'UPI1_TX_DP'<6>:'(0,0,0,0,0,0,0,0,0,0,0,0,0,J8,0,0,0,0,0,0,0,0,0,0,0,0,0,0,0~
,0)';OUT;
    'UPI1_TX_DP'<5>:'(0,0,0,0,0,0,0,0,0,0,0,0,0,K7,0,0,0,0,0,0,0,0,0,0,0,0,0,0,0~
,0)';OUT;
    'UPI1_TX_DP'<4>:'(0,0,0,0,0,0,0,0,0,0,0,0,0,F7,0,0,0,0,0,0,0,0,0,0,0,0,0,0,0~
,0)';OUT;
    'UPI1_TX_DP'<3>:'(0,0,0,0,0,0,0,0,0,0,0,0,0,H5,0,0,0,0,0,0,0,0,0,0,0,0,0,0,0~
,0)';OUT;
    'UPI1_TX_DP'<2>:'(0,0,0,0,0,0,0,0,0,0,0,0,0,M5,0,0,0,0,0,0,0,0,0,0,0,0,0,0,0~
,0)';OUT;
    'UPI1_TX_DP'<1>:'(0,0,0,0,0,0,0,0,0,0,0,0,0,K3,0,0,0,0,0,0,0,0,0,0,0,0,0,0,0~
,0)';OUT;
    'UPI1_TX_DP'<0>:'(0,0,0,0,0,0,0,0,0,0,0,0,0,P3,0,0,0,0,0,0,0,0,0,0,0,0,0,0,0~
,0)';OUT;
    'UPI2_RBIAS'<1>:'(CK29,0,0,0,0,0,0,0,0,0,0,0,0,0,0,0,0,0,0,0,0,0,0,0,0,0,0,0~
,0,0)';IN;
    'UPI2_RBIAS'<0>:'(CL28,0,0,0,0,0,0,0,0,0,0,0,0,0,0,0,0,0,0,0,0,0,0,0,0,0,0,0~
,0,0)';IN;
    'UPI2_RX_DN'<19>:'(0,0,0,0,0,0,0,0,0,0,0,0,0,0,BY17,0,0,0,0,0,0,0,0,0,0,0,0,~
0,0,0)';IN;
    'UPI2_RX_DN'<18>:'(0,0,0,0,0,0,0,0,0,0,0,0,0,0,CB15,0,0,0,0,0,0,0,0,0,0,0,0,~
0,0,0)';IN;
    'UPI2_RX_DN'<17>:'(0,0,0,0,0,0,0,0,0,0,0,0,0,0,CF17,0,0,0,0,0,0,0,0,0,0,0,0,~
0,0,0)';IN;
    'UPI2_RX_DN'<16>:'(0,0,0,0,0,0,0,0,0,0,0,0,0,0,CD15,0,0,0,0,0,0,0,0,0,0,0,0,~
0,0,0)';IN;
    'UPI2_RX_DN'<15>:'(0,0,0,0,0,0,0,0,0,0,0,0,0,0,CE16,0,0,0,0,0,0,0,0,0,0,0,0,~
0,0,0)';IN;
    'UPI2_RX_DN'<14>:'(0,0,0,0,0,0,0,0,0,0,0,0,0,0,CH17,0,0,0,0,0,0,0,0,0,0,0,0,~
0,0,0)';IN;
    'UPI2_RX_DN'<13>:'(0,0,0,0,0,0,0,0,0,0,0,0,0,0,CJ18,0,0,0,0,0,0,0,0,0,0,0,0,~
0,0,0)';IN;
    'UPI2_RX_DN'<12>:'(0,0,0,0,0,0,0,0,0,0,0,0,0,0,CL16,0,0,0,0,0,0,0,0,0,0,0,0,~
0,0,0)';IN;
    'UPI2_RX_DN'<11>:'(0,0,0,0,0,0,0,0,0,0,0,0,0,0,CP21,0,0,0,0,0,0,0,0,0,0,0,0,~
0,0,0)';IN;
    'UPI2_RX_DN'<10>:'(0,0,0,0,0,0,0,0,0,0,0,0,0,0,CN20,0,0,0,0,0,0,0,0,0,0,0,0,~
0,0,0)';IN;
    'UPI2_RX_DN'<9>:'(0,0,0,0,0,0,0,0,0,0,0,0,0,0,CR18,0,0,0,0,0,0,0,0,0,0,0,0,0~
,0,0)';IN;
    'UPI2_RX_DN'<8>:'(0,0,0,0,0,0,0,0,0,0,0,0,0,0,CT21,0,0,0,0,0,0,0,0,0,0,0,0,0~
,0,0)';IN;
    'UPI2_RX_DN'<7>:'(0,0,0,0,0,0,0,0,0,0,0,0,0,0,CV19,0,0,0,0,0,0,0,0,0,0,0,0,0~
,0,0)';IN;
    'UPI2_RX_DN'<6>:'(0,0,0,0,0,0,0,0,0,0,0,0,0,0,CW20,0,0,0,0,0,0,0,0,0,0,0,0,0~
,0,0)';IN;
    'UPI2_RX_DN'<5>:'(0,0,0,0,0,0,0,0,0,0,0,0,0,0,DA20,0,0,0,0,0,0,0,0,0,0,0,0,0~
,0,0)';IN;
    'UPI2_RX_DN'<4>:'(0,0,0,0,0,0,0,0,0,0,0,0,0,0,DD19,0,0,0,0,0,0,0,0,0,0,0,0,0~
,0,0)';IN;
    'UPI2_RX_DN'<3>:'(0,0,0,0,0,0,0,0,0,0,0,0,0,0,DB21,0,0,0,0,0,0,0,0,0,0,0,0,0~
,0,0)';IN;
    'UPI2_RX_DN'<2>:'(0,0,0,0,0,0,0,0,0,0,0,0,0,0,DC22,0,0,0,0,0,0,0,0,0,0,0,0,0~
,0,0)';IN;
    'UPI2_RX_DN'<1>:'(0,0,0,0,0,0,0,0,0,0,0,0,0,0,DE22,0,0,0,0,0,0,0,0,0,0,0,0,0~
,0,0)';IN;
    'UPI2_RX_DN'<0>:'(0,0,0,0,0,0,0,0,0,0,0,0,0,0,DF23,0,0,0,0,0,0,0,0,0,0,0,0,0~
,0,0)';IN;
    'UPI2_RX_DP'<19>:'(0,0,0,0,0,0,0,0,0,0,0,0,0,0,CA16,0,0,0,0,0,0,0,0,0,0,0,0,~
0,0,0)';IN;
    'UPI2_RX_DP'<18>:'(0,0,0,0,0,0,0,0,0,0,0,0,0,0,BY15,0,0,0,0,0,0,0,0,0,0,0,0,~
0,0,0)';IN;
    'UPI2_RX_DP'<17>:'(0,0,0,0,0,0,0,0,0,0,0,0,0,0,CD17,0,0,0,0,0,0,0,0,0,0,0,0,~
0,0,0)';IN;
    'UPI2_RX_DP'<16>:'(0,0,0,0,0,0,0,0,0,0,0,0,0,0,CC14,0,0,0,0,0,0,0,0,0,0,0,0,~
0,0,0)';IN;
    'UPI2_RX_DP'<15>:'(0,0,0,0,0,0,0,0,0,0,0,0,0,0,CF15,0,0,0,0,0,0,0,0,0,0,0,0,~
0,0,0)';IN;
    'UPI2_RX_DP'<14>:'(0,0,0,0,0,0,0,0,0,0,0,0,0,0,CG16,0,0,0,0,0,0,0,0,0,0,0,0,~
0,0,0)';IN;
    'UPI2_RX_DP'<13>:'(0,0,0,0,0,0,0,0,0,0,0,0,0,0,CK17,0,0,0,0,0,0,0,0,0,0,0,0,~
0,0,0)';IN;
    'UPI2_RX_DP'<12>:'(0,0,0,0,0,0,0,0,0,0,0,0,0,0,CJ16,0,0,0,0,0,0,0,0,0,0,0,0,~
0,0,0)';IN;
    'UPI2_RX_DP'<11>:'(0,0,0,0,0,0,0,0,0,0,0,0,0,0,CM21,0,0,0,0,0,0,0,0,0,0,0,0,~
0,0,0)';IN;
    'UPI2_RX_DP'<10>:'(0,0,0,0,0,0,0,0,0,0,0,0,0,0,CP19,0,0,0,0,0,0,0,0,0,0,0,0,~
0,0,0)';IN;
    'UPI2_RX_DP'<9>:'(0,0,0,0,0,0,0,0,0,0,0,0,0,0,CN18,0,0,0,0,0,0,0,0,0,0,0,0,0~
,0,0)';IN;
    'UPI2_RX_DP'<8>:'(0,0,0,0,0,0,0,0,0,0,0,0,0,0,CR20,0,0,0,0,0,0,0,0,0,0,0,0,0~
,0,0)';IN;
    'UPI2_RX_DP'<7>:'(0,0,0,0,0,0,0,0,0,0,0,0,0,0,CW18,0,0,0,0,0,0,0,0,0,0,0,0,0~
,0,0)';IN;
    'UPI2_RX_DP'<6>:'(0,0,0,0,0,0,0,0,0,0,0,0,0,0,CU20,0,0,0,0,0,0,0,0,0,0,0,0,0~
,0,0)';IN;
    'UPI2_RX_DP'<5>:'(0,0,0,0,0,0,0,0,0,0,0,0,0,0,CY19,0,0,0,0,0,0,0,0,0,0,0,0,0~
,0,0)';IN;
    'UPI2_RX_DP'<4>:'(0,0,0,0,0,0,0,0,0,0,0,0,0,0,DB19,0,0,0,0,0,0,0,0,0,0,0,0,0~
,0,0)';IN;
    'UPI2_RX_DP'<3>:'(0,0,0,0,0,0,0,0,0,0,0,0,0,0,DC20,0,0,0,0,0,0,0,0,0,0,0,0,0~
,0,0)';IN;
    'UPI2_RX_DP'<2>:'(0,0,0,0,0,0,0,0,0,0,0,0,0,0,DA22,0,0,0,0,0,0,0,0,0,0,0,0,0~
,0,0)';IN;
    'UPI2_RX_DP'<1>:'(0,0,0,0,0,0,0,0,0,0,0,0,0,0,DD21,0,0,0,0,0,0,0,0,0,0,0,0,0~
,0,0)';IN;
    'UPI2_RX_DP'<0>:'(0,0,0,0,0,0,0,0,0,0,0,0,0,0,DG22,0,0,0,0,0,0,0,0,0,0,0,0,0~
,0,0)';IN;
    'UPI2_TX_DN'<19>:'(0,0,0,0,0,0,0,0,0,0,0,0,0,0,CC12,0,0,0,0,0,0,0,0,0,0,0,0,~
0,0,0)';OUT;
    'UPI2_TX_DN'<18>:'(0,0,0,0,0,0,0,0,0,0,0,0,0,0,CC10,0,0,0,0,0,0,0,0,0,0,0,0,~
0,0,0)';OUT;
    'UPI2_TX_DN'<17>:'(0,0,0,0,0,0,0,0,0,0,0,0,0,0,CE12,0,0,0,0,0,0,0,0,0,0,0,0,~
0,0,0)';OUT;
    'UPI2_TX_DN'<16>:'(0,0,0,0,0,0,0,0,0,0,0,0,0,0,CH11,0,0,0,0,0,0,0,0,0,0,0,0,~
0,0,0)';OUT;
    'UPI2_TX_DN'<15>:'(0,0,0,0,0,0,0,0,0,0,0,0,0,0,CF13,0,0,0,0,0,0,0,0,0,0,0,0,~
0,0,0)';OUT;
    'UPI2_TX_DN'<14>:'(0,0,0,0,0,0,0,0,0,0,0,0,0,0,CJ14,0,0,0,0,0,0,0,0,0,0,0,0,~
0,0,0)';OUT;
    'UPI2_TX_DN'<13>:'(0,0,0,0,0,0,0,0,0,0,0,0,0,0,CM13,0,0,0,0,0,0,0,0,0,0,0,0,~
0,0,0)';OUT;
    'UPI2_TX_DN'<12>:'(0,0,0,0,0,0,0,0,0,0,0,0,0,0,CU14,0,0,0,0,0,0,0,0,0,0,0,0,~
0,0,0)';OUT;
    'UPI2_TX_DN'<11>:'(0,0,0,0,0,0,0,0,0,0,0,0,0,0,CW14,0,0,0,0,0,0,0,0,0,0,0,0,~
0,0,0)';OUT;
    'UPI2_TX_DN'<10>:'(0,0,0,0,0,0,0,0,0,0,0,0,0,0,DA16,0,0,0,0,0,0,0,0,0,0,0,0,~
0,0,0)';OUT;
    'UPI2_TX_DN'<9>:'(0,0,0,0,0,0,0,0,0,0,0,0,0,0,DC16,0,0,0,0,0,0,0,0,0,0,0,0,0~
,0,0)';OUT;
    'UPI2_TX_DN'<8>:'(0,0,0,0,0,0,0,0,0,0,0,0,0,0,DF15,0,0,0,0,0,0,0,0,0,0,0,0,0~
,0,0)';OUT;
    'UPI2_TX_DN'<7>:'(0,0,0,0,0,0,0,0,0,0,0,0,0,0,DD17,0,0,0,0,0,0,0,0,0,0,0,0,0~
,0,0)';OUT;
    'UPI2_TX_DN'<6>:'(0,0,0,0,0,0,0,0,0,0,0,0,0,0,DG18,0,0,0,0,0,0,0,0,0,0,0,0,0~
,0,0)';OUT;
    'UPI2_TX_DN'<5>:'(0,0,0,0,0,0,0,0,0,0,0,0,0,0,DK17,0,0,0,0,0,0,0,0,0,0,0,0,0~
,0,0)';OUT;
    'UPI2_TX_DN'<4>:'(0,0,0,0,0,0,0,0,0,0,0,0,0,0,DH19,0,0,0,0,0,0,0,0,0,0,0,0,0~
,0,0)';OUT;
    'UPI2_TX_DN'<3>:'(0,0,0,0,0,0,0,0,0,0,0,0,0,0,DG20,0,0,0,0,0,0,0,0,0,0,0,0,0~
,0,0)';OUT;
    'UPI2_TX_DN'<2>:'(0,0,0,0,0,0,0,0,0,0,0,0,0,0,DL20,0,0,0,0,0,0,0,0,0,0,0,0,0~
,0,0)';OUT;
    'UPI2_TX_DN'<1>:'(0,0,0,0,0,0,0,0,0,0,0,0,0,0,DM21,0,0,0,0,0,0,0,0,0,0,0,0,0~
,0,0)';OUT;
    'UPI2_TX_DN'<0>:'(0,0,0,0,0,0,0,0,0,0,0,0,0,0,DT21,0,0,0,0,0,0,0,0,0,0,0,0,0~
,0,0)';OUT;
    'UPI2_TX_DP'<19>:'(0,0,0,0,0,0,0,0,0,0,0,0,0,0,CA12,0,0,0,0,0,0,0,0,0,0,0,0,~
0,0,0)';OUT;
    'UPI2_TX_DP'<18>:'(0,0,0,0,0,0,0,0,0,0,0,0,0,0,CB11,0,0,0,0,0,0,0,0,0,0,0,0,~
0,0,0)';OUT;
    'UPI2_TX_DP'<17>:'(0,0,0,0,0,0,0,0,0,0,0,0,0,0,CD11,0,0,0,0,0,0,0,0,0,0,0,0,~
0,0,0)';OUT;
    'UPI2_TX_DP'<16>:'(0,0,0,0,0,0,0,0,0,0,0,0,0,0,CF11,0,0,0,0,0,0,0,0,0,0,0,0,~
0,0,0)';OUT;
    'UPI2_TX_DP'<15>:'(0,0,0,0,0,0,0,0,0,0,0,0,0,0,CG12,0,0,0,0,0,0,0,0,0,0,0,0,~
0,0,0)';OUT;
    'UPI2_TX_DP'<14>:'(0,0,0,0,0,0,0,0,0,0,0,0,0,0,CH13,0,0,0,0,0,0,0,0,0,0,0,0,~
0,0,0)';OUT;
    'UPI2_TX_DP'<13>:'(0,0,0,0,0,0,0,0,0,0,0,0,0,0,CK13,0,0,0,0,0,0,0,0,0,0,0,0,~
0,0,0)';OUT;
    'UPI2_TX_DP'<12>:'(0,0,0,0,0,0,0,0,0,0,0,0,0,0,CR14,0,0,0,0,0,0,0,0,0,0,0,0,~
0,0,0)';OUT;
    'UPI2_TX_DP'<11>:'(0,0,0,0,0,0,0,0,0,0,0,0,0,0,CV13,0,0,0,0,0,0,0,0,0,0,0,0,~
0,0,0)';OUT;
    'UPI2_TX_DP'<10>:'(0,0,0,0,0,0,0,0,0,0,0,0,0,0,CW16,0,0,0,0,0,0,0,0,0,0,0,0,~
0,0,0)';OUT;
    'UPI2_TX_DP'<9>:'(0,0,0,0,0,0,0,0,0,0,0,0,0,0,DB15,0,0,0,0,0,0,0,0,0,0,0,0,0~
,0,0)';OUT;
    'UPI2_TX_DP'<8>:'(0,0,0,0,0,0,0,0,0,0,0,0,0,0,DD15,0,0,0,0,0,0,0,0,0,0,0,0,0~
,0,0)';OUT;
    'UPI2_TX_DP'<7>:'(0,0,0,0,0,0,0,0,0,0,0,0,0,0,DE16,0,0,0,0,0,0,0,0,0,0,0,0,0~
,0,0)';OUT;
    'UPI2_TX_DP'<6>:'(0,0,0,0,0,0,0,0,0,0,0,0,0,0,DF17,0,0,0,0,0,0,0,0,0,0,0,0,0~
,0,0)';OUT;
    'UPI2_TX_DP'<5>:'(0,0,0,0,0,0,0,0,0,0,0,0,0,0,DH17,0,0,0,0,0,0,0,0,0,0,0,0,0~
,0,0)';OUT;
    'UPI2_TX_DP'<4>:'(0,0,0,0,0,0,0,0,0,0,0,0,0,0,DJ18,0,0,0,0,0,0,0,0,0,0,0,0,0~
,0,0)';OUT;
    'UPI2_TX_DP'<3>:'(0,0,0,0,0,0,0,0,0,0,0,0,0,0,DJ20,0,0,0,0,0,0,0,0,0,0,0,0,0~
,0,0)';OUT;
    'UPI2_TX_DP'<2>:'(0,0,0,0,0,0,0,0,0,0,0,0,0,0,DK19,0,0,0,0,0,0,0,0,0,0,0,0,0~
,0,0)';OUT;
    'UPI2_TX_DP'<1>:'(0,0,0,0,0,0,0,0,0,0,0,0,0,0,DN20,0,0,0,0,0,0,0,0,0,0,0,0,0~
,0,0)';OUT;
    'UPI2_TX_DP'<0>:'(0,0,0,0,0,0,0,0,0,0,0,0,0,0,DP21,0,0,0,0,0,0,0,0,0,0,0,0,0~
,0,0)';OUT;
    'VCC33':'(0,0,0,0,0,0,0,0,0,0,0,0,0,0,0,0,0,0,0,0,CY55,0,0,0,0,0,0,0,0,0)';$~
S;
    'VCCD012'<51>:'(0,0,0,0,0,0,0,0,0,0,0,0,0,0,0,0,0,0,0,B47,0,0,0,0,0,0,0,0,0,~
0)';
    'VCCD012'<50>:'(0,0,0,0,0,0,0,0,0,0,0,0,0,0,0,0,0,0,0,C46,0,0,0,0,0,0,0,0,0,~
0)';
    'VCCD012'<49>:'(0,0,0,0,0,0,0,0,0,0,0,0,0,0,0,0,0,0,0,D45,0,0,0,0,0,0,0,0,0,~
0)';
    'VCCD012'<48>:'(0,0,0,0,0,0,0,0,0,0,0,0,0,0,0,0,0,0,0,AF63,0,0,0,0,0,0,0,0,0~
,0)';
    'VCCD012'<47>:'(0,0,0,0,0,0,0,0,0,0,0,0,0,0,0,0,0,0,0,AF61,0,0,0,0,0,0,0,0,0~
,0)';
    'VCCD012'<46>:'(0,0,0,0,0,0,0,0,0,0,0,0,0,0,0,0,0,0,0,AF59,0,0,0,0,0,0,0,0,0~
,0)';
    'VCCD012'<45>:'(0,0,0,0,0,0,0,0,0,0,0,0,0,0,0,0,0,0,0,AF57,0,0,0,0,0,0,0,0,0~
,0)';
    'VCCD012'<44>:'(0,0,0,0,0,0,0,0,0,0,0,0,0,0,0,0,0,0,0,AF55,0,0,0,0,0,0,0,0,0~
,0)';
    'VCCD012'<43>:'(0,0,0,0,0,0,0,0,0,0,0,0,0,0,0,0,0,0,0,AD45,0,0,0,0,0,0,0,0,0~
,0)';
    'VCCD012'<42>:'(0,0,0,0,0,0,0,0,0,0,0,0,0,0,0,0,0,0,0,Y63,0,0,0,0,0,0,0,0,0,~
0)';
    'VCCD012'<41>:'(0,0,0,0,0,0,0,0,0,0,0,0,0,0,0,0,0,0,0,Y61,0,0,0,0,0,0,0,0,0,~
0)';
    'VCCD012'<40>:'(0,0,0,0,0,0,0,0,0,0,0,0,0,0,0,0,0,0,0,Y59,0,0,0,0,0,0,0,0,0,~
0)';
    'VCCD012'<39>:'(0,0,0,0,0,0,0,0,0,0,0,0,0,0,0,0,0,0,0,Y57,0,0,0,0,0,0,0,0,0,~
0)';
    'VCCD012'<38>:'(0,0,0,0,0,0,0,0,0,0,0,0,0,0,0,0,0,0,0,Y55,0,0,0,0,0,0,0,0,0,~
0)';
    'VCCD012'<37>:'(0,0,0,0,0,0,0,0,0,0,0,0,0,0,0,0,0,0,0,Y53,0,0,0,0,0,0,0,0,0,~
0)';
    'VCCD012'<36>:'(0,0,0,0,0,0,0,0,0,0,0,0,0,0,0,0,0,0,0,Y51,0,0,0,0,0,0,0,0,0,~
0)';
    'VCCD012'<35>:'(0,0,0,0,0,0,0,0,0,0,0,0,0,0,0,0,0,0,0,Y49,0,0,0,0,0,0,0,0,0,~
0)';
    'VCCD012'<34>:'(0,0,0,0,0,0,0,0,0,0,0,0,0,0,0,0,0,0,0,Y47,0,0,0,0,0,0,0,0,0,~
0)';
    'VCCD012'<33>:'(0,0,0,0,0,0,0,0,0,0,0,0,0,0,0,0,0,0,0,Y45,0,0,0,0,0,0,0,0,0,~
0)';
    'VCCD012'<32>:'(0,0,0,0,0,0,0,0,0,0,0,0,0,0,0,0,0,0,0,W64,0,0,0,0,0,0,0,0,0,~
0)';
    'VCCD012'<31>:'(0,0,0,0,0,0,0,0,0,0,0,0,0,0,0,0,0,0,0,U62,0,0,0,0,0,0,0,0,0,~
0)';
    'VCCD012'<30>:'(0,0,0,0,0,0,0,0,0,0,0,0,0,0,0,0,0,0,0,U60,0,0,0,0,0,0,0,0,0,~
0)';
    'VCCD012'<29>:'(0,0,0,0,0,0,0,0,0,0,0,0,0,0,0,0,0,0,0,U58,0,0,0,0,0,0,0,0,0,~
0)';
    'VCCD012'<28>:'(0,0,0,0,0,0,0,0,0,0,0,0,0,0,0,0,0,0,0,U56,0,0,0,0,0,0,0,0,0,~
0)';
    'VCCD012'<27>:'(0,0,0,0,0,0,0,0,0,0,0,0,0,0,0,0,0,0,0,U54,0,0,0,0,0,0,0,0,0,~
0)';
    'VCCD012'<26>:'(0,0,0,0,0,0,0,0,0,0,0,0,0,0,0,0,0,0,0,U52,0,0,0,0,0,0,0,0,0,~
0)';
    'VCCD012'<25>:'(0,0,0,0,0,0,0,0,0,0,0,0,0,0,0,0,0,0,0,U50,0,0,0,0,0,0,0,0,0,~
0)';
    'VCCD012'<24>:'(0,0,0,0,0,0,0,0,0,0,0,0,0,0,0,0,0,0,0,U48,0,0,0,0,0,0,0,0,0,~
0)';
    'VCCD012'<23>:'(0,0,0,0,0,0,0,0,0,0,0,0,0,0,0,0,0,0,0,U46,0,0,0,0,0,0,0,0,0,~
0)';
    'VCCD012'<22>:'(0,0,0,0,0,0,0,0,0,0,0,0,0,0,0,0,0,0,0,N64,0,0,0,0,0,0,0,0,0,~
0)';
    'VCCD012'<21>:'(0,0,0,0,0,0,0,0,0,0,0,0,0,0,0,0,0,0,0,L62,0,0,0,0,0,0,0,0,0,~
0)';
    'VCCD012'<20>:'(0,0,0,0,0,0,0,0,0,0,0,0,0,0,0,0,0,0,0,L60,0,0,0,0,0,0,0,0,0,~
0)';
    'VCCD012'<19>:'(0,0,0,0,0,0,0,0,0,0,0,0,0,0,0,0,0,0,0,L58,0,0,0,0,0,0,0,0,0,~
0)';
    'VCCD012'<18>:'(0,0,0,0,0,0,0,0,0,0,0,0,0,0,0,0,0,0,0,L56,0,0,0,0,0,0,0,0,0,~
0)';
    'VCCD012'<17>:'(0,0,0,0,0,0,0,0,0,0,0,0,0,0,0,0,0,0,0,L54,0,0,0,0,0,0,0,0,0,~
0)';
    'VCCD012'<16>:'(0,0,0,0,0,0,0,0,0,0,0,0,0,0,0,0,0,0,0,L52,0,0,0,0,0,0,0,0,0,~
0)';
    'VCCD012'<15>:'(0,0,0,0,0,0,0,0,0,0,0,0,0,0,0,0,0,0,0,L50,0,0,0,0,0,0,0,0,0,~
0)';
    'VCCD012'<14>:'(0,0,0,0,0,0,0,0,0,0,0,0,0,0,0,0,0,0,0,L48,0,0,0,0,0,0,0,0,0,~
0)';
    'VCCD012'<13>:'(0,0,0,0,0,0,0,0,0,0,0,0,0,0,0,0,0,0,0,L46,0,0,0,0,0,0,0,0,0,~
0)';
    'VCCD012'<12>:'(0,0,0,0,0,0,0,0,0,0,0,0,0,0,0,0,0,0,0,E64,0,0,0,0,0,0,0,0,0,~
0)';
    'VCCD012'<11>:'(0,0,0,0,0,0,0,0,0,0,0,0,0,0,0,0,0,0,0,E62,0,0,0,0,0,0,0,0,0,~
0)';
    'VCCD012'<10>:'(0,0,0,0,0,0,0,0,0,0,0,0,0,0,0,0,0,0,0,E60,0,0,0,0,0,0,0,0,0,~
0)';
    'VCCD012'<9>:'(0,0,0,0,0,0,0,0,0,0,0,0,0,0,0,0,0,0,0,E58,0,0,0,0,0,0,0,0,0,0~
)';
    'VCCD012'<8>:'(0,0,0,0,0,0,0,0,0,0,0,0,0,0,0,0,0,0,0,E56,0,0,0,0,0,0,0,0,0,0~
)';
    'VCCD012'<7>:'(0,0,0,0,0,0,0,0,0,0,0,0,0,0,0,0,0,0,0,E54,0,0,0,0,0,0,0,0,0,0~
)';
    'VCCD012'<6>:'(0,0,0,0,0,0,0,0,0,0,0,0,0,0,0,0,0,0,0,E52,0,0,0,0,0,0,0,0,0,0~
)';
    'VCCD012'<5>:'(0,0,0,0,0,0,0,0,0,0,0,0,0,0,0,0,0,0,0,E50,0,0,0,0,0,0,0,0,0,0~
)';
    'VCCD012'<4>:'(0,0,0,0,0,0,0,0,0,0,0,0,0,0,0,0,0,0,0,E48,0,0,0,0,0,0,0,0,0,0~
)';
    'VCCD012'<3>:'(0,0,0,0,0,0,0,0,0,0,0,0,0,0,0,0,0,0,0,E46,0,0,0,0,0,0,0,0,0,0~
)';
    'VCCD012'<2>:'(0,0,0,0,0,0,0,0,0,0,0,0,0,0,0,0,0,0,0,B59,0,0,0,0,0,0,0,0,0,0~
)';
    'VCCD012'<1>:'(0,0,0,0,0,0,0,0,0,0,0,0,0,0,0,0,0,0,0,B53,0,0,0,0,0,0,0,0,0,0~
)';
    'VCCD012'<0>:'(0,0,0,0,0,0,0,0,0,0,0,0,0,0,0,0,0,0,0,B49,0,0,0,0,0,0,0,0,0,0~
)';
    'VCCD345'<50>:'(0,0,0,0,0,0,0,0,0,0,0,0,0,0,0,0,0,0,0,EE44,0,0,0,0,0,0,0,0,0~
,0)';
    'VCCD345'<49>:'(0,0,0,0,0,0,0,0,0,0,0,0,0,0,0,0,0,0,0,EF45,0,0,0,0,0,0,0,0,0~
,0)';
    'VCCD345'<48>:'(0,0,0,0,0,0,0,0,0,0,0,0,0,0,0,0,0,0,0,DB53,0,0,0,0,0,0,0,0,0~
,0)';
    'VCCD345'<47>:'(0,0,0,0,0,0,0,0,0,0,0,0,0,0,0,0,0,0,0,DB55,0,0,0,0,0,0,0,0,0~
,0)';
    'VCCD345'<46>:'(0,0,0,0,0,0,0,0,0,0,0,0,0,0,0,0,0,0,0,DB57,0,0,0,0,0,0,0,0,0~
,0)';
    'VCCD345'<45>:'(0,0,0,0,0,0,0,0,0,0,0,0,0,0,0,0,0,0,0,DB59,0,0,0,0,0,0,0,0,0~
,0)';
    'VCCD345'<44>:'(0,0,0,0,0,0,0,0,0,0,0,0,0,0,0,0,0,0,0,DB61,0,0,0,0,0,0,0,0,0~
,0)';
    'VCCD345'<43>:'(0,0,0,0,0,0,0,0,0,0,0,0,0,0,0,0,0,0,0,DB63,0,0,0,0,0,0,0,0,0~
,0)';
    'VCCD345'<42>:'(0,0,0,0,0,0,0,0,0,0,0,0,0,0,0,0,0,0,0,DD45,0,0,0,0,0,0,0,0,0~
,0)';
    'VCCD345'<41>:'(0,0,0,0,0,0,0,0,0,0,0,0,0,0,0,0,0,0,0,DH45,0,0,0,0,0,0,0,0,0~
,0)';
    'VCCD345'<40>:'(0,0,0,0,0,0,0,0,0,0,0,0,0,0,0,0,0,0,0,DH47,0,0,0,0,0,0,0,0,0~
,0)';
    'VCCD345'<39>:'(0,0,0,0,0,0,0,0,0,0,0,0,0,0,0,0,0,0,0,DH49,0,0,0,0,0,0,0,0,0~
,0)';
    'VCCD345'<38>:'(0,0,0,0,0,0,0,0,0,0,0,0,0,0,0,0,0,0,0,DH51,0,0,0,0,0,0,0,0,0~
,0)';
    'VCCD345'<37>:'(0,0,0,0,0,0,0,0,0,0,0,0,0,0,0,0,0,0,0,DH53,0,0,0,0,0,0,0,0,0~
,0)';
    'VCCD345'<36>:'(0,0,0,0,0,0,0,0,0,0,0,0,0,0,0,0,0,0,0,DH55,0,0,0,0,0,0,0,0,0~
,0)';
    'VCCD345'<35>:'(0,0,0,0,0,0,0,0,0,0,0,0,0,0,0,0,0,0,0,DH57,0,0,0,0,0,0,0,0,0~
,0)';
    'VCCD345'<34>:'(0,0,0,0,0,0,0,0,0,0,0,0,0,0,0,0,0,0,0,DH59,0,0,0,0,0,0,0,0,0~
,0)';
    'VCCD345'<33>:'(0,0,0,0,0,0,0,0,0,0,0,0,0,0,0,0,0,0,0,DH61,0,0,0,0,0,0,0,0,0~
,0)';
    'VCCD345'<32>:'(0,0,0,0,0,0,0,0,0,0,0,0,0,0,0,0,0,0,0,DH63,0,0,0,0,0,0,0,0,0~
,0)';
    'VCCD345'<31>:'(0,0,0,0,0,0,0,0,0,0,0,0,0,0,0,0,0,0,0,DJ64,0,0,0,0,0,0,0,0,0~
,0)';
    'VCCD345'<30>:'(0,0,0,0,0,0,0,0,0,0,0,0,0,0,0,0,0,0,0,DL46,0,0,0,0,0,0,0,0,0~
,0)';
    'VCCD345'<29>:'(0,0,0,0,0,0,0,0,0,0,0,0,0,0,0,0,0,0,0,DL48,0,0,0,0,0,0,0,0,0~
,0)';
    'VCCD345'<28>:'(0,0,0,0,0,0,0,0,0,0,0,0,0,0,0,0,0,0,0,DL50,0,0,0,0,0,0,0,0,0~
,0)';
    'VCCD345'<27>:'(0,0,0,0,0,0,0,0,0,0,0,0,0,0,0,0,0,0,0,DL52,0,0,0,0,0,0,0,0,0~
,0)';
    'VCCD345'<26>:'(0,0,0,0,0,0,0,0,0,0,0,0,0,0,0,0,0,0,0,DL54,0,0,0,0,0,0,0,0,0~
,0)';
    'VCCD345'<25>:'(0,0,0,0,0,0,0,0,0,0,0,0,0,0,0,0,0,0,0,DL56,0,0,0,0,0,0,0,0,0~
,0)';
    'VCCD345'<24>:'(0,0,0,0,0,0,0,0,0,0,0,0,0,0,0,0,0,0,0,DL58,0,0,0,0,0,0,0,0,0~
,0)';
    'VCCD345'<23>:'(0,0,0,0,0,0,0,0,0,0,0,0,0,0,0,0,0,0,0,DL60,0,0,0,0,0,0,0,0,0~
,0)';
    'VCCD345'<22>:'(0,0,0,0,0,0,0,0,0,0,0,0,0,0,0,0,0,0,0,DL62,0,0,0,0,0,0,0,0,0~
,0)';
    'VCCD345'<21>:'(0,0,0,0,0,0,0,0,0,0,0,0,0,0,0,0,0,0,0,DU46,0,0,0,0,0,0,0,0,0~
,0)';
    'VCCD345'<20>:'(0,0,0,0,0,0,0,0,0,0,0,0,0,0,0,0,0,0,0,DU48,0,0,0,0,0,0,0,0,0~
,0)';
    'VCCD345'<19>:'(0,0,0,0,0,0,0,0,0,0,0,0,0,0,0,0,0,0,0,DU50,0,0,0,0,0,0,0,0,0~
,0)';
    'VCCD345'<18>:'(0,0,0,0,0,0,0,0,0,0,0,0,0,0,0,0,0,0,0,DU52,0,0,0,0,0,0,0,0,0~
,0)';
    'VCCD345'<17>:'(0,0,0,0,0,0,0,0,0,0,0,0,0,0,0,0,0,0,0,DU54,0,0,0,0,0,0,0,0,0~
,0)';
    'VCCD345'<16>:'(0,0,0,0,0,0,0,0,0,0,0,0,0,0,0,0,0,0,0,DU56,0,0,0,0,0,0,0,0,0~
,0)';
    'VCCD345'<15>:'(0,0,0,0,0,0,0,0,0,0,0,0,0,0,0,0,0,0,0,DU58,0,0,0,0,0,0,0,0,0~
,0)';
    'VCCD345'<14>:'(0,0,0,0,0,0,0,0,0,0,0,0,0,0,0,0,0,0,0,DU60,0,0,0,0,0,0,0,0,0~
,0)';
    'VCCD345'<13>:'(0,0,0,0,0,0,0,0,0,0,0,0,0,0,0,0,0,0,0,DU62,0,0,0,0,0,0,0,0,0~
,0)';
    'VCCD345'<12>:'(0,0,0,0,0,0,0,0,0,0,0,0,0,0,0,0,0,0,0,DU64,0,0,0,0,0,0,0,0,0~
,0)';
    'VCCD345'<11>:'(0,0,0,0,0,0,0,0,0,0,0,0,0,0,0,0,0,0,0,EC46,0,0,0,0,0,0,0,0,0~
,0)';
    'VCCD345'<10>:'(0,0,0,0,0,0,0,0,0,0,0,0,0,0,0,0,0,0,0,EC48,0,0,0,0,0,0,0,0,0~
,0)';
    'VCCD345'<9>:'(0,0,0,0,0,0,0,0,0,0,0,0,0,0,0,0,0,0,0,EC50,0,0,0,0,0,0,0,0,0,~
0)';
    'VCCD345'<8>:'(0,0,0,0,0,0,0,0,0,0,0,0,0,0,0,0,0,0,0,EC52,0,0,0,0,0,0,0,0,0,~
0)';
    'VCCD345'<7>:'(0,0,0,0,0,0,0,0,0,0,0,0,0,0,0,0,0,0,0,EC54,0,0,0,0,0,0,0,0,0,~
0)';
    'VCCD345'<6>:'(0,0,0,0,0,0,0,0,0,0,0,0,0,0,0,0,0,0,0,EC56,0,0,0,0,0,0,0,0,0,~
0)';
    'VCCD345'<5>:'(0,0,0,0,0,0,0,0,0,0,0,0,0,0,0,0,0,0,0,EC58,0,0,0,0,0,0,0,0,0,~
0)';
    'VCCD345'<4>:'(0,0,0,0,0,0,0,0,0,0,0,0,0,0,0,0,0,0,0,EC60,0,0,0,0,0,0,0,0,0,~
0)';
    'VCCD345'<3>:'(0,0,0,0,0,0,0,0,0,0,0,0,0,0,0,0,0,0,0,EC62,0,0,0,0,0,0,0,0,0,~
0)';
    'VCCD345'<2>:'(0,0,0,0,0,0,0,0,0,0,0,0,0,0,0,0,0,0,0,EF49,0,0,0,0,0,0,0,0,0,~
0)';
    'VCCD345'<1>:'(0,0,0,0,0,0,0,0,0,0,0,0,0,0,0,0,0,0,0,EF53,0,0,0,0,0,0,0,0,0,~
0)';
    'VCCD345'<0>:'(0,0,0,0,0,0,0,0,0,0,0,0,0,0,0,0,0,0,0,EF59,0,0,0,0,0,0,0,0,0,~
0)';
    'VCCIN'<267>:'(0,0,0,0,0,0,0,0,0,0,0,0,0,0,0,0,0,AF43,0,0,0,0,0,0,0,0,0,0,0,~
0)';
    'VCCIN'<266>:'(0,0,0,0,0,0,0,0,0,0,0,0,0,0,0,0,0,AG38,0,0,0,0,0,0,0,0,0,0,0,~
0)';
    'VCCIN'<265>:'(0,0,0,0,0,0,0,0,0,0,0,0,0,0,0,0,0,AG40,0,0,0,0,0,0,0,0,0,0,0,~
0)';
    'VCCIN'<264>:'(0,0,0,0,0,0,0,0,0,0,0,0,0,0,0,0,0,AG42,0,0,0,0,0,0,0,0,0,0,0,~
0)';
    'VCCIN'<263>:'(0,0,0,0,0,0,0,0,0,0,0,0,0,0,0,0,0,AH37,0,0,0,0,0,0,0,0,0,0,0,~
0)';
    'VCCIN'<262>:'(0,0,0,0,0,0,0,0,0,0,0,0,0,0,0,0,0,AH39,0,0,0,0,0,0,0,0,0,0,0,~
0)';
    'VCCIN'<261>:'(0,0,0,0,0,0,0,0,0,0,0,0,0,0,0,0,0,AH41,0,0,0,0,0,0,0,0,0,0,0,~
0)';
    'VCCIN'<260>:'(0,0,0,0,0,0,0,0,0,0,0,0,0,0,0,0,0,AJ36,0,0,0,0,0,0,0,0,0,0,0,~
0)';
    'VCCIN'<259>:'(0,0,0,0,0,0,0,0,0,0,0,0,0,0,0,0,0,AK35,0,0,0,0,0,0,0,0,0,0,0,~
0)';
    'VCCIN'<258>:'(0,0,0,0,0,0,0,0,0,0,0,0,0,0,0,0,0,AK45,0,0,0,0,0,0,0,0,0,0,0,~
0)';
    'VCCIN'<257>:'(0,0,0,0,0,0,0,0,0,0,0,0,0,0,0,0,0,AK47,0,0,0,0,0,0,0,0,0,0,0,~
0)';
    'VCCIN'<256>:'(0,0,0,0,0,0,0,0,0,0,0,0,0,0,0,0,0,AK49,0,0,0,0,0,0,0,0,0,0,0,~
0)';
    'VCCIN'<255>:'(0,0,0,0,0,0,0,0,0,0,0,0,0,0,0,0,0,AK51,0,0,0,0,0,0,0,0,0,0,0,~
0)';
    'VCCIN'<254>:'(0,0,0,0,0,0,0,0,0,0,0,0,0,0,0,0,0,AK53,0,0,0,0,0,0,0,0,0,0,0,~
0)';
    'VCCIN'<253>:'(0,0,0,0,0,0,0,0,0,0,0,0,0,0,0,0,0,AL34,0,0,0,0,0,0,0,0,0,0,0,~
0)';
    'VCCIN'<252>:'(0,0,0,0,0,0,0,0,0,0,0,0,0,0,0,0,0,AL46,0,0,0,0,0,0,0,0,0,0,0,~
0)';
    'VCCIN'<251>:'(0,0,0,0,0,0,0,0,0,0,0,0,0,0,0,0,0,AL48,0,0,0,0,0,0,0,0,0,0,0,~
0)';
    'VCCIN'<250>:'(0,0,0,0,0,0,0,0,0,0,0,0,0,0,0,0,0,AL50,0,0,0,0,0,0,0,0,0,0,0,~
0)';
    'VCCIN'<249>:'(0,0,0,0,0,0,0,0,0,0,0,0,0,0,0,0,0,AL52,0,0,0,0,0,0,0,0,0,0,0,~
0)';
    'VCCIN'<248>:'(0,0,0,0,0,0,0,0,0,0,0,0,0,0,0,0,0,AL54,0,0,0,0,0,0,0,0,0,0,0,~
0)';
    'VCCIN'<247>:'(0,0,0,0,0,0,0,0,0,0,0,0,0,0,0,0,0,AM33,0,0,0,0,0,0,0,0,0,0,0,~
0)';
    'VCCIN'<246>:'(0,0,0,0,0,0,0,0,0,0,0,0,0,0,0,0,0,AM53,0,0,0,0,0,0,0,0,0,0,0,~
0)';
    'VCCIN'<245>:'(0,0,0,0,0,0,0,0,0,0,0,0,0,0,0,0,0,AM55,0,0,0,0,0,0,0,0,0,0,0,~
0)';
    'VCCIN'<244>:'(0,0,0,0,0,0,0,0,0,0,0,0,0,0,0,0,0,AN32,0,0,0,0,0,0,0,0,0,0,0,~
0)';
    'VCCIN'<243>:'(0,0,0,0,0,0,0,0,0,0,0,0,0,0,0,0,0,AN54,0,0,0,0,0,0,0,0,0,0,0,~
0)';
    'VCCIN'<242>:'(0,0,0,0,0,0,0,0,0,0,0,0,0,0,0,0,0,AN56,0,0,0,0,0,0,0,0,0,0,0,~
0)';
    'VCCIN'<241>:'(0,0,0,0,0,0,0,0,0,0,0,0,0,0,0,0,0,AP55,0,0,0,0,0,0,0,0,0,0,0,~
0)';
    'VCCIN'<240>:'(0,0,0,0,0,0,0,0,0,0,0,0,0,0,0,0,0,AP57,0,0,0,0,0,0,0,0,0,0,0,~
0)';
    'VCCIN'<239>:'(0,0,0,0,0,0,0,0,0,0,0,0,0,0,0,0,0,AR56,0,0,0,0,0,0,0,0,0,0,0,~
0)';
    'VCCIN'<238>:'(0,0,0,0,0,0,0,0,0,0,0,0,0,0,0,0,0,AR58,0,0,0,0,0,0,0,0,0,0,0,~
0)';
    'VCCIN'<237>:'(0,0,0,0,0,0,0,0,0,0,0,0,0,0,0,0,0,AT57,0,0,0,0,0,0,0,0,0,0,0,~
0)';
    'VCCIN'<236>:'(0,0,0,0,0,0,0,0,0,0,0,0,0,0,0,0,0,AT59,0,0,0,0,0,0,0,0,0,0,0,~
0)';
    'VCCIN'<235>:'(0,0,0,0,0,0,0,0,0,0,0,0,0,0,0,0,0,AU58,0,0,0,0,0,0,0,0,0,0,0,~
0)';
    'VCCIN'<234>:'(0,0,0,0,0,0,0,0,0,0,0,0,0,0,0,0,0,AU60,0,0,0,0,0,0,0,0,0,0,0,~
0)';
    'VCCIN'<233>:'(0,0,0,0,0,0,0,0,0,0,0,0,0,0,0,0,0,AV59,0,0,0,0,0,0,0,0,0,0,0,~
0)';
    'VCCIN'<232>:'(0,0,0,0,0,0,0,0,0,0,0,0,0,0,0,0,0,AV61,0,0,0,0,0,0,0,0,0,0,0,~
0)';
    'VCCIN'<231>:'(0,0,0,0,0,0,0,0,0,0,0,0,0,0,0,0,0,AW60,0,0,0,0,0,0,0,0,0,0,0,~
0)';
    'VCCIN'<230>:'(0,0,0,0,0,0,0,0,0,0,0,0,0,0,0,0,0,AY61,0,0,0,0,0,0,0,0,0,0,0,~
0)';
    'VCCIN'<229>:'(0,0,0,0,0,0,0,0,0,0,0,0,0,0,0,0,0,BA60,0,0,0,0,0,0,0,0,0,0,0,~
0)';
    'VCCIN'<228>:'(0,0,0,0,0,0,0,0,0,0,0,0,0,0,0,0,0,BB61,0,0,0,0,0,0,0,0,0,0,0,~
0)';
    'VCCIN'<227>:'(0,0,0,0,0,0,0,0,0,0,0,0,0,0,0,0,0,BB85,0,0,0,0,0,0,0,0,0,0,0,~
0)';
    'VCCIN'<226>:'(0,0,0,0,0,0,0,0,0,0,0,0,0,0,0,0,0,BC60,0,0,0,0,0,0,0,0,0,0,0,~
0)';
    'VCCIN'<225>:'(0,0,0,0,0,0,0,0,0,0,0,0,0,0,0,0,0,BC62,0,0,0,0,0,0,0,0,0,0,0,~
0)';
    'VCCIN'<224>:'(0,0,0,0,0,0,0,0,0,0,0,0,0,0,0,0,0,BC84,0,0,0,0,0,0,0,0,0,0,0,~
0)';
    'VCCIN'<223>:'(0,0,0,0,0,0,0,0,0,0,0,0,0,0,0,0,0,BD61,0,0,0,0,0,0,0,0,0,0,0,~
0)';
    'VCCIN'<222>:'(0,0,0,0,0,0,0,0,0,0,0,0,0,0,0,0,0,BD73,0,0,0,0,0,0,0,0,0,0,0,~
0)';
    'VCCIN'<221>:'(0,0,0,0,0,0,0,0,0,0,0,0,0,0,0,0,0,BD75,0,0,0,0,0,0,0,0,0,0,0,~
0)';
    'VCCIN'<220>:'(0,0,0,0,0,0,0,0,0,0,0,0,0,0,0,0,0,BD77,0,0,0,0,0,0,0,0,0,0,0,~
0)';
    'VCCIN'<219>:'(0,0,0,0,0,0,0,0,0,0,0,0,0,0,0,0,0,BD79,0,0,0,0,0,0,0,0,0,0,0,~
0)';
    'VCCIN'<218>:'(0,0,0,0,0,0,0,0,0,0,0,0,0,0,0,0,0,BD81,0,0,0,0,0,0,0,0,0,0,0,~
0)';
    'VCCIN'<217>:'(0,0,0,0,0,0,0,0,0,0,0,0,0,0,0,0,0,BD83,0,0,0,0,0,0,0,0,0,0,0,~
0)';
    'VCCIN'<216>:'(0,0,0,0,0,0,0,0,0,0,0,0,0,0,0,0,0,BD85,0,0,0,0,0,0,0,0,0,0,0,~
0)';
    'VCCIN'<215>:'(0,0,0,0,0,0,0,0,0,0,0,0,0,0,0,0,0,BE60,0,0,0,0,0,0,0,0,0,0,0,~
0)';
    'VCCIN'<214>:'(0,0,0,0,0,0,0,0,0,0,0,0,0,0,0,0,0,BE62,0,0,0,0,0,0,0,0,0,0,0,~
0)';
    'VCCIN'<213>:'(0,0,0,0,0,0,0,0,0,0,0,0,0,0,0,0,0,BE72,0,0,0,0,0,0,0,0,0,0,0,~
0)';
    'VCCIN'<212>:'(0,0,0,0,0,0,0,0,0,0,0,0,0,0,0,0,0,BE74,0,0,0,0,0,0,0,0,0,0,0,~
0)';
    'VCCIN'<211>:'(0,0,0,0,0,0,0,0,0,0,0,0,0,0,0,0,0,BE76,0,0,0,0,0,0,0,0,0,0,0,~
0)';
    'VCCIN'<210>:'(0,0,0,0,0,0,0,0,0,0,0,0,0,0,0,0,0,BE78,0,0,0,0,0,0,0,0,0,0,0,~
0)';
    'VCCIN'<209>:'(0,0,0,0,0,0,0,0,0,0,0,0,0,0,0,0,0,BE80,0,0,0,0,0,0,0,0,0,0,0,~
0)';
    'VCCIN'<208>:'(0,0,0,0,0,0,0,0,0,0,0,0,0,0,0,0,0,BE82,0,0,0,0,0,0,0,0,0,0,0,~
0)';
    'VCCIN'<207>:'(0,0,0,0,0,0,0,0,0,0,0,0,0,0,0,0,0,BE84,0,0,0,0,0,0,0,0,0,0,0,~
0)';
    'VCCIN'<206>:'(0,0,0,0,0,0,0,0,0,0,0,0,0,0,0,0,0,BF61,0,0,0,0,0,0,0,0,0,0,0,~
0)';
    'VCCIN'<205>:'(0,0,0,0,0,0,0,0,0,0,0,0,0,0,0,0,0,BF73,0,0,0,0,0,0,0,0,0,0,0,~
0)';
    'VCCIN'<204>:'(0,0,0,0,0,0,0,0,0,0,0,0,0,0,0,0,0,BF75,0,0,0,0,0,0,0,0,0,0,0,~
0)';
    'VCCIN'<203>:'(0,0,0,0,0,0,0,0,0,0,0,0,0,0,0,0,0,BF77,0,0,0,0,0,0,0,0,0,0,0,~
0)';
    'VCCIN'<202>:'(0,0,0,0,0,0,0,0,0,0,0,0,0,0,0,0,0,BF79,0,0,0,0,0,0,0,0,0,0,0,~
0)';
    'VCCIN'<201>:'(0,0,0,0,0,0,0,0,0,0,0,0,0,0,0,0,0,BF81,0,0,0,0,0,0,0,0,0,0,0,~
0)';
    'VCCIN'<200>:'(0,0,0,0,0,0,0,0,0,0,0,0,0,0,0,0,0,BF83,0,0,0,0,0,0,0,0,0,0,0,~
0)';
    'VCCIN'<199>:'(0,0,0,0,0,0,0,0,0,0,0,0,0,0,0,0,0,BF85,0,0,0,0,0,0,0,0,0,0,0,~
0)';
    'VCCIN'<198>:'(0,0,0,0,0,0,0,0,0,0,0,0,0,0,0,0,0,BG60,0,0,0,0,0,0,0,0,0,0,0,~
0)';
    'VCCIN'<197>:'(0,0,0,0,0,0,0,0,0,0,0,0,0,0,0,0,0,BG62,0,0,0,0,0,0,0,0,0,0,0,~
0)';
    'VCCIN'<196>:'(0,0,0,0,0,0,0,0,0,0,0,0,0,0,0,0,0,BG64,0,0,0,0,0,0,0,0,0,0,0,~
0)';
    'VCCIN'<195>:'(0,0,0,0,0,0,0,0,0,0,0,0,0,0,0,0,0,BG66,0,0,0,0,0,0,0,0,0,0,0,~
0)';
    'VCCIN'<194>:'(0,0,0,0,0,0,0,0,0,0,0,0,0,0,0,0,0,BG68,0,0,0,0,0,0,0,0,0,0,0,~
0)';
    'VCCIN'<193>:'(0,0,0,0,0,0,0,0,0,0,0,0,0,0,0,0,0,BG70,0,0,0,0,0,0,0,0,0,0,0,~
0)';
    'VCCIN'<192>:'(0,0,0,0,0,0,0,0,0,0,0,0,0,0,0,0,0,BG84,0,0,0,0,0,0,0,0,0,0,0,~
0)';
    'VCCIN'<191>:'(0,0,0,0,0,0,0,0,0,0,0,0,0,0,0,0,0,BH61,0,0,0,0,0,0,0,0,0,0,0,~
0)';
    'VCCIN'<190>:'(0,0,0,0,0,0,0,0,0,0,0,0,0,0,0,0,0,BH63,0,0,0,0,0,0,0,0,0,0,0,~
0)';
    'VCCIN'<189>:'(0,0,0,0,0,0,0,0,0,0,0,0,0,0,0,0,0,BH65,0,0,0,0,0,0,0,0,0,0,0,~
0)';
    'VCCIN'<188>:'(0,0,0,0,0,0,0,0,0,0,0,0,0,0,0,0,0,BH67,0,0,0,0,0,0,0,0,0,0,0,~
0)';
    'VCCIN'<187>:'(0,0,0,0,0,0,0,0,0,0,0,0,0,0,0,0,0,BH69,0,0,0,0,0,0,0,0,0,0,0,~
0)';
    'VCCIN'<186>:'(0,0,0,0,0,0,0,0,0,0,0,0,0,0,0,0,0,BH71,0,0,0,0,0,0,0,0,0,0,0,~
0)';
    'VCCIN'<185>:'(0,0,0,0,0,0,0,0,0,0,0,0,0,0,0,0,0,BH73,0,0,0,0,0,0,0,0,0,0,0,~
0)';
    'VCCIN'<184>:'(0,0,0,0,0,0,0,0,0,0,0,0,0,0,0,0,0,BH75,0,0,0,0,0,0,0,0,0,0,0,~
0)';
    'VCCIN'<183>:'(0,0,0,0,0,0,0,0,0,0,0,0,0,0,0,0,0,BH77,0,0,0,0,0,0,0,0,0,0,0,~
0)';
    'VCCIN'<182>:'(0,0,0,0,0,0,0,0,0,0,0,0,0,0,0,0,0,BH79,0,0,0,0,0,0,0,0,0,0,0,~
0)';
    'VCCIN'<181>:'(0,0,0,0,0,0,0,0,0,0,0,0,0,0,0,0,0,BH81,0,0,0,0,0,0,0,0,0,0,0,~
0)';
    'VCCIN'<180>:'(0,0,0,0,0,0,0,0,0,0,0,0,0,0,0,0,0,BH83,0,0,0,0,0,0,0,0,0,0,0,~
0)';
    'VCCIN'<179>:'(0,0,0,0,0,0,0,0,0,0,0,0,0,0,0,0,0,BJ60,0,0,0,0,0,0,0,0,0,0,0,~
0)';
    'VCCIN'<178>:'(0,0,0,0,0,0,0,0,0,0,0,0,0,0,0,0,0,BJ62,0,0,0,0,0,0,0,0,0,0,0,~
0)';
    'VCCIN'<177>:'(0,0,0,0,0,0,0,0,0,0,0,0,0,0,0,0,0,BJ64,0,0,0,0,0,0,0,0,0,0,0,~
0)';
    'VCCIN'<176>:'(0,0,0,0,0,0,0,0,0,0,0,0,0,0,0,0,0,BJ66,0,0,0,0,0,0,0,0,0,0,0,~
0)';
    'VCCIN'<175>:'(0,0,0,0,0,0,0,0,0,0,0,0,0,0,0,0,0,BJ68,0,0,0,0,0,0,0,0,0,0,0,~
0)';
    'VCCIN'<174>:'(0,0,0,0,0,0,0,0,0,0,0,0,0,0,0,0,0,BJ70,0,0,0,0,0,0,0,0,0,0,0,~
0)';
    'VCCIN'<173>:'(0,0,0,0,0,0,0,0,0,0,0,0,0,0,0,0,0,BJ72,0,0,0,0,0,0,0,0,0,0,0,~
0)';
    'VCCIN'<172>:'(0,0,0,0,0,0,0,0,0,0,0,0,0,0,0,0,0,BJ74,0,0,0,0,0,0,0,0,0,0,0,~
0)';
    'VCCIN'<171>:'(0,0,0,0,0,0,0,0,0,0,0,0,0,0,0,0,0,BJ76,0,0,0,0,0,0,0,0,0,0,0,~
0)';
    'VCCIN'<170>:'(0,0,0,0,0,0,0,0,0,0,0,0,0,0,0,0,0,BJ78,0,0,0,0,0,0,0,0,0,0,0,~
0)';
    'VCCIN'<169>:'(0,0,0,0,0,0,0,0,0,0,0,0,0,0,0,0,0,BJ80,0,0,0,0,0,0,0,0,0,0,0,~
0)';
    'VCCIN'<168>:'(0,0,0,0,0,0,0,0,0,0,0,0,0,0,0,0,0,BJ82,0,0,0,0,0,0,0,0,0,0,0,~
0)';
    'VCCIN'<167>:'(0,0,0,0,0,0,0,0,0,0,0,0,0,0,0,0,0,BJ84,0,0,0,0,0,0,0,0,0,0,0,~
0)';
    'VCCIN'<166>:'(0,0,0,0,0,0,0,0,0,0,0,0,0,0,0,0,0,BK61,0,0,0,0,0,0,0,0,0,0,0,~
0)';
    'VCCIN'<165>:'(0,0,0,0,0,0,0,0,0,0,0,0,0,0,0,0,0,BK63,0,0,0,0,0,0,0,0,0,0,0,~
0)';
    'VCCIN'<164>:'(0,0,0,0,0,0,0,0,0,0,0,0,0,0,0,0,0,BK65,0,0,0,0,0,0,0,0,0,0,0,~
0)';
    'VCCIN'<163>:'(0,0,0,0,0,0,0,0,0,0,0,0,0,0,0,0,0,BK67,0,0,0,0,0,0,0,0,0,0,0,~
0)';
    'VCCIN'<162>:'(0,0,0,0,0,0,0,0,0,0,0,0,0,0,0,0,0,BK69,0,0,0,0,0,0,0,0,0,0,0,~
0)';
    'VCCIN'<161>:'(0,0,0,0,0,0,0,0,0,0,0,0,0,0,0,0,0,BK71,0,0,0,0,0,0,0,0,0,0,0,~
0)';
    'VCCIN'<160>:'(0,0,0,0,0,0,0,0,0,0,0,0,0,0,0,0,0,BK73,0,0,0,0,0,0,0,0,0,0,0,~
0)';
    'VCCIN'<159>:'(0,0,0,0,0,0,0,0,0,0,0,0,0,0,0,0,0,BK75,0,0,0,0,0,0,0,0,0,0,0,~
0)';
    'VCCIN'<158>:'(0,0,0,0,0,0,0,0,0,0,0,0,0,0,0,0,0,BK77,0,0,0,0,0,0,0,0,0,0,0,~
0)';
    'VCCIN'<157>:'(0,0,0,0,0,0,0,0,0,0,0,0,0,0,0,0,0,BK79,0,0,0,0,0,0,0,0,0,0,0,~
0)';
    'VCCIN'<156>:'(0,0,0,0,0,0,0,0,0,0,0,0,0,0,0,0,0,BK81,0,0,0,0,0,0,0,0,0,0,0,~
0)';
    'VCCIN'<155>:'(0,0,0,0,0,0,0,0,0,0,0,0,0,0,0,0,0,BK83,0,0,0,0,0,0,0,0,0,0,0,~
0)';
    'VCCIN'<154>:'(0,0,0,0,0,0,0,0,0,0,0,0,0,0,0,0,0,BL60,0,0,0,0,0,0,0,0,0,0,0,~
0)';
    'VCCIN'<153>:'(0,0,0,0,0,0,0,0,0,0,0,0,0,0,0,0,0,BL62,0,0,0,0,0,0,0,0,0,0,0,~
0)';
    'VCCIN'<152>:'(0,0,0,0,0,0,0,0,0,0,0,0,0,0,0,0,0,BL84,0,0,0,0,0,0,0,0,0,0,0,~
0)';
    'VCCIN'<151>:'(0,0,0,0,0,0,0,0,0,0,0,0,0,0,0,0,0,BM61,0,0,0,0,0,0,0,0,0,0,0,~
0)';
    'VCCIN'<150>:'(0,0,0,0,0,0,0,0,0,0,0,0,0,0,0,0,0,BM63,0,0,0,0,0,0,0,0,0,0,0,~
0)';
    'VCCIN'<149>:'(0,0,0,0,0,0,0,0,0,0,0,0,0,0,0,0,0,BM65,0,0,0,0,0,0,0,0,0,0,0,~
0)';
    'VCCIN'<148>:'(0,0,0,0,0,0,0,0,0,0,0,0,0,0,0,0,0,BM67,0,0,0,0,0,0,0,0,0,0,0,~
0)';
    'VCCIN'<147>:'(0,0,0,0,0,0,0,0,0,0,0,0,0,0,0,0,0,BM69,0,0,0,0,0,0,0,0,0,0,0,~
0)';
    'VCCIN'<146>:'(0,0,0,0,0,0,0,0,0,0,0,0,0,0,0,0,0,BM71,0,0,0,0,0,0,0,0,0,0,0,~
0)';
    'VCCIN'<145>:'(0,0,0,0,0,0,0,0,0,0,0,0,0,0,0,0,0,BM73,0,0,0,0,0,0,0,0,0,0,0,~
0)';
    'VCCIN'<144>:'(0,0,0,0,0,0,0,0,0,0,0,0,0,0,0,0,0,BM75,0,0,0,0,0,0,0,0,0,0,0,~
0)';
    'VCCIN'<143>:'(0,0,0,0,0,0,0,0,0,0,0,0,0,0,0,0,0,BM77,0,0,0,0,0,0,0,0,0,0,0,~
0)';
    'VCCIN'<142>:'(0,0,0,0,0,0,0,0,0,0,0,0,0,0,0,0,0,BM79,0,0,0,0,0,0,0,0,0,0,0,~
0)';
    'VCCIN'<141>:'(0,0,0,0,0,0,0,0,0,0,0,0,0,0,0,0,0,BM81,0,0,0,0,0,0,0,0,0,0,0,~
0)';
    'VCCIN'<140>:'(0,0,0,0,0,0,0,0,0,0,0,0,0,0,0,0,0,BM83,0,0,0,0,0,0,0,0,0,0,0,~
0)';
    'VCCIN'<139>:'(0,0,0,0,0,0,0,0,0,0,0,0,0,0,0,0,0,BN60,0,0,0,0,0,0,0,0,0,0,0,~
0)';
    'VCCIN'<138>:'(0,0,0,0,0,0,0,0,0,0,0,0,0,0,0,0,0,BN62,0,0,0,0,0,0,0,0,0,0,0,~
0)';
    'VCCIN'<137>:'(0,0,0,0,0,0,0,0,0,0,0,0,0,0,0,0,0,BN64,0,0,0,0,0,0,0,0,0,0,0,~
0)';
    'VCCIN'<136>:'(0,0,0,0,0,0,0,0,0,0,0,0,0,0,0,0,0,BN66,0,0,0,0,0,0,0,0,0,0,0,~
0)';
    'VCCIN'<135>:'(0,0,0,0,0,0,0,0,0,0,0,0,0,0,0,0,0,BN68,0,0,0,0,0,0,0,0,0,0,0,~
0)';
    'VCCIN'<134>:'(0,0,0,0,0,0,0,0,0,0,0,0,0,0,0,0,0,BN70,0,0,0,0,0,0,0,0,0,0,0,~
0)';
    'VCCIN'<133>:'(0,0,0,0,0,0,0,0,0,0,0,0,0,0,0,0,0,BN72,0,0,0,0,0,0,0,0,0,0,0,~
0)';
    'VCCIN'<132>:'(0,0,0,0,0,0,0,0,0,0,0,0,0,0,0,0,0,BN74,0,0,0,0,0,0,0,0,0,0,0,~
0)';
    'VCCIN'<131>:'(0,0,0,0,0,0,0,0,0,0,0,0,0,0,0,0,0,BN76,0,0,0,0,0,0,0,0,0,0,0,~
0)';
    'VCCIN'<130>:'(0,0,0,0,0,0,0,0,0,0,0,0,0,0,0,0,0,BN78,0,0,0,0,0,0,0,0,0,0,0,~
0)';
    'VCCIN'<129>:'(0,0,0,0,0,0,0,0,0,0,0,0,0,0,0,0,0,0,BN80,0,0,0,0,0,0,0,0,0,0,~
0)';
    'VCCIN'<128>:'(0,0,0,0,0,0,0,0,0,0,0,0,0,0,0,0,0,0,BN82,0,0,0,0,0,0,0,0,0,0,~
0)';
    'VCCIN'<127>:'(0,0,0,0,0,0,0,0,0,0,0,0,0,0,0,0,0,0,BN84,0,0,0,0,0,0,0,0,0,0,~
0)';
    'VCCIN'<126>:'(0,0,0,0,0,0,0,0,0,0,0,0,0,0,0,0,0,0,BP61,0,0,0,0,0,0,0,0,0,0,~
0)';
    'VCCIN'<125>:'(0,0,0,0,0,0,0,0,0,0,0,0,0,0,0,0,0,0,BP63,0,0,0,0,0,0,0,0,0,0,~
0)';
    'VCCIN'<124>:'(0,0,0,0,0,0,0,0,0,0,0,0,0,0,0,0,0,0,BP65,0,0,0,0,0,0,0,0,0,0,~
0)';
    'VCCIN'<123>:'(0,0,0,0,0,0,0,0,0,0,0,0,0,0,0,0,0,0,BP67,0,0,0,0,0,0,0,0,0,0,~
0)';
    'VCCIN'<122>:'(0,0,0,0,0,0,0,0,0,0,0,0,0,0,0,0,0,0,BP69,0,0,0,0,0,0,0,0,0,0,~
0)';
    'VCCIN'<121>:'(0,0,0,0,0,0,0,0,0,0,0,0,0,0,0,0,0,0,BP71,0,0,0,0,0,0,0,0,0,0,~
0)';
    'VCCIN'<120>:'(0,0,0,0,0,0,0,0,0,0,0,0,0,0,0,0,0,0,BP73,0,0,0,0,0,0,0,0,0,0,~
0)';
    'VCCIN'<119>:'(0,0,0,0,0,0,0,0,0,0,0,0,0,0,0,0,0,0,BP75,0,0,0,0,0,0,0,0,0,0,~
0)';
    'VCCIN'<118>:'(0,0,0,0,0,0,0,0,0,0,0,0,0,0,0,0,0,0,BP77,0,0,0,0,0,0,0,0,0,0,~
0)';
    'VCCIN'<117>:'(0,0,0,0,0,0,0,0,0,0,0,0,0,0,0,0,0,0,BP79,0,0,0,0,0,0,0,0,0,0,~
0)';
    'VCCIN'<116>:'(0,0,0,0,0,0,0,0,0,0,0,0,0,0,0,0,0,0,BP81,0,0,0,0,0,0,0,0,0,0,~
0)';
    'VCCIN'<115>:'(0,0,0,0,0,0,0,0,0,0,0,0,0,0,0,0,0,0,BP83,0,0,0,0,0,0,0,0,0,0,~
0)';
    'VCCIN'<114>:'(0,0,0,0,0,0,0,0,0,0,0,0,0,0,0,0,0,0,BR60,0,0,0,0,0,0,0,0,0,0,~
0)';
    'VCCIN'<113>:'(0,0,0,0,0,0,0,0,0,0,0,0,0,0,0,0,0,0,BR62,0,0,0,0,0,0,0,0,0,0,~
0)';
    'VCCIN'<112>:'(0,0,0,0,0,0,0,0,0,0,0,0,0,0,0,0,0,0,BR84,0,0,0,0,0,0,0,0,0,0,~
0)';
    'VCCIN'<111>:'(0,0,0,0,0,0,0,0,0,0,0,0,0,0,0,0,0,0,BT61,0,0,0,0,0,0,0,0,0,0,~
0)';
    'VCCIN'<110>:'(0,0,0,0,0,0,0,0,0,0,0,0,0,0,0,0,0,0,BT63,0,0,0,0,0,0,0,0,0,0,~
0)';
    'VCCIN'<109>:'(0,0,0,0,0,0,0,0,0,0,0,0,0,0,0,0,0,0,BT65,0,0,0,0,0,0,0,0,0,0,~
0)';
    'VCCIN'<108>:'(0,0,0,0,0,0,0,0,0,0,0,0,0,0,0,0,0,0,BT67,0,0,0,0,0,0,0,0,0,0,~
0)';
    'VCCIN'<107>:'(0,0,0,0,0,0,0,0,0,0,0,0,0,0,0,0,0,0,BT69,0,0,0,0,0,0,0,0,0,0,~
0)';
    'VCCIN'<106>:'(0,0,0,0,0,0,0,0,0,0,0,0,0,0,0,0,0,0,BT71,0,0,0,0,0,0,0,0,0,0,~
0)';
    'VCCIN'<105>:'(0,0,0,0,0,0,0,0,0,0,0,0,0,0,0,0,0,0,BT73,0,0,0,0,0,0,0,0,0,0,~
0)';
    'VCCIN'<104>:'(0,0,0,0,0,0,0,0,0,0,0,0,0,0,0,0,0,0,BT75,0,0,0,0,0,0,0,0,0,0,~
0)';
    'VCCIN'<103>:'(0,0,0,0,0,0,0,0,0,0,0,0,0,0,0,0,0,0,BT77,0,0,0,0,0,0,0,0,0,0,~
0)';
    'VCCIN'<102>:'(0,0,0,0,0,0,0,0,0,0,0,0,0,0,0,0,0,0,BT79,0,0,0,0,0,0,0,0,0,0,~
0)';
    'VCCIN'<101>:'(0,0,0,0,0,0,0,0,0,0,0,0,0,0,0,0,0,0,BT81,0,0,0,0,0,0,0,0,0,0,~
0)';
    'VCCIN'<100>:'(0,0,0,0,0,0,0,0,0,0,0,0,0,0,0,0,0,0,BT83,0,0,0,0,0,0,0,0,0,0,~
0)';
    'VCCIN'<99>:'(0,0,0,0,0,0,0,0,0,0,0,0,0,0,0,0,0,0,BU60,0,0,0,0,0,0,0,0,0,0,0~
)';
    'VCCIN'<98>:'(0,0,0,0,0,0,0,0,0,0,0,0,0,0,0,0,0,0,BU62,0,0,0,0,0,0,0,0,0,0,0~
)';
    'VCCIN'<97>:'(0,0,0,0,0,0,0,0,0,0,0,0,0,0,0,0,0,0,BU64,0,0,0,0,0,0,0,0,0,0,0~
)';
    'VCCIN'<96>:'(0,0,0,0,0,0,0,0,0,0,0,0,0,0,0,0,0,0,BU66,0,0,0,0,0,0,0,0,0,0,0~
)';
    'VCCIN'<95>:'(0,0,0,0,0,0,0,0,0,0,0,0,0,0,0,0,0,0,BU68,0,0,0,0,0,0,0,0,0,0,0~
)';
    'VCCIN'<94>:'(0,0,0,0,0,0,0,0,0,0,0,0,0,0,0,0,0,0,BU70,0,0,0,0,0,0,0,0,0,0,0~
)';
    'VCCIN'<93>:'(0,0,0,0,0,0,0,0,0,0,0,0,0,0,0,0,0,0,BU72,0,0,0,0,0,0,0,0,0,0,0~
)';
    'VCCIN'<92>:'(0,0,0,0,0,0,0,0,0,0,0,0,0,0,0,0,0,0,BU74,0,0,0,0,0,0,0,0,0,0,0~
)';
    'VCCIN'<91>:'(0,0,0,0,0,0,0,0,0,0,0,0,0,0,0,0,0,0,BU76,0,0,0,0,0,0,0,0,0,0,0~
)';
    'VCCIN'<90>:'(0,0,0,0,0,0,0,0,0,0,0,0,0,0,0,0,0,0,BU78,0,0,0,0,0,0,0,0,0,0,0~
)';
    'VCCIN'<89>:'(0,0,0,0,0,0,0,0,0,0,0,0,0,0,0,0,0,0,BU80,0,0,0,0,0,0,0,0,0,0,0~
)';
    'VCCIN'<88>:'(0,0,0,0,0,0,0,0,0,0,0,0,0,0,0,0,0,0,BU82,0,0,0,0,0,0,0,0,0,0,0~
)';
    'VCCIN'<87>:'(0,0,0,0,0,0,0,0,0,0,0,0,0,0,0,0,0,0,BU84,0,0,0,0,0,0,0,0,0,0,0~
)';
    'VCCIN'<86>:'(0,0,0,0,0,0,0,0,0,0,0,0,0,0,0,0,0,0,BV61,0,0,0,0,0,0,0,0,0,0,0~
)';
    'VCCIN'<85>:'(0,0,0,0,0,0,0,0,0,0,0,0,0,0,0,0,0,0,BV63,0,0,0,0,0,0,0,0,0,0,0~
)';
    'VCCIN'<84>:'(0,0,0,0,0,0,0,0,0,0,0,0,0,0,0,0,0,0,BV65,0,0,0,0,0,0,0,0,0,0,0~
)';
    'VCCIN'<83>:'(0,0,0,0,0,0,0,0,0,0,0,0,0,0,0,0,0,0,BV67,0,0,0,0,0,0,0,0,0,0,0~
)';
    'VCCIN'<82>:'(0,0,0,0,0,0,0,0,0,0,0,0,0,0,0,0,0,0,BV69,0,0,0,0,0,0,0,0,0,0,0~
)';
    'VCCIN'<81>:'(0,0,0,0,0,0,0,0,0,0,0,0,0,0,0,0,0,0,BV71,0,0,0,0,0,0,0,0,0,0,0~
)';
    'VCCIN'<80>:'(0,0,0,0,0,0,0,0,0,0,0,0,0,0,0,0,0,0,BV73,0,0,0,0,0,0,0,0,0,0,0~
)';
    'VCCIN'<79>:'(0,0,0,0,0,0,0,0,0,0,0,0,0,0,0,0,0,0,BV75,0,0,0,0,0,0,0,0,0,0,0~
)';
    'VCCIN'<78>:'(0,0,0,0,0,0,0,0,0,0,0,0,0,0,0,0,0,0,BV77,0,0,0,0,0,0,0,0,0,0,0~
)';
    'VCCIN'<77>:'(0,0,0,0,0,0,0,0,0,0,0,0,0,0,0,0,0,0,BV79,0,0,0,0,0,0,0,0,0,0,0~
)';
    'VCCIN'<76>:'(0,0,0,0,0,0,0,0,0,0,0,0,0,0,0,0,0,0,BV81,0,0,0,0,0,0,0,0,0,0,0~
)';
    'VCCIN'<75>:'(0,0,0,0,0,0,0,0,0,0,0,0,0,0,0,0,0,0,BV83,0,0,0,0,0,0,0,0,0,0,0~
)';
    'VCCIN'<74>:'(0,0,0,0,0,0,0,0,0,0,0,0,0,0,0,0,0,0,BW60,0,0,0,0,0,0,0,0,0,0,0~
)';
    'VCCIN'<73>:'(0,0,0,0,0,0,0,0,0,0,0,0,0,0,0,0,0,0,BW62,0,0,0,0,0,0,0,0,0,0,0~
)';
    'VCCIN'<72>:'(0,0,0,0,0,0,0,0,0,0,0,0,0,0,0,0,0,0,BW64,0,0,0,0,0,0,0,0,0,0,0~
)';
    'VCCIN'<71>:'(0,0,0,0,0,0,0,0,0,0,0,0,0,0,0,0,0,0,BW66,0,0,0,0,0,0,0,0,0,0,0~
)';
    'VCCIN'<70>:'(0,0,0,0,0,0,0,0,0,0,0,0,0,0,0,0,0,0,BW68,0,0,0,0,0,0,0,0,0,0,0~
)';
    'VCCIN'<69>:'(0,0,0,0,0,0,0,0,0,0,0,0,0,0,0,0,0,0,BW70,0,0,0,0,0,0,0,0,0,0,0~
)';
    'VCCIN'<68>:'(0,0,0,0,0,0,0,0,0,0,0,0,0,0,0,0,0,0,BW84,0,0,0,0,0,0,0,0,0,0,0~
)';
    'VCCIN'<67>:'(0,0,0,0,0,0,0,0,0,0,0,0,0,0,0,0,0,0,BY61,0,0,0,0,0,0,0,0,0,0,0~
)';
    'VCCIN'<66>:'(0,0,0,0,0,0,0,0,0,0,0,0,0,0,0,0,0,0,BY73,0,0,0,0,0,0,0,0,0,0,0~
)';
    'VCCIN'<65>:'(0,0,0,0,0,0,0,0,0,0,0,0,0,0,0,0,0,0,BY75,0,0,0,0,0,0,0,0,0,0,0~
)';
    'VCCIN'<64>:'(0,0,0,0,0,0,0,0,0,0,0,0,0,0,0,0,0,0,BY77,0,0,0,0,0,0,0,0,0,0,0~
)';
    'VCCIN'<63>:'(0,0,0,0,0,0,0,0,0,0,0,0,0,0,0,0,0,0,BY79,0,0,0,0,0,0,0,0,0,0,0~
)';
    'VCCIN'<62>:'(0,0,0,0,0,0,0,0,0,0,0,0,0,0,0,0,0,0,BY81,0,0,0,0,0,0,0,0,0,0,0~
)';
    'VCCIN'<61>:'(0,0,0,0,0,0,0,0,0,0,0,0,0,0,0,0,0,0,BY83,0,0,0,0,0,0,0,0,0,0,0~
)';
    'VCCIN'<60>:'(0,0,0,0,0,0,0,0,0,0,0,0,0,0,0,0,0,0,CA60,0,0,0,0,0,0,0,0,0,0,0~
)';
    'VCCIN'<59>:'(0,0,0,0,0,0,0,0,0,0,0,0,0,0,0,0,0,0,CA62,0,0,0,0,0,0,0,0,0,0,0~
)';
    'VCCIN'<58>:'(0,0,0,0,0,0,0,0,0,0,0,0,0,0,0,0,0,0,CA72,0,0,0,0,0,0,0,0,0,0,0~
)';
    'VCCIN'<57>:'(0,0,0,0,0,0,0,0,0,0,0,0,0,0,0,0,0,0,CA74,0,0,0,0,0,0,0,0,0,0,0~
)';
    'VCCIN'<56>:'(0,0,0,0,0,0,0,0,0,0,0,0,0,0,0,0,0,0,CA76,0,0,0,0,0,0,0,0,0,0,0~
)';
    'VCCIN'<55>:'(0,0,0,0,0,0,0,0,0,0,0,0,0,0,0,0,0,0,CA78,0,0,0,0,0,0,0,0,0,0,0~
)';
    'VCCIN'<54>:'(0,0,0,0,0,0,0,0,0,0,0,0,0,0,0,0,0,0,CA80,0,0,0,0,0,0,0,0,0,0,0~
)';
    'VCCIN'<53>:'(0,0,0,0,0,0,0,0,0,0,0,0,0,0,0,0,0,0,CA82,0,0,0,0,0,0,0,0,0,0,0~
)';
    'VCCIN'<52>:'(0,0,0,0,0,0,0,0,0,0,0,0,0,0,0,0,0,0,CA84,0,0,0,0,0,0,0,0,0,0,0~
)';
    'VCCIN'<51>:'(0,0,0,0,0,0,0,0,0,0,0,0,0,0,0,0,0,0,CB61,0,0,0,0,0,0,0,0,0,0,0~
)';
    'VCCIN'<50>:'(0,0,0,0,0,0,0,0,0,0,0,0,0,0,0,0,0,0,CB73,0,0,0,0,0,0,0,0,0,0,0~
)';
    'VCCIN'<49>:'(0,0,0,0,0,0,0,0,0,0,0,0,0,0,0,0,0,0,CB75,0,0,0,0,0,0,0,0,0,0,0~
)';
    'VCCIN'<48>:'(0,0,0,0,0,0,0,0,0,0,0,0,0,0,0,0,0,0,CB77,0,0,0,0,0,0,0,0,0,0,0~
)';
    'VCCIN'<47>:'(0,0,0,0,0,0,0,0,0,0,0,0,0,0,0,0,0,0,CB79,0,0,0,0,0,0,0,0,0,0,0~
)';
    'VCCIN'<46>:'(0,0,0,0,0,0,0,0,0,0,0,0,0,0,0,0,0,0,CB81,0,0,0,0,0,0,0,0,0,0,0~
)';
    'VCCIN'<45>:'(0,0,0,0,0,0,0,0,0,0,0,0,0,0,0,0,0,0,CB83,0,0,0,0,0,0,0,0,0,0,0~
)';
    'VCCIN'<44>:'(0,0,0,0,0,0,0,0,0,0,0,0,0,0,0,0,0,0,CC60,0,0,0,0,0,0,0,0,0,0,0~
)';
    'VCCIN'<43>:'(0,0,0,0,0,0,0,0,0,0,0,0,0,0,0,0,0,0,CC62,0,0,0,0,0,0,0,0,0,0,0~
)';
    'VCCIN'<42>:'(0,0,0,0,0,0,0,0,0,0,0,0,0,0,0,0,0,0,CC84,0,0,0,0,0,0,0,0,0,0,0~
)';
    'VCCIN'<41>:'(0,0,0,0,0,0,0,0,0,0,0,0,0,0,0,0,0,0,CD61,0,0,0,0,0,0,0,0,0,0,0~
)';
    'VCCIN'<40>:'(0,0,0,0,0,0,0,0,0,0,0,0,0,0,0,0,0,0,CD83,0,0,0,0,0,0,0,0,0,0,0~
)';
    'VCCIN'<39>:'(0,0,0,0,0,0,0,0,0,0,0,0,0,0,0,0,0,0,CD85,0,0,0,0,0,0,0,0,0,0,0~
)';
    'VCCIN'<38>:'(0,0,0,0,0,0,0,0,0,0,0,0,0,0,0,0,0,0,CE60,0,0,0,0,0,0,0,0,0,0,0~
)';
    'VCCIN'<37>:'(0,0,0,0,0,0,0,0,0,0,0,0,0,0,0,0,0,0,CE84,0,0,0,0,0,0,0,0,0,0,0~
)';
    'VCCIN'<36>:'(0,0,0,0,0,0,0,0,0,0,0,0,0,0,0,0,0,0,CF61,0,0,0,0,0,0,0,0,0,0,0~
)';
    'VCCIN'<35>:'(0,0,0,0,0,0,0,0,0,0,0,0,0,0,0,0,0,0,CF85,0,0,0,0,0,0,0,0,0,0,0~
)';
    'VCCIN'<34>:'(0,0,0,0,0,0,0,0,0,0,0,0,0,0,0,0,0,0,CG60,0,0,0,0,0,0,0,0,0,0,0~
)';
    'VCCIN'<33>:'(0,0,0,0,0,0,0,0,0,0,0,0,0,0,0,0,0,0,CG84,0,0,0,0,0,0,0,0,0,0,0~
)';
    'VCCIN'<32>:'(0,0,0,0,0,0,0,0,0,0,0,0,0,0,0,0,0,0,CH61,0,0,0,0,0,0,0,0,0,0,0~
)';
    'VCCIN'<31>:'(0,0,0,0,0,0,0,0,0,0,0,0,0,0,0,0,0,0,CH85,0,0,0,0,0,0,0,0,0,0,0~
)';
    'VCCIN'<30>:'(0,0,0,0,0,0,0,0,0,0,0,0,0,0,0,0,0,0,CJ60,0,0,0,0,0,0,0,0,0,0,0~
)';
    'VCCIN'<29>:'(0,0,0,0,0,0,0,0,0,0,0,0,0,0,0,0,0,0,CK59,0,0,0,0,0,0,0,0,0,0,0~
)';
    'VCCIN'<28>:'(0,0,0,0,0,0,0,0,0,0,0,0,0,0,0,0,0,0,CK61,0,0,0,0,0,0,0,0,0,0,0~
)';
    'VCCIN'<27>:'(0,0,0,0,0,0,0,0,0,0,0,0,0,0,0,0,0,0,CL58,0,0,0,0,0,0,0,0,0,0,0~
)';
    'VCCIN'<26>:'(0,0,0,0,0,0,0,0,0,0,0,0,0,0,0,0,0,0,CL60,0,0,0,0,0,0,0,0,0,0,0~
)';
    'VCCIN'<25>:'(0,0,0,0,0,0,0,0,0,0,0,0,0,0,0,0,0,0,CM57,0,0,0,0,0,0,0,0,0,0,0~
)';
    'VCCIN'<24>:'(0,0,0,0,0,0,0,0,0,0,0,0,0,0,0,0,0,0,CM59,0,0,0,0,0,0,0,0,0,0,0~
)';
    'VCCIN'<23>:'(0,0,0,0,0,0,0,0,0,0,0,0,0,0,0,0,0,0,CN56,0,0,0,0,0,0,0,0,0,0,0~
)';
    'VCCIN'<22>:'(0,0,0,0,0,0,0,0,0,0,0,0,0,0,0,0,0,0,CN58,0,0,0,0,0,0,0,0,0,0,0~
)';
    'VCCIN'<21>:'(0,0,0,0,0,0,0,0,0,0,0,0,0,0,0,0,0,0,CP33,0,0,0,0,0,0,0,0,0,0,0~
)';
    'VCCIN'<20>:'(0,0,0,0,0,0,0,0,0,0,0,0,0,0,0,0,0,0,CP55,0,0,0,0,0,0,0,0,0,0,0~
)';
    'VCCIN'<19>:'(0,0,0,0,0,0,0,0,0,0,0,0,0,0,0,0,0,0,CP57,0,0,0,0,0,0,0,0,0,0,0~
)';
    'VCCIN'<18>:'(0,0,0,0,0,0,0,0,0,0,0,0,0,0,0,0,0,0,CR34,0,0,0,0,0,0,0,0,0,0,0~
)';
    'VCCIN'<17>:'(0,0,0,0,0,0,0,0,0,0,0,0,0,0,0,0,0,0,CR54,0,0,0,0,0,0,0,0,0,0,0~
)';
    'VCCIN'<16>:'(0,0,0,0,0,0,0,0,0,0,0,0,0,0,0,0,0,0,CR56,0,0,0,0,0,0,0,0,0,0,0~
)';
    'VCCIN'<15>:'(0,0,0,0,0,0,0,0,0,0,0,0,0,0,0,0,0,0,CT37,0,0,0,0,0,0,0,0,0,0,0~
)';
    'VCCIN'<14>:'(0,0,0,0,0,0,0,0,0,0,0,0,0,0,0,0,0,0,CT39,0,0,0,0,0,0,0,0,0,0,0~
)';
    'VCCIN'<13>:'(0,0,0,0,0,0,0,0,0,0,0,0,0,0,0,0,0,0,CT41,0,0,0,0,0,0,0,0,0,0,0~
)';
    'VCCIN'<12>:'(0,0,0,0,0,0,0,0,0,0,0,0,0,0,0,0,0,0,CT53,0,0,0,0,0,0,0,0,0,0,0~
)';
    'VCCIN'<11>:'(0,0,0,0,0,0,0,0,0,0,0,0,0,0,0,0,0,0,CT55,0,0,0,0,0,0,0,0,0,0,0~
)';
    'VCCIN'<10>:'(0,0,0,0,0,0,0,0,0,0,0,0,0,0,0,0,0,0,CU38,0,0,0,0,0,0,0,0,0,0,0~
)';
    'VCCIN'<9>:'(0,0,0,0,0,0,0,0,0,0,0,0,0,0,0,0,0,0,CU40,0,0,0,0,0,0,0,0,0,0,0)~
';
    'VCCIN'<8>:'(0,0,0,0,0,0,0,0,0,0,0,0,0,0,0,0,0,0,CU42,0,0,0,0,0,0,0,0,0,0,0)~
';
    'VCCIN'<7>:'(0,0,0,0,0,0,0,0,0,0,0,0,0,0,0,0,0,0,CU52,0,0,0,0,0,0,0,0,0,0,0)~
';
    'VCCIN'<6>:'(0,0,0,0,0,0,0,0,0,0,0,0,0,0,0,0,0,0,CU54,0,0,0,0,0,0,0,0,0,0,0)~
';
    'VCCIN'<5>:'(0,0,0,0,0,0,0,0,0,0,0,0,0,0,0,0,0,0,CV51,0,0,0,0,0,0,0,0,0,0,0)~
';
    'VCCIN'<4>:'(0,0,0,0,0,0,0,0,0,0,0,0,0,0,0,0,0,0,CW46,0,0,0,0,0,0,0,0,0,0,0)~
';
    'VCCIN'<3>:'(0,0,0,0,0,0,0,0,0,0,0,0,0,0,0,0,0,0,CW48,0,0,0,0,0,0,0,0,0,0,0)~
';
    'VCCIN'<2>:'(0,0,0,0,0,0,0,0,0,0,0,0,0,0,0,0,0,0,CW50,0,0,0,0,0,0,0,0,0,0,0)~
';
    'VCCIN'<1>:'(0,0,0,0,0,0,0,0,0,0,0,0,0,0,0,0,0,0,CY47,0,0,0,0,0,0,0,0,0,0,0)~
';
    'VCCIN'<0>:'(0,0,0,0,0,0,0,0,0,0,0,0,0,0,0,0,0,0,CY49,0,0,0,0,0,0,0,0,0,0,0)~
';
    'VCCINPMAX'<1>:'(0,0,0,0,0,0,0,0,0,0,0,0,0,0,0,0,0,0,AV85,0,0,0,0,0,0,0,0,0,~
0,0)';
    'VCCINPMAX'<0>:'(0,0,0,0,0,0,0,0,0,0,0,0,0,0,0,0,0,0,AW86,0,0,0,0,0,0,0,0,0,~
0,0)';
    'VCCIN_SENSE':'(0,0,0,0,0,0,0,0,0,0,0,0,0,0,0,0,0,0,BA86,0,0,0,0,0,0,0,0,0,0~
,0)';$S;BIDI;
    'VCCIO'<104>:'(0,0,0,0,0,0,0,0,0,0,0,0,0,0,0,0,0,0,0,0,AR28,0,0,0,0,0,0,0,0,~
0)';
    'VCCIO'<103>:'(0,0,0,0,0,0,0,0,0,0,0,0,0,0,0,0,0,0,0,0,AL28,0,0,0,0,0,0,0,0,~
0)';
    'VCCIO'<102>:'(0,0,0,0,0,0,0,0,0,0,0,0,0,0,0,0,0,0,0,0,AM29,0,0,0,0,0,0,0,0,~
0)';
    'VCCIO'<101>:'(0,0,0,0,0,0,0,0,0,0,0,0,0,0,0,0,0,0,0,0,AG34,0,0,0,0,0,0,0,0,~
0)';
    'VCCIO'<100>:'(0,0,0,0,0,0,0,0,0,0,0,0,0,0,0,0,0,0,0,0,AE34,0,0,0,0,0,0,0,0,~
0)';
    'VCCIO'<99>:'(0,0,0,0,0,0,0,0,0,0,0,0,0,0,0,0,0,0,0,0,AD35,0,0,0,0,0,0,0,0,0~
)';
    'VCCIO'<98>:'(0,0,0,0,0,0,0,0,0,0,0,0,0,0,0,0,0,0,0,0,AF35,0,0,0,0,0,0,0,0,0~
)';
    'VCCIO'<97>:'(0,0,0,0,0,0,0,0,0,0,0,0,0,0,0,0,0,0,0,0,AC36,0,0,0,0,0,0,0,0,0~
)';
    'VCCIO'<96>:'(0,0,0,0,0,0,0,0,0,0,0,0,0,0,0,0,0,0,0,0,AD37,0,0,0,0,0,0,0,0,0~
)';
    'VCCIO'<95>:'(0,0,0,0,0,0,0,0,0,0,0,0,0,0,0,0,0,0,0,0,AE36,0,0,0,0,0,0,0,0,0~
)';
    'VCCIO'<94>:'(0,0,0,0,0,0,0,0,0,0,0,0,0,0,0,0,0,0,0,0,BF27,0,0,0,0,0,0,0,0,0~
)';
    'VCCIO'<93>:'(0,0,0,0,0,0,0,0,0,0,0,0,0,0,0,0,0,0,0,0,BG26,0,0,0,0,0,0,0,0,0~
)';
    'VCCIO'<92>:'(0,0,0,0,0,0,0,0,0,0,0,0,0,0,0,0,0,0,0,0,BH25,0,0,0,0,0,0,0,0,0~
)';
    'VCCIO'<91>:'(0,0,0,0,0,0,0,0,0,0,0,0,0,0,0,0,0,0,0,0,BH27,0,0,0,0,0,0,0,0,0~
)';
    'VCCIO'<90>:'(0,0,0,0,0,0,0,0,0,0,0,0,0,0,0,0,0,0,0,0,BJ26,0,0,0,0,0,0,0,0,0~
)';
    'VCCIO'<89>:'(0,0,0,0,0,0,0,0,0,0,0,0,0,0,0,0,0,0,0,0,BK25,0,0,0,0,0,0,0,0,0~
)';
    'VCCIO'<88>:'(0,0,0,0,0,0,0,0,0,0,0,0,0,0,0,0,0,0,0,0,BK27,0,0,0,0,0,0,0,0,0~
)';
    'VCCIO'<87>:'(0,0,0,0,0,0,0,0,0,0,0,0,0,0,0,0,0,0,0,0,BL26,0,0,0,0,0,0,0,0,0~
)';
    'VCCIO'<86>:'(0,0,0,0,0,0,0,0,0,0,0,0,0,0,0,0,0,0,0,0,BM27,0,0,0,0,0,0,0,0,0~
)';
    'VCCIO'<85>:'(0,0,0,0,0,0,0,0,0,0,0,0,0,0,0,0,0,0,0,0,CH27,0,0,0,0,0,0,0,0,0~
)';
    'VCCIO'<84>:'(0,0,0,0,0,0,0,0,0,0,0,0,0,0,0,0,0,0,0,0,CJ28,0,0,0,0,0,0,0,0,0~
)';
    'VCCIO'<83>:'(0,0,0,0,0,0,0,0,0,0,0,0,0,0,0,0,0,0,0,0,CC26,0,0,0,0,0,0,0,0,0~
)';
    'VCCIO'<82>:'(0,0,0,0,0,0,0,0,0,0,0,0,0,0,0,0,0,0,0,0,CD27,0,0,0,0,0,0,0,0,0~
)';
    'VCCIO'<81>:'(0,0,0,0,0,0,0,0,0,0,0,0,0,0,0,0,0,0,0,0,CF27,0,0,0,0,0,0,0,0,0~
)';
    'VCCIO'<80>:'(0,0,0,0,0,0,0,0,0,0,0,0,0,0,0,0,0,0,0,0,AV27,0,0,0,0,0,0,0,0,0~
)';
    'VCCIO'<79>:'(0,0,0,0,0,0,0,0,0,0,0,0,0,0,0,0,0,0,0,0,AW26,0,0,0,0,0,0,0,0,0~
)';
    'VCCIO'<78>:'(0,0,0,0,0,0,0,0,0,0,0,0,0,0,0,0,0,0,0,0,AY27,0,0,0,0,0,0,0,0,0~
)';
    'VCCIO'<77>:'(0,0,0,0,0,0,0,0,0,0,0,0,0,0,0,0,0,0,0,0,BA26,0,0,0,0,0,0,0,0,0~
)';
    'VCCIO'<76>:'(0,0,0,0,0,0,0,0,0,0,0,0,0,0,0,0,0,0,0,0,BB27,0,0,0,0,0,0,0,0,0~
)';
    'VCCIO'<75>:'(0,0,0,0,0,0,0,0,0,0,0,0,0,0,0,0,0,0,0,0,BC26,0,0,0,0,0,0,0,0,0~
)';
    'VCCIO'<74>:'(0,0,0,0,0,0,0,0,0,0,0,0,0,0,0,0,0,0,0,0,W10,0,0,0,0,0,0,0,0,0)~
';
    'VCCIO'<73>:'(0,0,0,0,0,0,0,0,0,0,0,0,0,0,0,0,0,0,0,0,N18,0,0,0,0,0,0,0,0,0)~
';
    'VCCIO'<72>:'(0,0,0,0,0,0,0,0,0,0,0,0,0,0,0,0,0,0,0,0,M9,0,0,0,0,0,0,0,0,0)';
    'VCCIO'<71>:'(0,0,0,0,0,0,0,0,0,0,0,0,0,0,0,0,0,0,0,0,M7,0,0,0,0,0,0,0,0,0)';
    'VCCIO'<70>:'(0,0,0,0,0,0,0,0,0,0,0,0,0,0,0,0,0,0,0,0,K15,0,0,0,0,0,0,0,0,0)~
';
    'VCCIO'<69>:'(0,0,0,0,0,0,0,0,0,0,0,0,0,0,0,0,0,0,0,0,J2,0,0,0,0,0,0,0,0,0)';
    'VCCIO'<68>:'(0,0,0,0,0,0,0,0,0,0,0,0,0,0,0,0,0,0,0,0,EB15,0,0,0,0,0,0,0,0,0~
)';
    'VCCIO'<67>:'(0,0,0,0,0,0,0,0,0,0,0,0,0,0,0,0,0,0,0,0,EA12,0,0,0,0,0,0,0,0,0~
)';
    'VCCIO'<66>:'(0,0,0,0,0,0,0,0,0,0,0,0,0,0,0,0,0,0,0,0,DU20,0,0,0,0,0,0,0,0,0~
)';
    'VCCIO'<65>:'(0,0,0,0,0,0,0,0,0,0,0,0,0,0,0,0,0,0,0,0,DR2,0,0,0,0,0,0,0,0,0)~
';
    'VCCIO'<64>:'(0,0,0,0,0,0,0,0,0,0,0,0,0,0,0,0,0,0,0,0,DR10,0,0,0,0,0,0,0,0,0~
)';
    'VCCIO'<63>:'(0,0,0,0,0,0,0,0,0,0,0,0,0,0,0,0,0,0,0,0,DP19,0,0,0,0,0,0,0,0,0~
)';
    'VCCIO'<62>:'(0,0,0,0,0,0,0,0,0,0,0,0,0,0,0,0,0,0,0,0,DN8,0,0,0,0,0,0,0,0,0)~
';
    'VCCIO'<61>:'(0,0,0,0,0,0,0,0,0,0,0,0,0,0,0,0,0,0,0,0,DM17,0,0,0,0,0,0,0,0,0~
)';
    'VCCIO'<60>:'(0,0,0,0,0,0,0,0,0,0,0,0,0,0,0,0,0,0,0,0,DJ16,0,0,0,0,0,0,0,0,0~
)';
    'VCCIO'<59>:'(0,0,0,0,0,0,0,0,0,0,0,0,0,0,0,0,0,0,0,0,H13,0,0,0,0,0,0,0,0,0)~
';
    'VCCIO'<58>:'(0,0,0,0,0,0,0,0,0,0,0,0,0,0,0,0,0,0,0,0,J10,0,0,0,0,0,0,0,0,0)~
';
    'VCCIO'<57>:'(0,0,0,0,0,0,0,0,0,0,0,0,0,0,0,0,0,0,0,0,L14,0,0,0,0,0,0,0,0,0)~
';
    'VCCIO'<56>:'(0,0,0,0,0,0,0,0,0,0,0,0,0,0,0,0,0,0,0,0,L16,0,0,0,0,0,0,0,0,0)~
';
    'VCCIO'<55>:'(0,0,0,0,0,0,0,0,0,0,0,0,0,0,0,0,0,0,0,0,DH7,0,0,0,0,0,0,0,0,0)~
';
    'VCCIO'<54>:'(0,0,0,0,0,0,0,0,0,0,0,0,0,0,0,0,0,0,0,0,DG8,0,0,0,0,0,0,0,0,0)~
';
    'VCCIO'<53>:'(0,0,0,0,0,0,0,0,0,0,0,0,0,0,0,0,0,0,0,0,M11,0,0,0,0,0,0,0,0,0)~
';
    'VCCIO'<52>:'(0,0,0,0,0,0,0,0,0,0,0,0,0,0,0,0,0,0,0,0,M21,0,0,0,0,0,0,0,0,0)~
';
    'VCCIO'<51>:'(0,0,0,0,0,0,0,0,0,0,0,0,0,0,0,0,0,0,0,0,P5,0,0,0,0,0,0,0,0,0)';
    'VCCIO'<50>:'(0,0,0,0,0,0,0,0,0,0,0,0,0,0,0,0,0,0,0,0,T3,0,0,0,0,0,0,0,0,0)';
    'VCCIO'<49>:'(0,0,0,0,0,0,0,0,0,0,0,0,0,0,0,0,0,0,0,0,U14,0,0,0,0,0,0,0,0,0)~
';
    'VCCIO'<48>:'(0,0,0,0,0,0,0,0,0,0,0,0,0,0,0,0,0,0,0,0,DF21,0,0,0,0,0,0,0,0,0~
)';
    'VCCIO'<47>:'(0,0,0,0,0,0,0,0,0,0,0,0,0,0,0,0,0,0,0,0,W4,0,0,0,0,0,0,0,0,0)';
    'VCCIO'<46>:'(0,0,0,0,0,0,0,0,0,0,0,0,0,0,0,0,0,0,0,0,W6,0,0,0,0,0,0,0,0,0)';
    'VCCIO'<45>:'(0,0,0,0,0,0,0,0,0,0,0,0,0,0,0,0,0,0,0,0,AA10,0,0,0,0,0,0,0,0,0~
)';
    'VCCIO'<44>:'(0,0,0,0,0,0,0,0,0,0,0,0,0,0,0,0,0,0,0,0,AC20,0,0,0,0,0,0,0,0,0~
)';
    'VCCIO'<43>:'(0,0,0,0,0,0,0,0,0,0,0,0,0,0,0,0,0,0,0,0,AC4,0,0,0,0,0,0,0,0,0)~
';
    'VCCIO'<42>:'(0,0,0,0,0,0,0,0,0,0,0,0,0,0,0,0,0,0,0,0,AH9,0,0,0,0,0,0,0,0,0)~
';
    'VCCIO'<41>:'(0,0,0,0,0,0,0,0,0,0,0,0,0,0,0,0,0,0,0,0,DF13,0,0,0,0,0,0,0,0,0~
)';
    'VCCIO'<40>:'(0,0,0,0,0,0,0,0,0,0,0,0,0,0,0,0,0,0,0,0,AN10,0,0,0,0,0,0,0,0,0~
)';
    'VCCIO'<39>:'(0,0,0,0,0,0,0,0,0,0,0,0,0,0,0,0,0,0,0,0,DD7,0,0,0,0,0,0,0,0,0)~
';
    'VCCIO'<38>:'(0,0,0,0,0,0,0,0,0,0,0,0,0,0,0,0,0,0,0,0,AT11,0,0,0,0,0,0,0,0,0~
)';
    'VCCIO'<37>:'(0,0,0,0,0,0,0,0,0,0,0,0,0,0,0,0,0,0,0,0,AW6,0,0,0,0,0,0,0,0,0)~
';
    'VCCIO'<36>:'(0,0,0,0,0,0,0,0,0,0,0,0,0,0,0,0,0,0,0,0,AY11,0,0,0,0,0,0,0,0,0~
)';
    'VCCIO'<35>:'(0,0,0,0,0,0,0,0,0,0,0,0,0,0,0,0,0,0,0,0,BA24,0,0,0,0,0,0,0,0,0~
)';
    'VCCIO'<34>:'(0,0,0,0,0,0,0,0,0,0,0,0,0,0,0,0,0,0,0,0,BB5,0,0,0,0,0,0,0,0,0)~
';
    'VCCIO'<33>:'(0,0,0,0,0,0,0,0,0,0,0,0,0,0,0,0,0,0,0,0,DA14,0,0,0,0,0,0,0,0,0~
)';
    'VCCIO'<32>:'(0,0,0,0,0,0,0,0,0,0,0,0,0,0,0,0,0,0,0,0,BF23,0,0,0,0,0,0,0,0,0~
)';
    'VCCIO'<31>:'(0,0,0,0,0,0,0,0,0,0,0,0,0,0,0,0,0,0,0,0,BJ24,0,0,0,0,0,0,0,0,0~
)';
    'VCCIO'<30>:'(0,0,0,0,0,0,0,0,0,0,0,0,0,0,0,0,0,0,0,0,BP25,0,0,0,0,0,0,0,0,0~
)';
    'VCCIO'<29>:'(0,0,0,0,0,0,0,0,0,0,0,0,0,0,0,0,0,0,0,0,CB13,0,0,0,0,0,0,0,0,0~
)';
    'VCCIO'<28>:'(0,0,0,0,0,0,0,0,0,0,0,0,0,0,0,0,0,0,0,0,CB17,0,0,0,0,0,0,0,0,0~
)';
    'VCCIO'<27>:'(0,0,0,0,0,0,0,0,0,0,0,0,0,0,0,0,0,0,0,0,CD9,0,0,0,0,0,0,0,0,0)~
';
    'VCCIO'<26>:'(0,0,0,0,0,0,0,0,0,0,0,0,0,0,0,0,0,0,0,0,CE18,0,0,0,0,0,0,0,0,0~
)';
    'VCCIO'<25>:'(0,0,0,0,0,0,0,0,0,0,0,0,0,0,0,0,0,0,0,0,D7,0,0,0,0,0,0,0,0,0)';
    'VCCIO'<24>:'(0,0,0,0,0,0,0,0,0,0,0,0,0,0,0,0,0,0,0,0,CH9,0,0,0,0,0,0,0,0,0)~
';
    'VCCIO'<23>:'(0,0,0,0,0,0,0,0,0,0,0,0,0,0,0,0,0,0,0,0,CV7,0,0,0,0,0,0,0,0,0)~
';
    'VCCIO'<22>:'(0,0,0,0,0,0,0,0,0,0,0,0,0,0,0,0,0,0,0,0,CK5,0,0,0,0,0,0,0,0,0)~
';
    'VCCIO'<21>:'(0,0,0,0,0,0,0,0,0,0,0,0,0,0,0,0,0,0,0,0,CL12,0,0,0,0,0,0,0,0,0~
)';
    'VCCIO'<20>:'(0,0,0,0,0,0,0,0,0,0,0,0,0,0,0,0,0,0,0,0,CM15,0,0,0,0,0,0,0,0,0~
)';
    'VCCIO'<19>:'(0,0,0,0,0,0,0,0,0,0,0,0,0,0,0,0,0,0,0,0,0,CN6,0,0,0,0,0,0,0,0)~
';
    'VCCIO'<18>:'(0,0,0,0,0,0,0,0,0,0,0,0,0,0,0,0,0,0,0,0,0,CU12,0,0,0,0,0,0,0,0~
)';
    'VCCIO'<17>:'(0,0,0,0,0,0,0,0,0,0,0,0,0,0,0,0,0,0,0,0,0,CV21,0,0,0,0,0,0,0,0~
)';
    'VCCIO'<16>:'(0,0,0,0,0,0,0,0,0,0,0,0,0,0,0,0,0,0,0,0,0,CU18,0,0,0,0,0,0,0,0~
)';
    'VCCIO'<15>:'(0,0,0,0,0,0,0,0,0,0,0,0,0,0,0,0,0,0,0,0,0,CY17,0,0,0,0,0,0,0,0~
)';
    'VCCIO'<14>:'(0,0,0,0,0,0,0,0,0,0,0,0,0,0,0,0,0,0,0,0,0,DC18,0,0,0,0,0,0,0,0~
)';
    'VCCIO'<13>:'(0,0,0,0,0,0,0,0,0,0,0,0,0,0,0,0,0,0,0,0,0,DE14,0,0,0,0,0,0,0,0~
)';
    'VCCIO'<12>:'(0,0,0,0,0,0,0,0,0,0,0,0,0,0,0,0,0,0,0,0,0,CP13,0,0,0,0,0,0,0,0~
)';
    'VCCIO'<11>:'(0,0,0,0,0,0,0,0,0,0,0,0,0,0,0,0,0,0,0,0,0,CL20,0,0,0,0,0,0,0,0~
)';
    'VCCIO'<10>:'(0,0,0,0,0,0,0,0,0,0,0,0,0,0,0,0,0,0,0,0,0,CG14,0,0,0,0,0,0,0,0~
)';
    'VCCIO'<9>:'(0,0,0,0,0,0,0,0,0,0,0,0,0,0,0,0,0,0,0,0,0,CF5,0,0,0,0,0,0,0,0)';
    'VCCIO'<8>:'(0,0,0,0,0,0,0,0,0,0,0,0,0,0,0,0,0,0,0,0,0,DK21,0,0,0,0,0,0,0,0)~
';
    'VCCIO'<7>:'(0,0,0,0,0,0,0,0,0,0,0,0,0,0,0,0,0,0,0,0,0,BE24,0,0,0,0,0,0,0,0)~
';
    'VCCIO'<6>:'(0,0,0,0,0,0,0,0,0,0,0,0,0,0,0,0,0,0,0,0,0,AT7,0,0,0,0,0,0,0,0)';
    'VCCIO'<5>:'(0,0,0,0,0,0,0,0,0,0,0,0,0,0,0,0,0,0,0,0,0,AT5,0,0,0,0,0,0,0,0)';
    'VCCIO'<4>:'(0,0,0,0,0,0,0,0,0,0,0,0,0,0,0,0,0,0,0,0,0,AM5,0,0,0,0,0,0,0,0)';
    'VCCIO'<3>:'(0,0,0,0,0,0,0,0,0,0,0,0,0,0,0,0,0,0,0,0,0,DV11,0,0,0,0,0,0,0,0)~
';
    'VCCIO'<2>:'(0,0,0,0,0,0,0,0,0,0,0,0,0,0,0,0,0,0,0,0,0,AF5,0,0,0,0,0,0,0,0)';
    'VCCIO'<1>:'(0,0,0,0,0,0,0,0,0,0,0,0,0,0,0,0,0,0,0,0,0,AE10,0,0,0,0,0,0,0,0)~
';
    'VCCIO'<0>:'(0,0,0,0,0,0,0,0,0,0,0,0,0,0,0,0,0,0,0,0,0,EE10,0,0,0,0,0,0,0,0)~
';
    'VCCIO_SENSE':'(0,0,0,0,0,0,0,0,0,0,0,0,0,0,0,0,0,0,0,0,0,BH5,0,0,0,0,0,0,0,~
0)';$S;
    'VCCSA'<25>:'(0,0,0,0,0,0,0,0,0,0,0,0,0,0,0,0,0,0,0,0,CB65,0,0,0,0,0,0,0,0,0~
)';
    'VCCSA'<24>:'(0,0,0,0,0,0,0,0,0,0,0,0,0,0,0,0,0,0,0,0,CB67,0,0,0,0,0,0,0,0,0~
)';
    'VCCSA'<23>:'(0,0,0,0,0,0,0,0,0,0,0,0,0,0,0,0,0,0,0,0,CB69,0,0,0,0,0,0,0,0,0~
)';
    'VCCSA'<22>:'(0,0,0,0,0,0,0,0,0,0,0,0,0,0,0,0,0,0,0,0,CC66,0,0,0,0,0,0,0,0,0~
)';
    'VCCSA'<21>:'(0,0,0,0,0,0,0,0,0,0,0,0,0,0,0,0,0,0,0,0,CC68,0,0,0,0,0,0,0,0,0~
)';
    'VCCSA'<20>:'(0,0,0,0,0,0,0,0,0,0,0,0,0,0,0,0,0,0,0,0,CC70,0,0,0,0,0,0,0,0,0~
)';
    'VCCSA'<19>:'(0,0,0,0,0,0,0,0,0,0,0,0,0,0,0,0,0,0,0,0,CD65,0,0,0,0,0,0,0,0,0~
)';
    'VCCSA'<18>:'(0,0,0,0,0,0,0,0,0,0,0,0,0,0,0,0,0,0,0,0,CD67,0,0,0,0,0,0,0,0,0~
)';
    'VCCSA'<17>:'(0,0,0,0,0,0,0,0,0,0,0,0,0,0,0,0,0,0,0,0,CD69,0,0,0,0,0,0,0,0,0~
)';
    'VCCSA'<16>:'(0,0,0,0,0,0,0,0,0,0,0,0,0,0,0,0,0,0,0,0,CD71,0,0,0,0,0,0,0,0,0~
)';
    'VCCSA'<15>:'(0,0,0,0,0,0,0,0,0,0,0,0,0,0,0,0,0,0,0,0,CE64,0,0,0,0,0,0,0,0,0~
)';
    'VCCSA'<14>:'(0,0,0,0,0,0,0,0,0,0,0,0,0,0,0,0,0,0,0,0,CE66,0,0,0,0,0,0,0,0,0~
)';
    'VCCSA'<13>:'(0,0,0,0,0,0,0,0,0,0,0,0,0,0,0,0,0,0,0,0,CE68,0,0,0,0,0,0,0,0,0~
)';
    'VCCSA'<12>:'(0,0,0,0,0,0,0,0,0,0,0,0,0,0,0,0,0,0,0,0,CE72,0,0,0,0,0,0,0,0,0~
)';
    'VCCSA'<11>:'(0,0,0,0,0,0,0,0,0,0,0,0,0,0,0,0,0,0,0,0,CE74,0,0,0,0,0,0,0,0,0~
)';
    'VCCSA'<10>:'(0,0,0,0,0,0,0,0,0,0,0,0,0,0,0,0,0,0,0,0,CF65,0,0,0,0,0,0,0,0,0~
)';
    'VCCSA'<9>:'(0,0,0,0,0,0,0,0,0,0,0,0,0,0,0,0,0,0,0,0,CF67,0,0,0,0,0,0,0,0,0)~
';
    'VCCSA'<8>:'(0,0,0,0,0,0,0,0,0,0,0,0,0,0,0,0,0,0,0,0,CF73,0,0,0,0,0,0,0,0,0)~
';
    'VCCSA'<7>:'(0,0,0,0,0,0,0,0,0,0,0,0,0,0,0,0,0,0,0,0,CF75,0,0,0,0,0,0,0,0,0)~
';
    'VCCSA'<6>:'(0,0,0,0,0,0,0,0,0,0,0,0,0,0,0,0,0,0,0,0,CG64,0,0,0,0,0,0,0,0,0)~
';
    'VCCSA'<5>:'(0,0,0,0,0,0,0,0,0,0,0,0,0,0,0,0,0,0,0,0,CG66,0,0,0,0,0,0,0,0,0)~
';
    'VCCSA'<4>:'(0,0,0,0,0,0,0,0,0,0,0,0,0,0,0,0,0,0,0,0,CG74,0,0,0,0,0,0,0,0,0)~
';
    'VCCSA'<3>:'(0,0,0,0,0,0,0,0,0,0,0,0,0,0,0,0,0,0,0,0,CH65,0,0,0,0,0,0,0,0,0)~
';
    'VCCSA'<2>:'(0,0,0,0,0,0,0,0,0,0,0,0,0,0,0,0,0,0,0,0,CH75,0,0,0,0,0,0,0,0,0)~
';
    'VCCSA'<1>:'(0,0,0,0,0,0,0,0,0,0,0,0,0,0,0,0,0,0,0,0,CJ64,0,0,0,0,0,0,0,0,0)~
';
    'VCCSA'<0>:'(0,0,0,0,0,0,0,0,0,0,0,0,0,0,0,0,0,0,0,0,CJ66,0,0,0,0,0,0,0,0,0)~
';
    'VCCSA_SENSE':'(0,0,0,0,0,0,0,0,0,0,0,0,0,0,0,0,0,0,0,0,0,CE76,0,0,0,0,0,0,0~
,0)';$S;
    'VSENSEPMAX':'(0,0,0,0,0,0,0,0,0,0,0,0,0,0,0,0,0,0,AD41,0,0,0,0,0,0,0,0,0,0,~
0)';$S;
    'VSS'<1253>:'(0,0,0,0,0,0,0,0,0,0,0,0,0,0,0,0,0,0,0,0,0,0,B9,0,0,0,0,0,0,0)';
    'VSS'<1252>:'(0,0,0,0,0,0,0,0,0,0,0,0,0,0,0,0,0,0,0,0,0,0,A42,0,0,0,0,0,0,0)~
';
    'VSS'<1251>:'(0,0,0,0,0,0,0,0,0,0,0,0,0,0,0,0,0,0,0,0,0,0,B43,0,0,0,0,0,0,0)~
';
    'VSS'<1250>:'(0,0,0,0,0,0,0,0,0,0,0,0,0,0,0,0,0,0,0,0,0,0,B5,0,0,0,0,0,0,0)';
    'VSS'<1249>:'(0,0,0,0,0,0,0,0,0,0,0,0,0,0,0,0,0,0,0,0,0,0,B79,0,0,0,0,0,0,0)~
';
    'VSS'<1248>:'(0,0,0,0,0,0,0,0,0,0,0,0,0,0,0,0,0,0,0,0,0,0,C4,0,0,0,0,0,0,0)';
    'VSS'<1247>:'(0,0,0,0,0,0,0,0,0,0,0,0,0,0,0,0,0,0,0,0,0,0,C80,0,0,0,0,0,0,0)~
';
    'VSS'<1246>:'(0,0,0,0,0,0,0,0,0,0,0,0,0,0,0,0,0,0,0,0,0,0,D3,0,0,0,0,0,0,0)';
    'VSS'<1245>:'(0,0,0,0,0,0,0,0,0,0,0,0,0,0,0,0,0,0,0,0,0,0,D81,0,0,0,0,0,0,0)~
';
    'VSS'<1244>:'(0,0,0,0,0,0,0,0,0,0,0,0,0,0,0,0,0,0,0,0,0,0,E82,0,0,0,0,0,0,0)~
';
    'VSS'<1243>:'(0,0,0,0,0,0,0,0,0,0,0,0,0,0,0,0,0,0,0,0,0,0,J86,0,0,0,0,0,0,0)~
';
    'VSS'<1242>:'(0,0,0,0,0,0,0,0,0,0,0,0,0,0,0,0,0,0,0,0,0,0,DY85,0,0,0,0,0,0,0~
)';
    'VSS'<1241>:'(0,0,0,0,0,0,0,0,0,0,0,0,0,0,0,0,0,0,0,0,0,0,EA84,0,0,0,0,0,0,0~
)';
    'VSS'<1240>:'(0,0,0,0,0,0,0,0,0,0,0,0,0,0,0,0,0,0,0,0,0,0,EB83,0,0,0,0,0,0,0~
)';
    'VSS'<1239>:'(0,0,0,0,0,0,0,0,0,0,0,0,0,0,0,0,0,0,0,0,0,0,DW2,0,0,0,0,0,0,0)~
';
    'VSS'<1238>:'(0,0,0,0,0,0,0,0,0,0,0,0,0,0,0,0,0,0,0,0,0,0,EC42,0,0,0,0,0,0,0~
)';
    'VSS'<1237>:'(0,0,0,0,0,0,0,0,0,0,0,0,0,0,0,0,0,0,0,0,0,0,EC6,0,0,0,0,0,0,0)~
';
    'VSS'<1236>:'(0,0,0,0,0,0,0,0,0,0,0,0,0,0,0,0,0,0,0,0,0,0,EC82,0,0,0,0,0,0,0~
)';
    'VSS'<1235>:'(0,0,0,0,0,0,0,0,0,0,0,0,0,0,0,0,0,0,0,0,0,0,ED41,0,0,0,0,0,0,0~
)';
    'VSS'<1234>:'(0,0,0,0,0,0,0,0,0,0,0,0,0,0,0,0,0,0,0,0,0,0,ED7,0,0,0,0,0,0,0)~
';
    'VSS'<1233>:'(0,0,0,0,0,0,0,0,0,0,0,0,0,0,0,0,0,0,0,0,0,0,ED81,0,0,0,0,0,0,0~
)';
    'VSS'<1232>:'(0,0,0,0,0,0,0,0,0,0,0,0,0,0,0,0,0,0,0,0,0,0,EE40,0,0,0,0,0,0,0~
)';
    'VSS'<1231>:'(0,0,0,0,0,0,0,0,0,0,0,0,0,0,0,0,0,0,0,0,0,0,EE8,0,0,0,0,0,0,0)~
';
    'VSS'<1230>:'(0,0,0,0,0,0,0,0,0,0,0,0,0,0,0,0,0,0,0,0,0,0,EE80,0,0,0,0,0,0,0~
)';
    'VSS'<1229>:'(0,0,0,0,0,0,0,0,0,0,0,0,0,0,0,0,0,0,0,0,0,0,ED69,0,0,0,0,0,0,0~
)';
    'VSS'<1228>:'(0,0,0,0,0,0,0,0,0,0,0,0,0,0,0,0,0,0,0,0,0,0,E66,0,0,0,0,0,0,0)~
';
    'VSS'<1227>:'(0,0,0,0,0,0,0,0,0,0,0,0,0,0,0,0,0,0,0,0,0,0,V11,0,0,0,0,0,0,0)~
';
    'VSS'<1226>:'(0,0,0,0,0,0,0,0,0,0,0,0,0,0,0,0,0,0,0,0,0,0,L8,0,0,0,0,0,0,0)';
    'VSS'<1225>:'(0,0,0,0,0,0,0,0,0,0,0,0,0,0,0,0,0,0,0,0,0,0,EA14,0,0,0,0,0,0,0~
)';
    'VSS'<1224>:'(0,0,0,0,0,0,0,0,0,0,0,0,0,0,0,0,0,0,0,0,0,0,DY63,0,0,0,0,0,0,0~
)';
    'VSS'<1223>:'(0,0,0,0,0,0,0,0,0,0,0,0,0,0,0,0,0,0,0,0,0,0,DY61,0,0,0,0,0,0,0~
)';
    'VSS'<1222>:'(0,0,0,0,0,0,0,0,0,0,0,0,0,0,0,0,0,0,0,0,0,0,DY59,0,0,0,0,0,0,0~
)';
    'VSS'<1221>:'(0,0,0,0,0,0,0,0,0,0,0,0,0,0,0,0,0,0,0,0,0,0,DY57,0,0,0,0,0,0,0~
)';
    'VSS'<1220>:'(0,0,0,0,0,0,0,0,0,0,0,0,0,0,0,0,0,0,0,0,0,0,DY55,0,0,0,0,0,0,0~
)';
    'VSS'<1219>:'(0,0,0,0,0,0,0,0,0,0,0,0,0,0,0,0,0,0,0,0,0,0,DY53,0,0,0,0,0,0,0~
)';
    'VSS'<1218>:'(0,0,0,0,0,0,0,0,0,0,0,0,0,0,0,0,0,0,0,0,0,0,DY51,0,0,0,0,0,0,0~
)';
    'VSS'<1217>:'(0,0,0,0,0,0,0,0,0,0,0,0,0,0,0,0,0,0,0,0,0,0,DY49,0,0,0,0,0,0,0~
)';
    'VSS'<1216>:'(0,0,0,0,0,0,0,0,0,0,0,0,0,0,0,0,0,0,0,0,0,0,DY47,0,0,0,0,0,0,0~
)';
    'VSS'<1215>:'(0,0,0,0,0,0,0,0,0,0,0,0,0,0,0,0,0,0,0,0,0,0,DY45,0,0,0,0,0,0,0~
)';
    'VSS'<1214>:'(0,0,0,0,0,0,0,0,0,0,0,0,0,0,0,0,0,0,0,0,0,0,DV19,0,0,0,0,0,0,0~
)';
    'VSS'<1213>:'(0,0,0,0,0,0,0,0,0,0,0,0,0,0,0,0,0,0,0,0,0,0,DP9,0,0,0,0,0,0,0)~
';
    'VSS'<1212>:'(0,0,0,0,0,0,0,0,0,0,0,0,0,0,0,0,0,0,0,0,0,0,DP63,0,0,0,0,0,0,0~
)';
    'VSS'<1211>:'(0,0,0,0,0,0,0,0,0,0,0,0,0,0,0,0,0,0,0,0,0,0,DP61,0,0,0,0,0,0,0~
)';
    'VSS'<1210>:'(0,0,0,0,0,0,0,0,0,0,0,0,0,0,0,0,0,0,0,0,0,0,DP59,0,0,0,0,0,0,0~
)';
    'VSS'<1209>:'(0,0,0,0,0,0,0,0,0,0,0,0,0,0,0,0,0,0,0,0,0,0,DP57,0,0,0,0,0,0,0~
)';
    'VSS'<1208>:'(0,0,0,0,0,0,0,0,0,0,0,0,0,0,0,0,0,0,0,0,0,0,DP55,0,0,0,0,0,0,0~
)';
    'VSS'<1207>:'(0,0,0,0,0,0,0,0,0,0,0,0,0,0,0,0,0,0,0,0,0,0,DP53,0,0,0,0,0,0,0~
)';
    'VSS'<1206>:'(0,0,0,0,0,0,0,0,0,0,0,0,0,0,0,0,0,0,0,0,0,0,DP51,0,0,0,0,0,0,0~
)';
    'VSS'<1205>:'(0,0,0,0,0,0,0,0,0,0,0,0,0,0,0,0,0,0,0,0,0,0,DP49,0,0,0,0,0,0,0~
)';
    'VSS'<1204>:'(0,0,0,0,0,0,0,0,0,0,0,0,0,0,0,0,0,0,0,0,0,0,DP47,0,0,0,0,0,0,0~
)';
    'VSS'<1203>:'(0,0,0,0,0,0,0,0,0,0,0,0,0,0,0,0,0,0,0,0,0,0,DP45,0,0,0,0,0,0,0~
)';
    'VSS'<1202>:'(0,0,0,0,0,0,0,0,0,0,0,0,0,0,0,0,0,0,0,0,0,0,DN18,0,0,0,0,0,0,0~
)';
    'VSS'<1201>:'(0,0,0,0,0,0,0,0,0,0,0,0,0,0,0,0,0,0,0,0,0,0,DL8,0,0,0,0,0,0,0)~
';
    'VSS'<1200>:'(0,0,0,0,0,0,0,0,0,0,0,0,0,0,0,0,0,0,0,0,0,0,DE62,0,0,0,0,0,0,0~
)';
    'VSS'<1199>:'(0,0,0,0,0,0,0,0,0,0,0,0,0,0,0,0,0,0,0,0,0,0,DE60,0,0,0,0,0,0,0~
)';
    'VSS'<1198>:'(0,0,0,0,0,0,0,0,0,0,0,0,0,0,0,0,0,0,0,0,0,0,DE58,0,0,0,0,0,0,0~
)';
    'VSS'<1197>:'(0,0,0,0,0,0,0,0,0,0,0,0,0,0,0,0,0,0,0,0,0,0,DE56,0,0,0,0,0,0,0~
)';
    'VSS'<1196>:'(0,0,0,0,0,0,0,0,0,0,0,0,0,0,0,0,0,0,0,0,0,0,DE54,0,0,0,0,0,0,0~
)';
    'VSS'<1195>:'(0,0,0,0,0,0,0,0,0,0,0,0,0,0,0,0,0,0,0,0,0,0,DE52,0,0,0,0,0,0,0~
)';
    'VSS'<1194>:'(0,0,0,0,0,0,0,0,0,0,0,0,0,0,0,0,0,0,0,0,0,0,DE50,0,0,0,0,0,0,0~
)';
    'VSS'<1193>:'(0,0,0,0,0,0,0,0,0,0,0,0,0,0,0,0,0,0,0,0,0,0,DE48,0,0,0,0,0,0,0~
)';
    'VSS'<1192>:'(0,0,0,0,0,0,0,0,0,0,0,0,0,0,0,0,0,0,0,0,0,0,CW6,0,0,0,0,0,0,0)~
';
    'VSS'<1191>:'(0,0,0,0,0,0,0,0,0,0,0,0,0,0,0,0,0,0,0,0,0,0,CG6,0,0,0,0,0,0,0)~
';
    'VSS'<1190>:'(0,0,0,0,0,0,0,0,0,0,0,0,0,0,0,0,0,0,0,0,0,0,AR6,0,0,0,0,0,0,0)~
';
    'VSS'<1189>:'(0,0,0,0,0,0,0,0,0,0,0,0,0,0,0,0,0,0,0,0,0,0,AJ4,0,0,0,0,0,0,0)~
';
    'VSS'<1188>:'(0,0,0,0,0,0,0,0,0,0,0,0,0,0,0,0,0,0,0,0,0,0,AC62,0,0,0,0,0,0,0~
)';
    'VSS'<1187>:'(0,0,0,0,0,0,0,0,0,0,0,0,0,0,0,0,0,0,0,0,0,0,AC60,0,0,0,0,0,0,0~
)';
    'VSS'<1186>:'(0,0,0,0,0,0,0,0,0,0,0,0,0,0,0,0,0,0,0,0,0,0,AC58,0,0,0,0,0,0,0~
)';
    'VSS'<1185>:'(0,0,0,0,0,0,0,0,0,0,0,0,0,0,0,0,0,0,0,0,0,0,A26,0,0,0,0,0,0,0)~
';
    'VSS'<1184>:'(0,0,0,0,0,0,0,0,0,0,0,0,0,0,0,0,0,0,0,0,0,0,A30,0,0,0,0,0,0,0)~
';
    'VSS'<1183>:'(0,0,0,0,0,0,0,0,0,0,0,0,0,0,0,0,0,0,0,0,0,0,A32,0,0,0,0,0,0,0)~
';
    'VSS'<1182>:'(0,0,0,0,0,0,0,0,0,0,0,0,0,0,0,0,0,0,0,0,0,0,A36,0,0,0,0,0,0,0)~
';
    'VSS'<1181>:'(0,0,0,0,0,0,0,0,0,0,0,0,0,0,0,0,0,0,0,0,0,0,A38,0,0,0,0,0,0,0)~
';
    'VSS'<1180>:'(0,0,0,0,0,0,0,0,0,0,0,0,0,0,0,0,0,0,0,0,0,0,B25,0,0,0,0,0,0,0)~
';
    'VSS'<1179>:'(0,0,0,0,0,0,0,0,0,0,0,0,0,0,0,0,0,0,0,0,0,0,B31,0,0,0,0,0,0,0)~
';
    'VSS'<1178>:'(0,0,0,0,0,0,0,0,0,0,0,0,0,0,0,0,0,0,0,0,0,0,B37,0,0,0,0,0,0,0)~
';
    'VSS'<1177>:'(0,0,0,0,0,0,0,0,0,0,0,0,0,0,0,0,0,0,0,0,0,0,B71,0,0,0,0,0,0,0)~
';
    'VSS'<1176>:'(0,0,0,0,0,0,0,0,0,0,0,0,0,0,0,0,0,0,0,0,0,0,B75,0,0,0,0,0,0,0)~
';
    'VSS'<1175>:'(0,0,0,0,0,0,0,0,0,0,0,0,0,0,0,0,0,0,0,0,0,0,C8,0,0,0,0,0,0,0)';
    'VSS'<1174>:'(0,0,0,0,0,0,0,0,0,0,0,0,0,0,0,0,0,0,0,0,0,0,C10,0,0,0,0,0,0,0)~
';
    'VSS'<1173>:'(0,0,0,0,0,0,0,0,0,0,0,0,0,0,0,0,0,0,0,0,0,0,C12,0,0,0,0,0,0,0)~
';
    'VSS'<1172>:'(0,0,0,0,0,0,0,0,0,0,0,0,0,0,0,0,0,0,0,0,0,0,C14,0,0,0,0,0,0,0)~
';
    'VSS'<1171>:'(0,0,0,0,0,0,0,0,0,0,0,0,0,0,0,0,0,0,0,0,0,0,C16,0,0,0,0,0,0,0)~
';
    'VSS'<1170>:'(0,0,0,0,0,0,0,0,0,0,0,0,0,0,0,0,0,0,0,0,0,0,C76,0,0,0,0,0,0,0)~
';
    'VSS'<1169>:'(0,0,0,0,0,0,0,0,0,0,0,0,0,0,0,0,0,0,0,0,0,0,C78,0,0,0,0,0,0,0)~
';
    'VSS'<1168>:'(0,0,0,0,0,0,0,0,0,0,0,0,0,0,0,0,0,0,0,0,0,0,CM27,0,0,0,0,0,0,0~
)';
    'VSS'<1167>:'(0,0,0,0,0,0,0,0,0,0,0,0,0,0,0,0,0,0,0,0,0,0,D11,0,0,0,0,0,0,0)~
';
    'VSS'<1166>:'(0,0,0,0,0,0,0,0,0,0,0,0,0,0,0,0,0,0,0,0,0,0,D13,0,0,0,0,0,0,0)~
';
    'VSS'<1165>:'(0,0,0,0,0,0,0,0,0,0,0,0,0,0,0,0,0,0,0,0,0,0,D25,0,0,0,0,0,0,0)~
';
    'VSS'<1164>:'(0,0,0,0,0,0,0,0,0,0,0,0,0,0,0,0,0,0,0,0,0,0,D27,0,0,0,0,0,0,0)~
';
    'VSS'<1163>:'(0,0,0,0,0,0,0,0,0,0,0,0,0,0,0,0,0,0,0,0,0,0,D29,0,0,0,0,0,0,0)~
';
    'VSS'<1162>:'(0,0,0,0,0,0,0,0,0,0,0,0,0,0,0,0,0,0,0,0,0,0,D31,0,0,0,0,0,0,0)~
';
    'VSS'<1161>:'(0,0,0,0,0,0,0,0,0,0,0,0,0,0,0,0,0,0,0,0,0,0,D33,0,0,0,0,0,0,0)~
';
    'VSS'<1160>:'(0,0,0,0,0,0,0,0,0,0,0,0,0,0,0,0,0,0,0,0,0,0,D35,0,0,0,0,0,0,0)~
';
    'VSS'<1159>:'(0,0,0,0,0,0,0,0,0,0,0,0,0,0,0,0,0,0,0,0,0,0,D37,0,0,0,0,0,0,0)~
';
    'VSS'<1158>:'(0,0,0,0,0,0,0,0,0,0,0,0,0,0,0,0,0,0,0,0,0,0,D39,0,0,0,0,0,0,0)~
';
    'VSS'<1157>:'(0,0,0,0,0,0,0,0,0,0,0,0,0,0,0,0,0,0,0,0,0,0,D41,0,0,0,0,0,0,0)~
';
    'VSS'<1156>:'(0,0,0,0,0,0,0,0,0,0,0,0,0,0,0,0,0,0,0,0,0,0,D43,0,0,0,0,0,0,0)~
';
    'VSS'<1155>:'(0,0,0,0,0,0,0,0,0,0,0,0,0,0,0,0,0,0,0,0,0,0,D77,0,0,0,0,0,0,0)~
';
    'VSS'<1154>:'(0,0,0,0,0,0,0,0,0,0,0,0,0,0,0,0,0,0,0,0,0,0,E6,0,0,0,0,0,0,0)';
    'VSS'<1153>:'(0,0,0,0,0,0,0,0,0,0,0,0,0,0,0,0,0,0,0,0,0,0,E8,0,0,0,0,0,0,0)';
    'VSS'<1152>:'(0,0,0,0,0,0,0,0,0,0,0,0,0,0,0,0,0,0,0,0,0,0,E16,0,0,0,0,0,0,0)~
';
    'VSS'<1151>:'(0,0,0,0,0,0,0,0,0,0,0,0,0,0,0,0,0,0,0,0,0,0,E18,0,0,0,0,0,0,0)~
';
    'VSS'<1150>:'(0,0,0,0,0,0,0,0,0,0,0,0,0,0,0,0,0,0,0,0,0,0,E20,0,0,0,0,0,0,0)~
';
    'VSS'<1149>:'(0,0,0,0,0,0,0,0,0,0,0,0,0,0,0,0,0,0,0,0,0,0,E22,0,0,0,0,0,0,0)~
';
    'VSS'<1148>:'(0,0,0,0,0,0,0,0,0,0,0,0,0,0,0,0,0,0,0,0,0,0,E72,0,0,0,0,0,0,0)~
';
    'VSS'<1147>:'(0,0,0,0,0,0,0,0,0,0,0,0,0,0,0,0,0,0,0,0,0,0,E74,0,0,0,0,0,0,0)~
';
    'VSS'<1146>:'(0,0,0,0,0,0,0,0,0,0,0,0,0,0,0,0,0,0,0,0,0,0,E76,0,0,0,0,0,0,0)~
';
    'VSS'<1145>:'(0,0,0,0,0,0,0,0,0,0,0,0,0,0,0,0,0,0,0,0,0,0,F5,0,0,0,0,0,0,0)';
    'VSS'<1144>:'(0,0,0,0,0,0,0,0,0,0,0,0,0,0,0,0,0,0,0,0,0,0,F17,0,0,0,0,0,0,0)~
';
    'VSS'<1143>:'(0,0,0,0,0,0,0,0,0,0,0,0,0,0,0,0,0,0,0,0,0,0,F19,0,0,0,0,0,0,0)~
';
    'VSS'<1142>:'(0,0,0,0,0,0,0,0,0,0,0,0,0,0,0,0,0,0,0,0,0,0,F25,0,0,0,0,0,0,0)~
';
    'VSS'<1141>:'(0,0,0,0,0,0,0,0,0,0,0,0,0,0,0,0,0,0,0,0,0,0,F31,0,0,0,0,0,0,0)~
';
    'VSS'<1140>:'(0,0,0,0,0,0,0,0,0,0,0,0,0,0,0,0,0,0,0,0,0,0,F37,0,0,0,0,0,0,0)~
';
    'VSS'<1139>:'(0,0,0,0,0,0,0,0,0,0,0,0,0,0,0,0,0,0,0,0,0,0,F43,0,0,0,0,0,0,0)~
';
    'VSS'<1138>:'(0,0,0,0,0,0,0,0,0,0,0,0,0,0,0,0,0,0,0,0,0,0,F67,0,0,0,0,0,0,0)~
';
    'VSS'<1137>:'(0,0,0,0,0,0,0,0,0,0,0,0,0,0,0,0,0,0,0,0,0,0,F69,0,0,0,0,0,0,0)~
';
    'VSS'<1136>:'(0,0,0,0,0,0,0,0,0,0,0,0,0,0,0,0,0,0,0,0,0,0,G4,0,0,0,0,0,0,0)';
    'VSS'<1135>:'(0,0,0,0,0,0,0,0,0,0,0,0,0,0,0,0,0,0,0,0,0,0,G8,0,0,0,0,0,0,0)';
    'VSS'<1134>:'(0,0,0,0,0,0,0,0,0,0,0,0,0,0,0,0,0,0,0,0,0,0,G22,0,0,0,0,0,0,0)~
';
    'VSS'<1133>:'(0,0,0,0,0,0,0,0,0,0,0,0,0,0,0,0,0,0,0,0,0,0,G24,0,0,0,0,0,0,0)~
';
    'VSS'<1132>:'(0,0,0,0,0,0,0,0,0,0,0,0,0,0,0,0,0,0,0,0,0,0,G26,0,0,0,0,0,0,0)~
';
    'VSS'<1131>:'(0,0,0,0,0,0,0,0,0,0,0,0,0,0,0,0,0,0,0,0,0,0,G30,0,0,0,0,0,0,0)~
';
    'VSS'<1130>:'(0,0,0,0,0,0,0,0,0,0,0,0,0,0,0,0,0,0,0,0,0,0,G32,0,0,0,0,0,0,0)~
';
    'VSS'<1129>:'(0,0,0,0,0,0,0,0,0,0,0,0,0,0,0,0,0,0,0,0,0,0,G36,0,0,0,0,0,0,0)~
';
    'VSS'<1128>:'(0,0,0,0,0,0,0,0,0,0,0,0,0,0,0,0,0,0,0,0,0,0,G38,0,0,0,0,0,0,0)~
';
    'VSS'<1127>:'(0,0,0,0,0,0,0,0,0,0,0,0,0,0,0,0,0,0,0,0,0,0,G42,0,0,0,0,0,0,0)~
';
    'VSS'<1126>:'(0,0,0,0,0,0,0,0,0,0,0,0,0,0,0,0,0,0,0,0,0,0,G66,0,0,0,0,0,0,0)~
';
    'VSS'<1125>:'(0,0,0,0,0,0,0,0,0,0,0,0,0,0,0,0,0,0,0,0,0,0,G70,0,0,0,0,0,0,0)~
';
    'VSS'<1124>:'(0,0,0,0,0,0,0,0,0,0,0,0,0,0,0,0,0,0,0,0,0,0,G76,0,0,0,0,0,0,0)~
';
    'VSS'<1123>:'(0,0,0,0,0,0,0,0,0,0,0,0,0,0,0,0,0,0,0,0,0,0,G78,0,0,0,0,0,0,0)~
';
    'VSS'<1122>:'(0,0,0,0,0,0,0,0,0,0,0,0,0,0,0,0,0,0,0,0,0,0,G80,0,0,0,0,0,0,0)~
';
    'VSS'<1121>:'(0,0,0,0,0,0,0,0,0,0,0,0,0,0,0,0,0,0,0,0,0,0,G82,0,0,0,0,0,0,0)~
';
    'VSS'<1120>:'(0,0,0,0,0,0,0,0,0,0,0,0,0,0,0,0,0,0,0,0,0,0,H3,0,0,0,0,0,0,0)';
    'VSS'<1119>:'(0,0,0,0,0,0,0,0,0,0,0,0,0,0,0,0,0,0,0,0,0,0,H11,0,0,0,0,0,0,0)~
';
    'VSS'<1118>:'(0,0,0,0,0,0,0,0,0,0,0,0,0,0,0,0,0,0,0,0,0,0,H25,0,0,0,0,0,0,0)~
';
    'VSS'<1117>:'(0,0,0,0,0,0,0,0,0,0,0,0,0,0,0,0,0,0,0,0,0,0,H27,0,0,0,0,0,0,0)~
';
    'VSS'<1116>:'(0,0,0,0,0,0,0,0,0,0,0,0,0,0,0,0,0,0,0,0,0,0,H29,0,0,0,0,0,0,0)~
';
    'VSS'<1115>:'(0,0,0,0,0,0,0,0,0,0,0,0,0,0,0,0,0,0,0,0,0,0,H31,0,0,0,0,0,0,0)~
';
    'VSS'<1114>:'(0,0,0,0,0,0,0,0,0,0,0,0,0,0,0,0,0,0,0,0,0,0,H33,0,0,0,0,0,0,0)~
';
    'VSS'<1113>:'(0,0,0,0,0,0,0,0,0,0,0,0,0,0,0,0,0,0,0,0,0,0,H35,0,0,0,0,0,0,0)~
';
    'VSS'<1112>:'(0,0,0,0,0,0,0,0,0,0,0,0,0,0,0,0,0,0,0,0,0,0,H37,0,0,0,0,0,0,0)~
';
    'VSS'<1111>:'(0,0,0,0,0,0,0,0,0,0,0,0,0,0,0,0,0,0,0,0,0,0,H39,0,0,0,0,0,0,0)~
';
    'VSS'<1110>:'(0,0,0,0,0,0,0,0,0,0,0,0,0,0,0,0,0,0,0,0,0,0,H41,0,0,0,0,0,0,0)~
';
    'VSS'<1109>:'(0,0,0,0,0,0,0,0,0,0,0,0,0,0,0,0,0,0,0,0,0,0,H65,0,0,0,0,0,0,0)~
';
    'VSS'<1108>:'(0,0,0,0,0,0,0,0,0,0,0,0,0,0,0,0,0,0,0,0,0,0,H71,0,0,0,0,0,0,0)~
';
    'VSS'<1107>:'(0,0,0,0,0,0,0,0,0,0,0,0,0,0,0,0,0,0,0,0,0,0,H75,0,0,0,0,0,0,0)~
';
    'VSS'<1106>:'(0,0,0,0,0,0,0,0,0,0,0,0,0,0,0,0,0,0,0,0,0,0,DN44,0,0,0,0,0,0,0~
)';
    'VSS'<1105>:'(0,0,0,0,0,0,0,0,0,0,0,0,0,0,0,0,0,0,0,0,0,0,J4,0,0,0,0,0,0,0)';
    'VSS'<1104>:'(0,0,0,0,0,0,0,0,0,0,0,0,0,0,0,0,0,0,0,0,0,0,J12,0,0,0,0,0,0,0)~
';
    'VSS'<1103>:'(0,0,0,0,0,0,0,0,0,0,0,0,0,0,0,0,0,0,0,0,0,0,J14,0,0,0,0,0,0,0)~
';
    'VSS'<1102>:'(0,0,0,0,0,0,0,0,0,0,0,0,0,0,0,0,0,0,0,0,0,0,J22,0,0,0,0,0,0,0)~
';
    'VSS'<1101>:'(0,0,0,0,0,0,0,0,0,0,0,0,0,0,0,0,0,0,0,0,0,0,J26,0,0,0,0,0,0,0)~
';
    'VSS'<1100>:'(0,0,0,0,0,0,0,0,0,0,0,0,0,0,0,0,0,0,0,0,0,0,J28,0,0,0,0,0,0,0)~
';
    'VSS'<1099>:'(0,0,0,0,0,0,0,0,0,0,0,0,0,0,0,0,0,0,0,0,0,0,J32,0,0,0,0,0,0,0)~
';
    'VSS'<1098>:'(0,0,0,0,0,0,0,0,0,0,0,0,0,0,0,0,0,0,0,0,0,0,J34,0,0,0,0,0,0,0)~
';
    'VSS'<1097>:'(0,0,0,0,0,0,0,0,0,0,0,0,0,0,0,0,0,0,0,0,0,0,J38,0,0,0,0,0,0,0)~
';
    'VSS'<1096>:'(0,0,0,0,0,0,0,0,0,0,0,0,0,0,0,0,0,0,0,0,0,0,J40,0,0,0,0,0,0,0)~
';
    'VSS'<1095>:'(0,0,0,0,0,0,0,0,0,0,0,0,0,0,0,0,0,0,0,0,0,0,J72,0,0,0,0,0,0,0)~
';
    'VSS'<1094>:'(0,0,0,0,0,0,0,0,0,0,0,0,0,0,0,0,0,0,0,0,0,0,J74,0,0,0,0,0,0,0)~
';
    'VSS'<1093>:'(0,0,0,0,0,0,0,0,0,0,0,0,0,0,0,0,0,0,0,0,0,0,0,J76,0,0,0,0,0,0)~
';
    'VSS'<1092>:'(0,0,0,0,0,0,0,0,0,0,0,0,0,0,0,0,0,0,0,0,0,0,0,J82,0,0,0,0,0,0)~
';
    'VSS'<1091>:'(0,0,0,0,0,0,0,0,0,0,0,0,0,0,0,0,0,0,0,0,0,0,0,J84,0,0,0,0,0,0)~
';
    'VSS'<1090>:'(0,0,0,0,0,0,0,0,0,0,0,0,0,0,0,0,0,0,0,0,0,0,0,K1,0,0,0,0,0,0)';
    'VSS'<1089>:'(0,0,0,0,0,0,0,0,0,0,0,0,0,0,0,0,0,0,0,0,0,0,0,K11,0,0,0,0,0,0)~
';
    'VSS'<1088>:'(0,0,0,0,0,0,0,0,0,0,0,0,0,0,0,0,0,0,0,0,0,0,0,K13,0,0,0,0,0,0)~
';
    'VSS'<1087>:'(0,0,0,0,0,0,0,0,0,0,0,0,0,0,0,0,0,0,0,0,0,0,0,K17,0,0,0,0,0,0)~
';
    'VSS'<1086>:'(0,0,0,0,0,0,0,0,0,0,0,0,0,0,0,0,0,0,0,0,0,0,0,DB7,0,0,0,0,0,0)~
';
    'VSS'<1085>:'(0,0,0,0,0,0,0,0,0,0,0,0,0,0,0,0,0,0,0,0,0,0,0,K27,0,0,0,0,0,0)~
';
    'VSS'<1084>:'(0,0,0,0,0,0,0,0,0,0,0,0,0,0,0,0,0,0,0,0,0,0,0,K33,0,0,0,0,0,0)~
';
    'VSS'<1083>:'(0,0,0,0,0,0,0,0,0,0,0,0,0,0,0,0,0,0,0,0,0,0,0,K39,0,0,0,0,0,0)~
';
    'VSS'<1082>:'(0,0,0,0,0,0,0,0,0,0,0,0,0,0,0,0,0,0,0,0,0,0,0,K65,0,0,0,0,0,0)~
';
    'VSS'<1081>:'(0,0,0,0,0,0,0,0,0,0,0,0,0,0,0,0,0,0,0,0,0,0,0,K67,0,0,0,0,0,0)~
';
    'VSS'<1080>:'(0,0,0,0,0,0,0,0,0,0,0,0,0,0,0,0,0,0,0,0,0,0,0,K69,0,0,0,0,0,0)~
';
    'VSS'<1079>:'(0,0,0,0,0,0,0,0,0,0,0,0,0,0,0,0,0,0,0,0,0,0,0,K71,0,0,0,0,0,0)~
';
    'VSS'<1078>:'(0,0,0,0,0,0,0,0,0,0,0,0,0,0,0,0,0,0,0,0,0,0,0,K73,0,0,0,0,0,0)~
';
    'VSS'<1077>:'(0,0,0,0,0,0,0,0,0,0,0,0,0,0,0,0,0,0,0,0,0,0,0,K77,0,0,0,0,0,0)~
';
    'VSS'<1076>:'(0,0,0,0,0,0,0,0,0,0,0,0,0,0,0,0,0,0,0,0,0,0,0,K81,0,0,0,0,0,0)~
';
    'VSS'<1075>:'(0,0,0,0,0,0,0,0,0,0,0,0,0,0,0,0,0,0,0,0,0,0,0,K83,0,0,0,0,0,0)~
';
    'VSS'<1074>:'(0,0,0,0,0,0,0,0,0,0,0,0,0,0,0,0,0,0,0,0,0,0,0,K85,0,0,0,0,0,0)~
';
    'VSS'<1073>:'(0,0,0,0,0,0,0,0,0,0,0,0,0,0,0,0,0,0,0,0,0,0,0,L10,0,0,0,0,0,0)~
';
    'VSS'<1072>:'(0,0,0,0,0,0,0,0,0,0,0,0,0,0,0,0,0,0,0,0,0,0,0,L2,0,0,0,0,0,0)';
    'VSS'<1071>:'(0,0,0,0,0,0,0,0,0,0,0,0,0,0,0,0,0,0,0,0,0,0,0,L6,0,0,0,0,0,0)';
    'VSS'<1070>:'(0,0,0,0,0,0,0,0,0,0,0,0,0,0,0,0,0,0,0,0,0,0,0,L20,0,0,0,0,0,0)~
';
    'VSS'<1069>:'(0,0,0,0,0,0,0,0,0,0,0,0,0,0,0,0,0,0,0,0,0,0,0,L22,0,0,0,0,0,0)~
';
    'VSS'<1068>:'(0,0,0,0,0,0,0,0,0,0,0,0,0,0,0,0,0,0,0,0,0,0,0,L72,0,0,0,0,0,0)~
';
    'VSS'<1067>:'(0,0,0,0,0,0,0,0,0,0,0,0,0,0,0,0,0,0,0,0,0,0,0,L78,0,0,0,0,0,0)~
';
    'VSS'<1066>:'(0,0,0,0,0,0,0,0,0,0,0,0,0,0,0,0,0,0,0,0,0,0,0,L80,0,0,0,0,0,0)~
';
    'VSS'<1065>:'(0,0,0,0,0,0,0,0,0,0,0,0,0,0,0,0,0,0,0,0,0,0,0,L82,0,0,0,0,0,0)~
';
    'VSS'<1064>:'(0,0,0,0,0,0,0,0,0,0,0,0,0,0,0,0,0,0,0,0,0,0,0,BT9,0,0,0,0,0,0)~
';
    'VSS'<1063>:'(0,0,0,0,0,0,0,0,0,0,0,0,0,0,0,0,0,0,0,0,0,0,0,CT7,0,0,0,0,0,0)~
';
    'VSS'<1062>:'(0,0,0,0,0,0,0,0,0,0,0,0,0,0,0,0,0,0,0,0,0,0,0,M15,0,0,0,0,0,0)~
';
    'VSS'<1061>:'(0,0,0,0,0,0,0,0,0,0,0,0,0,0,0,0,0,0,0,0,0,0,0,M17,0,0,0,0,0,0)~
';
    'VSS'<1060>:'(0,0,0,0,0,0,0,0,0,0,0,0,0,0,0,0,0,0,0,0,0,0,0,M19,0,0,0,0,0,0)~
';
    'VSS'<1059>:'(0,0,0,0,0,0,0,0,0,0,0,0,0,0,0,0,0,0,0,0,0,0,0,M23,0,0,0,0,0,0)~
';
    'VSS'<1058>:'(0,0,0,0,0,0,0,0,0,0,0,0,0,0,0,0,0,0,0,0,0,0,0,M25,0,0,0,0,0,0)~
';
    'VSS'<1057>:'(0,0,0,0,0,0,0,0,0,0,0,0,0,0,0,0,0,0,0,0,0,0,0,M27,0,0,0,0,0,0)~
';
    'VSS'<1056>:'(0,0,0,0,0,0,0,0,0,0,0,0,0,0,0,0,0,0,0,0,0,0,0,M29,0,0,0,0,0,0)~
';
    'VSS'<1055>:'(0,0,0,0,0,0,0,0,0,0,0,0,0,0,0,0,0,0,0,0,0,0,0,M31,0,0,0,0,0,0)~
';
    'VSS'<1054>:'(0,0,0,0,0,0,0,0,0,0,0,0,0,0,0,0,0,0,0,0,0,0,0,M33,0,0,0,0,0,0)~
';
    'VSS'<1053>:'(0,0,0,0,0,0,0,0,0,0,0,0,0,0,0,0,0,0,0,0,0,0,0,M35,0,0,0,0,0,0)~
';
    'VSS'<1052>:'(0,0,0,0,0,0,0,0,0,0,0,0,0,0,0,0,0,0,0,0,0,0,0,M37,0,0,0,0,0,0)~
';
    'VSS'<1051>:'(0,0,0,0,0,0,0,0,0,0,0,0,0,0,0,0,0,0,0,0,0,0,0,M39,0,0,0,0,0,0)~
';
    'VSS'<1050>:'(0,0,0,0,0,0,0,0,0,0,0,0,0,0,0,0,0,0,0,0,0,0,0,M41,0,0,0,0,0,0)~
';
    'VSS'<1049>:'(0,0,0,0,0,0,0,0,0,0,0,0,0,0,0,0,0,0,0,0,0,0,0,M43,0,0,0,0,0,0)~
';
    'VSS'<1048>:'(0,0,0,0,0,0,0,0,0,0,0,0,0,0,0,0,0,0,0,0,0,0,0,M65,0,0,0,0,0,0)~
';
    'VSS'<1047>:'(0,0,0,0,0,0,0,0,0,0,0,0,0,0,0,0,0,0,0,0,0,0,0,M71,0,0,0,0,0,0)~
';
    'VSS'<1046>:'(0,0,0,0,0,0,0,0,0,0,0,0,0,0,0,0,0,0,0,0,0,0,0,M79,0,0,0,0,0,0)~
';
    'VSS'<1045>:'(0,0,0,0,0,0,0,0,0,0,0,0,0,0,0,0,0,0,0,0,0,0,0,M83,0,0,0,0,0,0)~
';
    'VSS'<1044>:'(0,0,0,0,0,0,0,0,0,0,0,0,0,0,0,0,0,0,0,0,0,0,0,M85,0,0,0,0,0,0)~
';
    'VSS'<1043>:'(0,0,0,0,0,0,0,0,0,0,0,0,0,0,0,0,0,0,0,0,0,0,0,DM19,0,0,0,0,0,0~
)';
    'VSS'<1042>:'(0,0,0,0,0,0,0,0,0,0,0,0,0,0,0,0,0,0,0,0,0,0,0,N20,0,0,0,0,0,0)~
';
    'VSS'<1041>:'(0,0,0,0,0,0,0,0,0,0,0,0,0,0,0,0,0,0,0,0,0,0,0,N22,0,0,0,0,0,0)~
';
    'VSS'<1040>:'(0,0,0,0,0,0,0,0,0,0,0,0,0,0,0,0,0,0,0,0,0,0,0,N6,0,0,0,0,0,0)';
    'VSS'<1039>:'(0,0,0,0,0,0,0,0,0,0,0,0,0,0,0,0,0,0,0,0,0,0,0,N66,0,0,0,0,0,0)~
';
    'VSS'<1038>:'(0,0,0,0,0,0,0,0,0,0,0,0,0,0,0,0,0,0,0,0,0,0,0,N70,0,0,0,0,0,0)~
';
    'VSS'<1037>:'(0,0,0,0,0,0,0,0,0,0,0,0,0,0,0,0,0,0,0,0,0,0,0,N72,0,0,0,0,0,0)~
';
    'VSS'<1036>:'(0,0,0,0,0,0,0,0,0,0,0,0,0,0,0,0,0,0,0,0,0,0,0,N74,0,0,0,0,0,0)~
';
    'VSS'<1035>:'(0,0,0,0,0,0,0,0,0,0,0,0,0,0,0,0,0,0,0,0,0,0,0,N76,0,0,0,0,0,0)~
';
    'VSS'<1034>:'(0,0,0,0,0,0,0,0,0,0,0,0,0,0,0,0,0,0,0,0,0,0,0,N78,0,0,0,0,0,0)~
';
    'VSS'<1033>:'(0,0,0,0,0,0,0,0,0,0,0,0,0,0,0,0,0,0,0,0,0,0,0,N4,0,0,0,0,0,0)';
    'VSS'<1032>:'(0,0,0,0,0,0,0,0,0,0,0,0,0,0,0,0,0,0,0,0,0,0,0,N8,0,0,0,0,0,0)';
    'VSS'<1031>:'(0,0,0,0,0,0,0,0,0,0,0,0,0,0,0,0,0,0,0,0,0,0,0,P11,0,0,0,0,0,0)~
';
    'VSS'<1030>:'(0,0,0,0,0,0,0,0,0,0,0,0,0,0,0,0,0,0,0,0,0,0,0,P15,0,0,0,0,0,0)~
';
    'VSS'<1029>:'(0,0,0,0,0,0,0,0,0,0,0,0,0,0,0,0,0,0,0,0,0,0,0,P27,0,0,0,0,0,0)~
';
    'VSS'<1028>:'(0,0,0,0,0,0,0,0,0,0,0,0,0,0,0,0,0,0,0,0,0,0,0,P33,0,0,0,0,0,0)~
';
    'VSS'<1027>:'(0,0,0,0,0,0,0,0,0,0,0,0,0,0,0,0,0,0,0,0,0,0,0,P39,0,0,0,0,0,0)~
';
    'VSS'<1026>:'(0,0,0,0,0,0,0,0,0,0,0,0,0,0,0,0,0,0,0,0,0,0,0,P67,0,0,0,0,0,0)~
';
    'VSS'<1025>:'(0,0,0,0,0,0,0,0,0,0,0,0,0,0,0,0,0,0,0,0,0,0,0,P69,0,0,0,0,0,0)~
';
    'VSS'<1024>:'(0,0,0,0,0,0,0,0,0,0,0,0,0,0,0,0,0,0,0,0,0,0,0,P71,0,0,0,0,0,0)~
';
    'VSS'<1023>:'(0,0,0,0,0,0,0,0,0,0,0,0,0,0,0,0,0,0,0,0,0,0,0,P81,0,0,0,0,0,0)~
';
    'VSS'<1022>:'(0,0,0,0,0,0,0,0,0,0,0,0,0,0,0,0,0,0,0,0,0,0,0,P83,0,0,0,0,0,0)~
';
    'VSS'<1021>:'(0,0,0,0,0,0,0,0,0,0,0,0,0,0,0,0,0,0,0,0,0,0,0,R14,0,0,0,0,0,0)~
';
    'VSS'<1020>:'(0,0,0,0,0,0,0,0,0,0,0,0,0,0,0,0,0,0,0,0,0,0,0,R18,0,0,0,0,0,0)~
';
    'VSS'<1019>:'(0,0,0,0,0,0,0,0,0,0,0,0,0,0,0,0,0,0,0,0,0,0,0,R2,0,0,0,0,0,0)';
    'VSS'<1018>:'(0,0,0,0,0,0,0,0,0,0,0,0,0,0,0,0,0,0,0,0,0,0,0,R4,0,0,0,0,0,0)';
    'VSS'<1017>:'(0,0,0,0,0,0,0,0,0,0,0,0,0,0,0,0,0,0,0,0,0,0,0,R22,0,0,0,0,0,0)~
';
    'VSS'<1016>:'(0,0,0,0,0,0,0,0,0,0,0,0,0,0,0,0,0,0,0,0,0,0,0,R26,0,0,0,0,0,0)~
';
    'VSS'<1015>:'(0,0,0,0,0,0,0,0,0,0,0,0,0,0,0,0,0,0,0,0,0,0,0,R28,0,0,0,0,0,0)~
';
    'VSS'<1014>:'(0,0,0,0,0,0,0,0,0,0,0,0,0,0,0,0,0,0,0,0,0,0,0,R32,0,0,0,0,0,0)~
';
    'VSS'<1013>:'(0,0,0,0,0,0,0,0,0,0,0,0,0,0,0,0,0,0,0,0,0,0,0,R34,0,0,0,0,0,0)~
';
    'VSS'<1012>:'(0,0,0,0,0,0,0,0,0,0,0,0,0,0,0,0,0,0,0,0,0,0,0,R38,0,0,0,0,0,0)~
';
    'VSS'<1011>:'(0,0,0,0,0,0,0,0,0,0,0,0,0,0,0,0,0,0,0,0,0,0,0,R40,0,0,0,0,0,0)~
';
    'VSS'<1010>:'(0,0,0,0,0,0,0,0,0,0,0,0,0,0,0,0,0,0,0,0,0,0,0,R68,0,0,0,0,0,0)~
';
    'VSS'<1009>:'(0,0,0,0,0,0,0,0,0,0,0,0,0,0,0,0,0,0,0,0,0,0,0,R72,0,0,0,0,0,0)~
';
    'VSS'<1008>:'(0,0,0,0,0,0,0,0,0,0,0,0,0,0,0,0,0,0,0,0,0,0,0,R78,0,0,0,0,0,0)~
';
    'VSS'<1007>:'(0,0,0,0,0,0,0,0,0,0,0,0,0,0,0,0,0,0,0,0,0,0,0,R86,0,0,0,0,0,0)~
';
    'VSS'<1006>:'(0,0,0,0,0,0,0,0,0,0,0,0,0,0,0,0,0,0,0,0,0,0,0,T13,0,0,0,0,0,0)~
';
    'VSS'<1005>:'(0,0,0,0,0,0,0,0,0,0,0,0,0,0,0,0,0,0,0,0,0,0,0,T17,0,0,0,0,0,0)~
';
    'VSS'<1004>:'(0,0,0,0,0,0,0,0,0,0,0,0,0,0,0,0,0,0,0,0,0,0,0,T25,0,0,0,0,0,0)~
';
    'VSS'<1003>:'(0,0,0,0,0,0,0,0,0,0,0,0,0,0,0,0,0,0,0,0,0,0,0,T29,0,0,0,0,0,0)~
';
    'VSS'<1002>:'(0,0,0,0,0,0,0,0,0,0,0,0,0,0,0,0,0,0,0,0,0,0,0,T31,0,0,0,0,0,0)~
';
    'VSS'<1001>:'(0,0,0,0,0,0,0,0,0,0,0,0,0,0,0,0,0,0,0,0,0,0,0,T35,0,0,0,0,0,0)~
';
    'VSS'<1000>:'(0,0,0,0,0,0,0,0,0,0,0,0,0,0,0,0,0,0,0,0,0,0,0,T37,0,0,0,0,0,0)~
';
    'VSS'<999>:'(0,0,0,0,0,0,0,0,0,0,0,0,0,0,0,0,0,0,0,0,0,0,0,T41,0,0,0,0,0,0)';
    'VSS'<998>:'(0,0,0,0,0,0,0,0,0,0,0,0,0,0,0,0,0,0,0,0,0,0,0,T65,0,0,0,0,0,0)';
    'VSS'<997>:'(0,0,0,0,0,0,0,0,0,0,0,0,0,0,0,0,0,0,0,0,0,0,0,T73,0,0,0,0,0,0)';
    'VSS'<996>:'(0,0,0,0,0,0,0,0,0,0,0,0,0,0,0,0,0,0,0,0,0,0,0,T77,0,0,0,0,0,0)';
    'VSS'<995>:'(0,0,0,0,0,0,0,0,0,0,0,0,0,0,0,0,0,0,0,0,0,0,0,T83,0,0,0,0,0,0)';
    'VSS'<994>:'(0,0,0,0,0,0,0,0,0,0,0,0,0,0,0,0,0,0,0,0,0,0,0,T85,0,0,0,0,0,0)';
    'VSS'<993>:'(0,0,0,0,0,0,0,0,0,0,0,0,0,0,0,0,0,0,0,0,0,0,0,U2,0,0,0,0,0,0)';~

    'VSS'<992>:'(0,0,0,0,0,0,0,0,0,0,0,0,0,0,0,0,0,0,0,0,0,0,0,U4,0,0,0,0,0,0)';~

    'VSS'<991>:'(0,0,0,0,0,0,0,0,0,0,0,0,0,0,0,0,0,0,0,0,0,0,0,U6,0,0,0,0,0,0)';~

    'VSS'<990>:'(0,0,0,0,0,0,0,0,0,0,0,0,0,0,0,0,0,0,0,0,0,0,0,U20,0,0,0,0,0,0)';
    'VSS'<989>:'(0,0,0,0,0,0,0,0,0,0,0,0,0,0,0,0,0,0,0,0,0,0,0,U22,0,0,0,0,0,0)';
    'VSS'<988>:'(0,0,0,0,0,0,0,0,0,0,0,0,0,0,0,0,0,0,0,0,0,0,0,U24,0,0,0,0,0,0)';
    'VSS'<987>:'(0,0,0,0,0,0,0,0,0,0,0,0,0,0,0,0,0,0,0,0,0,0,0,U30,0,0,0,0,0,0)';
    'VSS'<986>:'(0,0,0,0,0,0,0,0,0,0,0,0,0,0,0,0,0,0,0,0,0,0,0,U36,0,0,0,0,0,0)';
    'VSS'<985>:'(0,0,0,0,0,0,0,0,0,0,0,0,0,0,0,0,0,0,0,0,0,0,0,U42,0,0,0,0,0,0)';
    'VSS'<984>:'(0,0,0,0,0,0,0,0,0,0,0,0,0,0,0,0,0,0,0,0,0,0,0,U68,0,0,0,0,0,0)';
    'VSS'<983>:'(0,0,0,0,0,0,0,0,0,0,0,0,0,0,0,0,0,0,0,0,0,0,0,U70,0,0,0,0,0,0)';
    'VSS'<982>:'(0,0,0,0,0,0,0,0,0,0,0,0,0,0,0,0,0,0,0,0,0,0,0,U74,0,0,0,0,0,0)';
    'VSS'<981>:'(0,0,0,0,0,0,0,0,0,0,0,0,0,0,0,0,0,0,0,0,0,0,0,U76,0,0,0,0,0,0)';
    'VSS'<980>:'(0,0,0,0,0,0,0,0,0,0,0,0,0,0,0,0,0,0,0,0,0,0,0,U78,0,0,0,0,0,0)';
    'VSS'<979>:'(0,0,0,0,0,0,0,0,0,0,0,0,0,0,0,0,0,0,0,0,0,0,0,U80,0,0,0,0,0,0)';
    'VSS'<978>:'(0,0,0,0,0,0,0,0,0,0,0,0,0,0,0,0,0,0,0,0,0,0,0,U86,0,0,0,0,0,0)';
    'VSS'<977>:'(0,0,0,0,0,0,0,0,0,0,0,0,0,0,0,0,0,0,0,0,0,0,0,V1,0,0,0,0,0,0)';~

    'VSS'<976>:'(0,0,0,0,0,0,0,0,0,0,0,0,0,0,0,0,0,0,0,0,0,0,0,V5,0,0,0,0,0,0)';~

    'VSS'<975>:'(0,0,0,0,0,0,0,0,0,0,0,0,0,0,0,0,0,0,0,0,0,0,0,V9,0,0,0,0,0,0)';~

    'VSS'<974>:'(0,0,0,0,0,0,0,0,0,0,0,0,0,0,0,0,0,0,0,0,0,0,0,V13,0,0,0,0,0,0)';
    'VSS'<973>:'(0,0,0,0,0,0,0,0,0,0,0,0,0,0,0,0,0,0,0,0,0,0,0,V15,0,0,0,0,0,0)';
    'VSS'<972>:'(0,0,0,0,0,0,0,0,0,0,0,0,0,0,0,0,0,0,0,0,0,0,0,V21,0,0,0,0,0,0)';
    'VSS'<971>:'(0,0,0,0,0,0,0,0,0,0,0,0,0,0,0,0,0,0,0,0,0,0,0,V23,0,0,0,0,0,0)';
    'VSS'<970>:'(0,0,0,0,0,0,0,0,0,0,0,0,0,0,0,0,0,0,0,0,0,0,0,V43,0,0,0,0,0,0)';
    'VSS'<969>:'(0,0,0,0,0,0,0,0,0,0,0,0,0,0,0,0,0,0,0,0,0,0,0,V73,0,0,0,0,0,0)';
    'VSS'<968>:'(0,0,0,0,0,0,0,0,0,0,0,0,0,0,0,0,0,0,0,0,0,0,0,V75,0,0,0,0,0,0)';
    'VSS'<967>:'(0,0,0,0,0,0,0,0,0,0,0,0,0,0,0,0,0,0,0,0,0,0,0,V77,0,0,0,0,0,0)';
    'VSS'<966>:'(0,0,0,0,0,0,0,0,0,0,0,0,0,0,0,0,0,0,0,0,0,0,0,V83,0,0,0,0,0,0)';
    'VSS'<965>:'(0,0,0,0,0,0,0,0,0,0,0,0,0,0,0,0,0,0,0,0,0,0,0,W8,0,0,0,0,0,0)';~

    'VSS'<964>:'(0,0,0,0,0,0,0,0,0,0,0,0,0,0,0,0,0,0,0,0,0,0,0,AC56,0,0,0,0,0,0)~
';
    'VSS'<963>:'(0,0,0,0,0,0,0,0,0,0,0,0,0,0,0,0,0,0,0,0,0,0,0,W12,0,0,0,0,0,0)';
    'VSS'<962>:'(0,0,0,0,0,0,0,0,0,0,0,0,0,0,0,0,0,0,0,0,0,0,0,W22,0,0,0,0,0,0)';
    'VSS'<961>:'(0,0,0,0,0,0,0,0,0,0,0,0,0,0,0,0,0,0,0,0,0,0,0,W24,0,0,0,0,0,0)';
    'VSS'<960>:'(0,0,0,0,0,0,0,0,0,0,0,0,0,0,0,0,0,0,0,0,0,0,0,W26,0,0,0,0,0,0)';
    'VSS'<959>:'(0,0,0,0,0,0,0,0,0,0,0,0,0,0,0,0,0,0,0,0,0,0,0,W28,0,0,0,0,0,0)';
    'VSS'<958>:'(0,0,0,0,0,0,0,0,0,0,0,0,0,0,0,0,0,0,0,0,0,0,0,W30,0,0,0,0,0,0)';
    'VSS'<957>:'(0,0,0,0,0,0,0,0,0,0,0,0,0,0,0,0,0,0,0,0,0,0,0,W32,0,0,0,0,0,0)';
    'VSS'<956>:'(0,0,0,0,0,0,0,0,0,0,0,0,0,0,0,0,0,0,0,0,0,0,0,W34,0,0,0,0,0,0)';
    'VSS'<955>:'(0,0,0,0,0,0,0,0,0,0,0,0,0,0,0,0,0,0,0,0,0,0,0,W36,0,0,0,0,0,0)';
    'VSS'<954>:'(0,0,0,0,0,0,0,0,0,0,0,0,0,0,0,0,0,0,0,0,0,0,0,W38,0,0,0,0,0,0)';
    'VSS'<953>:'(0,0,0,0,0,0,0,0,0,0,0,0,0,0,0,0,0,0,0,0,0,0,0,W40,0,0,0,0,0,0)';
    'VSS'<952>:'(0,0,0,0,0,0,0,0,0,0,0,0,0,0,0,0,0,0,0,0,0,0,0,W42,0,0,0,0,0,0)';
    'VSS'<951>:'(0,0,0,0,0,0,0,0,0,0,0,0,0,0,0,0,0,0,0,0,0,0,0,W68,0,0,0,0,0,0)';
    'VSS'<950>:'(0,0,0,0,0,0,0,0,0,0,0,0,0,0,0,0,0,0,0,0,0,0,0,W74,0,0,0,0,0,0)';
    'VSS'<949>:'(0,0,0,0,0,0,0,0,0,0,0,0,0,0,0,0,0,0,0,0,0,0,0,W78,0,0,0,0,0,0)';
    'VSS'<948>:'(0,0,0,0,0,0,0,0,0,0,0,0,0,0,0,0,0,0,0,0,0,0,0,W82,0,0,0,0,0,0)';
    'VSS'<947>:'(0,0,0,0,0,0,0,0,0,0,0,0,0,0,0,0,0,0,0,0,0,0,0,Y15,0,0,0,0,0,0)';
    'VSS'<946>:'(0,0,0,0,0,0,0,0,0,0,0,0,0,0,0,0,0,0,0,0,0,0,0,Y17,0,0,0,0,0,0)';
    'VSS'<945>:'(0,0,0,0,0,0,0,0,0,0,0,0,0,0,0,0,0,0,0,0,0,0,0,Y5,0,0,0,0,0,0)';~

    'VSS'<944>:'(0,0,0,0,0,0,0,0,0,0,0,0,0,0,0,0,0,0,0,0,0,0,0,Y67,0,0,0,0,0,0)';
    'VSS'<943>:'(0,0,0,0,0,0,0,0,0,0,0,0,0,0,0,0,0,0,0,0,0,0,0,Y7,0,0,0,0,0,0)';~

    'VSS'<942>:'(0,0,0,0,0,0,0,0,0,0,0,0,0,0,0,0,0,0,0,0,0,0,0,Y9,0,0,0,0,0,0)';~

    'VSS'<941>:'(0,0,0,0,0,0,0,0,0,0,0,0,0,0,0,0,0,0,0,0,0,0,0,Y71,0,0,0,0,0,0)';
    'VSS'<940>:'(0,0,0,0,0,0,0,0,0,0,0,0,0,0,0,0,0,0,0,0,0,0,0,Y73,0,0,0,0,0,0)';
    'VSS'<939>:'(0,0,0,0,0,0,0,0,0,0,0,0,0,0,0,0,0,0,0,0,0,0,0,Y79,0,0,0,0,0,0)';
    'VSS'<938>:'(0,0,0,0,0,0,0,0,0,0,0,0,0,0,0,0,0,0,0,0,0,0,0,Y81,0,0,0,0,0,0)';
    'VSS'<937>:'(0,0,0,0,0,0,0,0,0,0,0,0,0,0,0,0,0,0,0,0,0,0,0,Y83,0,0,0,0,0,0)';
    'VSS'<936>:'(0,0,0,0,0,0,0,0,0,0,0,0,0,0,0,0,0,0,0,0,0,0,0,Y85,0,0,0,0,0,0)';
    'VSS'<935>:'(0,0,0,0,0,0,0,0,0,0,0,0,0,0,0,0,0,0,0,0,0,0,0,AA4,0,0,0,0,0,0)';
    'VSS'<934>:'(0,0,0,0,0,0,0,0,0,0,0,0,0,0,0,0,0,0,0,0,0,0,0,AA16,0,0,0,0,0,0)~
';
    'VSS'<933>:'(0,0,0,0,0,0,0,0,0,0,0,0,0,0,0,0,0,0,0,0,0,0,0,0,AA18,0,0,0,0,0)~
';
    'VSS'<932>:'(0,0,0,0,0,0,0,0,0,0,0,0,0,0,0,0,0,0,0,0,0,0,0,0,AA22,0,0,0,0,0)~
';
    'VSS'<931>:'(0,0,0,0,0,0,0,0,0,0,0,0,0,0,0,0,0,0,0,0,0,0,0,0,AA24,0,0,0,0,0)~
';
    'VSS'<930>:'(0,0,0,0,0,0,0,0,0,0,0,0,0,0,0,0,0,0,0,0,0,0,0,0,AA30,0,0,0,0,0)~
';
    'VSS'<929>:'(0,0,0,0,0,0,0,0,0,0,0,0,0,0,0,0,0,0,0,0,0,0,0,0,AA36,0,0,0,0,0)~
';
    'VSS'<928>:'(0,0,0,0,0,0,0,0,0,0,0,0,0,0,0,0,0,0,0,0,0,0,0,0,AA42,0,0,0,0,0)~
';
    'VSS'<927>:'(0,0,0,0,0,0,0,0,0,0,0,0,0,0,0,0,0,0,0,0,0,0,0,0,AA64,0,0,0,0,0)~
';
    'VSS'<926>:'(0,0,0,0,0,0,0,0,0,0,0,0,0,0,0,0,0,0,0,0,0,0,0,0,AA66,0,0,0,0,0)~
';
    'VSS'<925>:'(0,0,0,0,0,0,0,0,0,0,0,0,0,0,0,0,0,0,0,0,0,0,0,0,AA68,0,0,0,0,0)~
';
    'VSS'<924>:'(0,0,0,0,0,0,0,0,0,0,0,0,0,0,0,0,0,0,0,0,0,0,0,0,AA76,0,0,0,0,0)~
';
    'VSS'<923>:'(0,0,0,0,0,0,0,0,0,0,0,0,0,0,0,0,0,0,0,0,0,0,0,0,AA78,0,0,0,0,0)~
';
    'VSS'<922>:'(0,0,0,0,0,0,0,0,0,0,0,0,0,0,0,0,0,0,0,0,0,0,0,0,AA80,0,0,0,0,0)~
';
    'VSS'<921>:'(0,0,0,0,0,0,0,0,0,0,0,0,0,0,0,0,0,0,0,0,0,0,0,0,AA82,0,0,0,0,0)~
';
    'VSS'<920>:'(0,0,0,0,0,0,0,0,0,0,0,0,0,0,0,0,0,0,0,0,0,0,0,0,AB1,0,0,0,0,0)';
    'VSS'<919>:'(0,0,0,0,0,0,0,0,0,0,0,0,0,0,0,0,0,0,0,0,0,0,0,0,AB5,0,0,0,0,0)';
    'VSS'<918>:'(0,0,0,0,0,0,0,0,0,0,0,0,0,0,0,0,0,0,0,0,0,0,0,0,AB11,0,0,0,0,0)~
';
    'VSS'<917>:'(0,0,0,0,0,0,0,0,0,0,0,0,0,0,0,0,0,0,0,0,0,0,0,0,AB21,0,0,0,0,0)~
';
    'VSS'<916>:'(0,0,0,0,0,0,0,0,0,0,0,0,0,0,0,0,0,0,0,0,0,0,0,0,AB23,0,0,0,0,0)~
';
    'VSS'<915>:'(0,0,0,0,0,0,0,0,0,0,0,0,0,0,0,0,0,0,0,0,0,0,0,0,AB25,0,0,0,0,0)~
';
    'VSS'<914>:'(0,0,0,0,0,0,0,0,0,0,0,0,0,0,0,0,0,0,0,0,0,0,0,0,AB29,0,0,0,0,0)~
';
    'VSS'<913>:'(0,0,0,0,0,0,0,0,0,0,0,0,0,0,0,0,0,0,0,0,0,0,0,0,AB31,0,0,0,0,0)~
';
    'VSS'<912>:'(0,0,0,0,0,0,0,0,0,0,0,0,0,0,0,0,0,0,0,0,0,0,0,0,AB35,0,0,0,0,0)~
';
    'VSS'<911>:'(0,0,0,0,0,0,0,0,0,0,0,0,0,0,0,0,0,0,0,0,0,0,0,0,AB37,0,0,0,0,0)~
';
    'VSS'<910>:'(0,0,0,0,0,0,0,0,0,0,0,0,0,0,0,0,0,0,0,0,0,0,0,0,AB41,0,0,0,0,0)~
';
    'VSS'<909>:'(0,0,0,0,0,0,0,0,0,0,0,0,0,0,0,0,0,0,0,0,0,0,0,0,AB65,0,0,0,0,0)~
';
    'VSS'<908>:'(0,0,0,0,0,0,0,0,0,0,0,0,0,0,0,0,0,0,0,0,0,0,0,0,AB69,0,0,0,0,0)~
';
    'VSS'<907>:'(0,0,0,0,0,0,0,0,0,0,0,0,0,0,0,0,0,0,0,0,0,0,0,0,AB73,0,0,0,0,0)~
';
    'VSS'<906>:'(0,0,0,0,0,0,0,0,0,0,0,0,0,0,0,0,0,0,0,0,0,0,0,0,AB79,0,0,0,0,0)~
';
    'VSS'<905>:'(0,0,0,0,0,0,0,0,0,0,0,0,0,0,0,0,0,0,0,0,0,0,0,0,AB83,0,0,0,0,0)~
';
    'VSS'<904>:'(0,0,0,0,0,0,0,0,0,0,0,0,0,0,0,0,0,0,0,0,0,0,0,0,AB85,0,0,0,0,0)~
';
    'VSS'<903>:'(0,0,0,0,0,0,0,0,0,0,0,0,0,0,0,0,0,0,0,0,0,0,0,0,AC18,0,0,0,0,0)~
';
    'VSS'<902>:'(0,0,0,0,0,0,0,0,0,0,0,0,0,0,0,0,0,0,0,0,0,0,0,0,AC22,0,0,0,0,0)~
';
    'VSS'<901>:'(0,0,0,0,0,0,0,0,0,0,0,0,0,0,0,0,0,0,0,0,0,0,0,0,AC26,0,0,0,0,0)~
';
    'VSS'<900>:'(0,0,0,0,0,0,0,0,0,0,0,0,0,0,0,0,0,0,0,0,0,0,0,0,AC28,0,0,0,0,0)~
';
    'VSS'<899>:'(0,0,0,0,0,0,0,0,0,0,0,0,0,0,0,0,0,0,0,0,0,0,0,0,AC32,0,0,0,0,0)~
';
    'VSS'<898>:'(0,0,0,0,0,0,0,0,0,0,0,0,0,0,0,0,0,0,0,0,0,0,0,0,AC34,0,0,0,0,0)~
';
    'VSS'<897>:'(0,0,0,0,0,0,0,0,0,0,0,0,0,0,0,0,0,0,0,0,0,0,0,0,AC38,0,0,0,0,0)~
';
    'VSS'<896>:'(0,0,0,0,0,0,0,0,0,0,0,0,0,0,0,0,0,0,0,0,0,0,0,0,AC40,0,0,0,0,0)~
';
    'VSS'<895>:'(0,0,0,0,0,0,0,0,0,0,0,0,0,0,0,0,0,0,0,0,0,0,0,0,AC64,0,0,0,0,0)~
';
    'VSS'<894>:'(0,0,0,0,0,0,0,0,0,0,0,0,0,0,0,0,0,0,0,0,0,0,0,0,AC70,0,0,0,0,0)~
';
    'VSS'<893>:'(0,0,0,0,0,0,0,0,0,0,0,0,0,0,0,0,0,0,0,0,0,0,0,0,AC72,0,0,0,0,0)~
';
    'VSS'<892>:'(0,0,0,0,0,0,0,0,0,0,0,0,0,0,0,0,0,0,0,0,0,0,0,0,AC78,0,0,0,0,0)~
';
    'VSS'<891>:'(0,0,0,0,0,0,0,0,0,0,0,0,0,0,0,0,0,0,0,0,0,0,0,0,AC84,0,0,0,0,0)~
';
    'VSS'<890>:'(0,0,0,0,0,0,0,0,0,0,0,0,0,0,0,0,0,0,0,0,0,0,0,0,AC86,0,0,0,0,0)~
';
    'VSS'<889>:'(0,0,0,0,0,0,0,0,0,0,0,0,0,0,0,0,0,0,0,0,0,0,0,0,AD3,0,0,0,0,0)';
    'VSS'<888>:'(0,0,0,0,0,0,0,0,0,0,0,0,0,0,0,0,0,0,0,0,0,0,0,0,AD7,0,0,0,0,0)';
    'VSS'<887>:'(0,0,0,0,0,0,0,0,0,0,0,0,0,0,0,0,0,0,0,0,0,0,0,0,AD9,0,0,0,0,0)';
    'VSS'<886>:'(0,0,0,0,0,0,0,0,0,0,0,0,0,0,0,0,0,0,0,0,0,0,0,0,AD11,0,0,0,0,0)~
';
    'VSS'<885>:'(0,0,0,0,0,0,0,0,0,0,0,0,0,0,0,0,0,0,0,0,0,0,0,0,AD13,0,0,0,0,0)~
';
    'VSS'<884>:'(0,0,0,0,0,0,0,0,0,0,0,0,0,0,0,0,0,0,0,0,0,0,0,0,AD15,0,0,0,0,0)~
';
    'VSS'<883>:'(0,0,0,0,0,0,0,0,0,0,0,0,0,0,0,0,0,0,0,0,0,0,0,0,AD19,0,0,0,0,0)~
';
    'VSS'<882>:'(0,0,0,0,0,0,0,0,0,0,0,0,0,0,0,0,0,0,0,0,0,0,0,0,AD21,0,0,0,0,0)~
';
    'VSS'<881>:'(0,0,0,0,0,0,0,0,0,0,0,0,0,0,0,0,0,0,0,0,0,0,0,0,AD27,0,0,0,0,0)~
';
    'VSS'<880>:'(0,0,0,0,0,0,0,0,0,0,0,0,0,0,0,0,0,0,0,0,0,0,0,0,AD33,0,0,0,0,0)~
';
    'VSS'<879>:'(0,0,0,0,0,0,0,0,0,0,0,0,0,0,0,0,0,0,0,0,0,0,0,0,AD39,0,0,0,0,0)~
';
    'VSS'<878>:'(0,0,0,0,0,0,0,0,0,0,0,0,0,0,0,0,0,0,0,0,0,0,0,0,AD43,0,0,0,0,0)~
';
    'VSS'<877>:'(0,0,0,0,0,0,0,0,0,0,0,0,0,0,0,0,0,0,0,0,0,0,0,0,AD71,0,0,0,0,0)~
';
    'VSS'<876>:'(0,0,0,0,0,0,0,0,0,0,0,0,0,0,0,0,0,0,0,0,0,0,0,0,AD73,0,0,0,0,0)~
';
    'VSS'<875>:'(0,0,0,0,0,0,0,0,0,0,0,0,0,0,0,0,0,0,0,0,0,0,0,0,AD75,0,0,0,0,0)~
';
    'VSS'<874>:'(0,0,0,0,0,0,0,0,0,0,0,0,0,0,0,0,0,0,0,0,0,0,0,0,AD81,0,0,0,0,0)~
';
    'VSS'<873>:'(0,0,0,0,0,0,0,0,0,0,0,0,0,0,0,0,0,0,0,0,0,0,0,0,AD83,0,0,0,0,0)~
';
    'VSS'<872>:'(0,0,0,0,0,0,0,0,0,0,0,0,0,0,0,0,0,0,0,0,0,0,0,0,AD85,0,0,0,0,0)~
';
    'VSS'<871>:'(0,0,0,0,0,0,0,0,0,0,0,0,0,0,0,0,0,0,0,0,0,0,0,0,AE4,0,0,0,0,0)';
    'VSS'<870>:'(0,0,0,0,0,0,0,0,0,0,0,0,0,0,0,0,0,0,0,0,0,0,0,0,AE8,0,0,0,0,0)';
    'VSS'<869>:'(0,0,0,0,0,0,0,0,0,0,0,0,0,0,0,0,0,0,0,0,0,0,0,0,AC54,0,0,0,0,0)~
';
    'VSS'<868>:'(0,0,0,0,0,0,0,0,0,0,0,0,0,0,0,0,0,0,0,0,0,0,0,0,AE16,0,0,0,0,0)~
';
    'VSS'<867>:'(0,0,0,0,0,0,0,0,0,0,0,0,0,0,0,0,0,0,0,0,0,0,0,0,AE38,0,0,0,0,0)~
';
    'VSS'<866>:'(0,0,0,0,0,0,0,0,0,0,0,0,0,0,0,0,0,0,0,0,0,0,0,0,AE40,0,0,0,0,0)~
';
    'VSS'<865>:'(0,0,0,0,0,0,0,0,0,0,0,0,0,0,0,0,0,0,0,0,0,0,0,0,AE42,0,0,0,0,0)~
';
    'VSS'<864>:'(0,0,0,0,0,0,0,0,0,0,0,0,0,0,0,0,0,0,0,0,0,0,0,0,AE64,0,0,0,0,0)~
';
    'VSS'<863>:'(0,0,0,0,0,0,0,0,0,0,0,0,0,0,0,0,0,0,0,0,0,0,0,0,AE66,0,0,0,0,0)~
';
    'VSS'<862>:'(0,0,0,0,0,0,0,0,0,0,0,0,0,0,0,0,0,0,0,0,0,0,0,0,AE68,0,0,0,0,0)~
';
    'VSS'<861>:'(0,0,0,0,0,0,0,0,0,0,0,0,0,0,0,0,0,0,0,0,0,0,0,0,AE70,0,0,0,0,0)~
';
    'VSS'<860>:'(0,0,0,0,0,0,0,0,0,0,0,0,0,0,0,0,0,0,0,0,0,0,0,0,AE78,0,0,0,0,0)~
';
    'VSS'<859>:'(0,0,0,0,0,0,0,0,0,0,0,0,0,0,0,0,0,0,0,0,0,0,0,0,AF1,0,0,0,0,0)';
    'VSS'<858>:'(0,0,0,0,0,0,0,0,0,0,0,0,0,0,0,0,0,0,0,0,0,0,0,0,AC52,0,0,0,0,0)~
';
    'VSS'<857>:'(0,0,0,0,0,0,0,0,0,0,0,0,0,0,0,0,0,0,0,0,0,0,0,0,AF9,0,0,0,0,0)';
    'VSS'<856>:'(0,0,0,0,0,0,0,0,0,0,0,0,0,0,0,0,0,0,0,0,0,0,0,0,AF21,0,0,0,0,0)~
';
    'VSS'<855>:'(0,0,0,0,0,0,0,0,0,0,0,0,0,0,0,0,0,0,0,0,0,0,0,0,AF23,0,0,0,0,0)~
';
    'VSS'<854>:'(0,0,0,0,0,0,0,0,0,0,0,0,0,0,0,0,0,0,0,0,0,0,0,0,AF25,0,0,0,0,0)~
';
    'VSS'<853>:'(0,0,0,0,0,0,0,0,0,0,0,0,0,0,0,0,0,0,0,0,0,0,0,0,AF27,0,0,0,0,0)~
';
    'VSS'<852>:'(0,0,0,0,0,0,0,0,0,0,0,0,0,0,0,0,0,0,0,0,0,0,0,0,AF29,0,0,0,0,0)~
';
    'VSS'<851>:'(0,0,0,0,0,0,0,0,0,0,0,0,0,0,0,0,0,0,0,0,0,0,0,0,AF31,0,0,0,0,0)~
';
    'VSS'<850>:'(0,0,0,0,0,0,0,0,0,0,0,0,0,0,0,0,0,0,0,0,0,0,0,0,AF33,0,0,0,0,0)~
';
    'VSS'<849>:'(0,0,0,0,0,0,0,0,0,0,0,0,0,0,0,0,0,0,0,0,0,0,0,0,AF37,0,0,0,0,0)~
';
    'VSS'<848>:'(0,0,0,0,0,0,0,0,0,0,0,0,0,0,0,0,0,0,0,0,0,0,0,0,AF39,0,0,0,0,0)~
';
    'VSS'<847>:'(0,0,0,0,0,0,0,0,0,0,0,0,0,0,0,0,0,0,0,0,0,0,0,0,AF41,0,0,0,0,0)~
';
    'VSS'<846>:'(0,0,0,0,0,0,0,0,0,0,0,0,0,0,0,0,0,0,0,0,0,0,0,0,AF73,0,0,0,0,0)~
';
    'VSS'<845>:'(0,0,0,0,0,0,0,0,0,0,0,0,0,0,0,0,0,0,0,0,0,0,0,0,AF77,0,0,0,0,0)~
';
    'VSS'<844>:'(0,0,0,0,0,0,0,0,0,0,0,0,0,0,0,0,0,0,0,0,0,0,0,0,AF83,0,0,0,0,0)~
';
    'VSS'<843>:'(0,0,0,0,0,0,0,0,0,0,0,0,0,0,0,0,0,0,0,0,0,0,0,0,AF85,0,0,0,0,0)~
';
    'VSS'<842>:'(0,0,0,0,0,0,0,0,0,0,0,0,0,0,0,0,0,0,0,0,0,0,0,0,AG12,0,0,0,0,0)~
';
    'VSS'<841>:'(0,0,0,0,0,0,0,0,0,0,0,0,0,0,0,0,0,0,0,0,0,0,0,0,AG14,0,0,0,0,0)~
';
    'VSS'<840>:'(0,0,0,0,0,0,0,0,0,0,0,0,0,0,0,0,0,0,0,0,0,0,0,0,AG18,0,0,0,0,0)~
';
    'VSS'<839>:'(0,0,0,0,0,0,0,0,0,0,0,0,0,0,0,0,0,0,0,0,0,0,0,0,AG36,0,0,0,0,0)~
';
    'VSS'<838>:'(0,0,0,0,0,0,0,0,0,0,0,0,0,0,0,0,0,0,0,0,0,0,0,0,AG64,0,0,0,0,0)~
';
    'VSS'<837>:'(0,0,0,0,0,0,0,0,0,0,0,0,0,0,0,0,0,0,0,0,0,0,0,0,AG70,0,0,0,0,0)~
';
    'VSS'<836>:'(0,0,0,0,0,0,0,0,0,0,0,0,0,0,0,0,0,0,0,0,0,0,0,0,AG74,0,0,0,0,0)~
';
    'VSS'<835>:'(0,0,0,0,0,0,0,0,0,0,0,0,0,0,0,0,0,0,0,0,0,0,0,0,AG76,0,0,0,0,0)~
';
    'VSS'<834>:'(0,0,0,0,0,0,0,0,0,0,0,0,0,0,0,0,0,0,0,0,0,0,0,0,AG78,0,0,0,0,0)~
';
    'VSS'<833>:'(0,0,0,0,0,0,0,0,0,0,0,0,0,0,0,0,0,0,0,0,0,0,0,0,AG80,0,0,0,0,0)~
';
    'VSS'<832>:'(0,0,0,0,0,0,0,0,0,0,0,0,0,0,0,0,0,0,0,0,0,0,0,0,AH1,0,0,0,0,0)';
    'VSS'<831>:'(0,0,0,0,0,0,0,0,0,0,0,0,0,0,0,0,0,0,0,0,0,0,0,0,AH5,0,0,0,0,0)';
    'VSS'<830>:'(0,0,0,0,0,0,0,0,0,0,0,0,0,0,0,0,0,0,0,0,0,0,0,0,AH21,0,0,0,0,0)~
';
    'VSS'<829>:'(0,0,0,0,0,0,0,0,0,0,0,0,0,0,0,0,0,0,0,0,0,0,0,0,AH27,0,0,0,0,0)~
';
    'VSS'<828>:'(0,0,0,0,0,0,0,0,0,0,0,0,0,0,0,0,0,0,0,0,0,0,0,0,AH33,0,0,0,0,0)~
';
    'VSS'<827>:'(0,0,0,0,0,0,0,0,0,0,0,0,0,0,0,0,0,0,0,0,0,0,0,0,AH35,0,0,0,0,0)~
';
    'VSS'<826>:'(0,0,0,0,0,0,0,0,0,0,0,0,0,0,0,0,0,0,0,0,0,0,0,0,AH45,0,0,0,0,0)~
';
    'VSS'<825>:'(0,0,0,0,0,0,0,0,0,0,0,0,0,0,0,0,0,0,0,0,0,0,0,0,AH47,0,0,0,0,0)~
';
    'VSS'<824>:'(0,0,0,0,0,0,0,0,0,0,0,0,0,0,0,0,0,0,0,0,0,0,0,0,AH49,0,0,0,0,0)~
';
    'VSS'<823>:'(0,0,0,0,0,0,0,0,0,0,0,0,0,0,0,0,0,0,0,0,0,0,0,0,AH51,0,0,0,0,0)~
';
    'VSS'<822>:'(0,0,0,0,0,0,0,0,0,0,0,0,0,0,0,0,0,0,0,0,0,0,0,0,AH53,0,0,0,0,0)~
';
    'VSS'<821>:'(0,0,0,0,0,0,0,0,0,0,0,0,0,0,0,0,0,0,0,0,0,0,0,0,AH59,0,0,0,0,0)~
';
    'VSS'<820>:'(0,0,0,0,0,0,0,0,0,0,0,0,0,0,0,0,0,0,0,0,0,0,0,0,AH61,0,0,0,0,0)~
';
    'VSS'<819>:'(0,0,0,0,0,0,0,0,0,0,0,0,0,0,0,0,0,0,0,0,0,0,0,0,AH65,0,0,0,0,0)~
';
    'VSS'<818>:'(0,0,0,0,0,0,0,0,0,0,0,0,0,0,0,0,0,0,0,0,0,0,0,0,AH69,0,0,0,0,0)~
';
    'VSS'<817>:'(0,0,0,0,0,0,0,0,0,0,0,0,0,0,0,0,0,0,0,0,0,0,0,0,AH75,0,0,0,0,0)~
';
    'VSS'<816>:'(0,0,0,0,0,0,0,0,0,0,0,0,0,0,0,0,0,0,0,0,0,0,0,0,AH77,0,0,0,0,0)~
';
    'VSS'<815>:'(0,0,0,0,0,0,0,0,0,0,0,0,0,0,0,0,0,0,0,0,0,0,0,0,AH83,0,0,0,0,0)~
';
    'VSS'<814>:'(0,0,0,0,0,0,0,0,0,0,0,0,0,0,0,0,0,0,0,0,0,0,0,0,AJ8,0,0,0,0,0)';
    'VSS'<813>:'(0,0,0,0,0,0,0,0,0,0,0,0,0,0,0,0,0,0,0,0,0,0,0,0,AJ22,0,0,0,0,0)~
';
    'VSS'<812>:'(0,0,0,0,0,0,0,0,0,0,0,0,0,0,0,0,0,0,0,0,0,0,0,0,AJ26,0,0,0,0,0)~
';
    'VSS'<811>:'(0,0,0,0,0,0,0,0,0,0,0,0,0,0,0,0,0,0,0,0,0,0,0,0,AJ28,0,0,0,0,0)~
';
    'VSS'<810>:'(0,0,0,0,0,0,0,0,0,0,0,0,0,0,0,0,0,0,0,0,0,0,0,0,AJ32,0,0,0,0,0)~
';
    'VSS'<809>:'(0,0,0,0,0,0,0,0,0,0,0,0,0,0,0,0,0,0,0,0,0,0,0,0,AJ34,0,0,0,0,0)~
';
    'VSS'<808>:'(0,0,0,0,0,0,0,0,0,0,0,0,0,0,0,0,0,0,0,0,0,0,0,0,AJ46,0,0,0,0,0)~
';
    'VSS'<807>:'(0,0,0,0,0,0,0,0,0,0,0,0,0,0,0,0,0,0,0,0,0,0,0,0,AJ48,0,0,0,0,0)~
';
    'VSS'<806>:'(0,0,0,0,0,0,0,0,0,0,0,0,0,0,0,0,0,0,0,0,0,0,0,0,AJ50,0,0,0,0,0)~
';
    'VSS'<805>:'(0,0,0,0,0,0,0,0,0,0,0,0,0,0,0,0,0,0,0,0,0,0,0,0,AJ52,0,0,0,0,0)~
';
    'VSS'<804>:'(0,0,0,0,0,0,0,0,0,0,0,0,0,0,0,0,0,0,0,0,0,0,0,0,AJ54,0,0,0,0,0)~
';
    'VSS'<803>:'(0,0,0,0,0,0,0,0,0,0,0,0,0,0,0,0,0,0,0,0,0,0,0,0,AJ66,0,0,0,0,0)~
';
    'VSS'<802>:'(0,0,0,0,0,0,0,0,0,0,0,0,0,0,0,0,0,0,0,0,0,0,0,0,AJ68,0,0,0,0,0)~
';
    'VSS'<801>:'(0,0,0,0,0,0,0,0,0,0,0,0,0,0,0,0,0,0,0,0,0,0,0,0,AJ74,0,0,0,0,0)~
';
    'VSS'<800>:'(0,0,0,0,0,0,0,0,0,0,0,0,0,0,0,0,0,0,0,0,0,0,0,0,AJ78,0,0,0,0,0)~
';
    'VSS'<799>:'(0,0,0,0,0,0,0,0,0,0,0,0,0,0,0,0,0,0,0,0,0,0,0,0,AJ82,0,0,0,0,0)~
';
    'VSS'<798>:'(0,0,0,0,0,0,0,0,0,0,0,0,0,0,0,0,0,0,0,0,0,0,0,0,AJ86,0,0,0,0,0)~
';
    'VSS'<797>:'(0,0,0,0,0,0,0,0,0,0,0,0,0,0,0,0,0,0,0,0,0,0,0,0,AK9,0,0,0,0,0)';
    'VSS'<796>:'(0,0,0,0,0,0,0,0,0,0,0,0,0,0,0,0,0,0,0,0,0,0,0,0,AK13,0,0,0,0,0)~
';
    'VSS'<795>:'(0,0,0,0,0,0,0,0,0,0,0,0,0,0,0,0,0,0,0,0,0,0,0,0,AK19,0,0,0,0,0)~
';
    'VSS'<794>:'(0,0,0,0,0,0,0,0,0,0,0,0,0,0,0,0,0,0,0,0,0,0,0,0,AK23,0,0,0,0,0)~
';
    'VSS'<793>:'(0,0,0,0,0,0,0,0,0,0,0,0,0,0,0,0,0,0,0,0,0,0,0,0,AK25,0,0,0,0,0)~
';
    'VSS'<792>:'(0,0,0,0,0,0,0,0,0,0,0,0,0,0,0,0,0,0,0,0,0,0,0,0,AK29,0,0,0,0,0)~
';
    'VSS'<791>:'(0,0,0,0,0,0,0,0,0,0,0,0,0,0,0,0,0,0,0,0,0,0,0,0,AK31,0,0,0,0,0)~
';
    'VSS'<790>:'(0,0,0,0,0,0,0,0,0,0,0,0,0,0,0,0,0,0,0,0,0,0,0,0,AK33,0,0,0,0,0)~
';
    'VSS'<789>:'(0,0,0,0,0,0,0,0,0,0,0,0,0,0,0,0,0,0,0,0,0,0,0,0,AK55,0,0,0,0,0)~
';
    'VSS'<788>:'(0,0,0,0,0,0,0,0,0,0,0,0,0,0,0,0,0,0,0,0,0,0,0,0,AK65,0,0,0,0,0)~
';
    'VSS'<787>:'(0,0,0,0,0,0,0,0,0,0,0,0,0,0,0,0,0,0,0,0,0,0,0,0,AK67,0,0,0,0,0)~
';
    'VSS'<786>:'(0,0,0,0,0,0,0,0,0,0,0,0,0,0,0,0,0,0,0,0,0,0,0,0,AK73,0,0,0,0,0)~
';
    'VSS'<785>:'(0,0,0,0,0,0,0,0,0,0,0,0,0,0,0,0,0,0,0,0,0,0,0,0,AK79,0,0,0,0,0)~
';
    'VSS'<784>:'(0,0,0,0,0,0,0,0,0,0,0,0,0,0,0,0,0,0,0,0,0,0,0,0,AK81,0,0,0,0,0)~
';
    'VSS'<783>:'(0,0,0,0,0,0,0,0,0,0,0,0,0,0,0,0,0,0,0,0,0,0,0,0,AK83,0,0,0,0,0)~
';
    'VSS'<782>:'(0,0,0,0,0,0,0,0,0,0,0,0,0,0,0,0,0,0,0,0,0,0,0,0,AK85,0,0,0,0,0)~
';
    'VSS'<781>:'(0,0,0,0,0,0,0,0,0,0,0,0,0,0,0,0,0,0,0,0,0,0,0,0,AL4,0,0,0,0,0)';
    'VSS'<780>:'(0,0,0,0,0,0,0,0,0,0,0,0,0,0,0,0,0,0,0,0,0,0,0,0,AL10,0,0,0,0,0)~
';
    'VSS'<779>:'(0,0,0,0,0,0,0,0,0,0,0,0,0,0,0,0,0,0,0,0,0,0,0,0,AL24,0,0,0,0,0)~
';
    'VSS'<778>:'(0,0,0,0,0,0,0,0,0,0,0,0,0,0,0,0,0,0,0,0,0,0,0,0,AL30,0,0,0,0,0)~
';
    'VSS'<777>:'(0,0,0,0,0,0,0,0,0,0,0,0,0,0,0,0,0,0,0,0,0,0,0,0,AL32,0,0,0,0,0)~
';
    'VSS'<776>:'(0,0,0,0,0,0,0,0,0,0,0,0,0,0,0,0,0,0,0,0,0,0,0,0,AL56,0,0,0,0,0)~
';
    'VSS'<775>:'(0,0,0,0,0,0,0,0,0,0,0,0,0,0,0,0,0,0,0,0,0,0,0,0,AL64,0,0,0,0,0)~
';
    'VSS'<774>:'(0,0,0,0,0,0,0,0,0,0,0,0,0,0,0,0,0,0,0,0,0,0,0,0,AL68,0,0,0,0,0)~
';
    'VSS'<773>:'(0,0,0,0,0,0,0,0,0,0,0,0,0,0,0,0,0,0,0,0,0,0,0,0,0,AL76,0,0,0,0)~
';
    'VSS'<772>:'(0,0,0,0,0,0,0,0,0,0,0,0,0,0,0,0,0,0,0,0,0,0,0,0,0,AL78,0,0,0,0)~
';
    'VSS'<771>:'(0,0,0,0,0,0,0,0,0,0,0,0,0,0,0,0,0,0,0,0,0,0,0,0,0,AL80,0,0,0,0)~
';
    'VSS'<770>:'(0,0,0,0,0,0,0,0,0,0,0,0,0,0,0,0,0,0,0,0,0,0,0,0,0,AL82,0,0,0,0)~
';
    'VSS'<769>:'(0,0,0,0,0,0,0,0,0,0,0,0,0,0,0,0,0,0,0,0,0,0,0,0,0,AL86,0,0,0,0)~
';
    'VSS'<768>:'(0,0,0,0,0,0,0,0,0,0,0,0,0,0,0,0,0,0,0,0,0,0,0,0,0,AM1,0,0,0,0)';
    'VSS'<767>:'(0,0,0,0,0,0,0,0,0,0,0,0,0,0,0,0,0,0,0,0,0,0,0,0,0,AC50,0,0,0,0)~
';
    'VSS'<766>:'(0,0,0,0,0,0,0,0,0,0,0,0,0,0,0,0,0,0,0,0,0,0,0,0,0,AM31,0,0,0,0)~
';
    'VSS'<765>:'(0,0,0,0,0,0,0,0,0,0,0,0,0,0,0,0,0,0,0,0,0,0,0,0,0,AM57,0,0,0,0)~
';
    'VSS'<764>:'(0,0,0,0,0,0,0,0,0,0,0,0,0,0,0,0,0,0,0,0,0,0,0,0,0,AM63,0,0,0,0)~
';
    'VSS'<763>:'(0,0,0,0,0,0,0,0,0,0,0,0,0,0,0,0,0,0,0,0,0,0,0,0,0,AM69,0,0,0,0)~
';
    'VSS'<762>:'(0,0,0,0,0,0,0,0,0,0,0,0,0,0,0,0,0,0,0,0,0,0,0,0,0,AM73,0,0,0,0)~
';
    'VSS'<761>:'(0,0,0,0,0,0,0,0,0,0,0,0,0,0,0,0,0,0,0,0,0,0,0,0,0,AM79,0,0,0,0)~
';
    'VSS'<760>:'(0,0,0,0,0,0,0,0,0,0,0,0,0,0,0,0,0,0,0,0,0,0,0,0,0,AM83,0,0,0,0)~
';
    'VSS'<759>:'(0,0,0,0,0,0,0,0,0,0,0,0,0,0,0,0,0,0,0,0,0,0,0,0,0,AN2,0,0,0,0)';
    'VSS'<758>:'(0,0,0,0,0,0,0,0,0,0,0,0,0,0,0,0,0,0,0,0,0,0,0,0,0,AN6,0,0,0,0)';
    'VSS'<757>:'(0,0,0,0,0,0,0,0,0,0,0,0,0,0,0,0,0,0,0,0,0,0,0,0,0,AN28,0,0,0,0)~
';
    'VSS'<756>:'(0,0,0,0,0,0,0,0,0,0,0,0,0,0,0,0,0,0,0,0,0,0,0,0,0,AN58,0,0,0,0)~
';
    'VSS'<755>:'(0,0,0,0,0,0,0,0,0,0,0,0,0,0,0,0,0,0,0,0,0,0,0,0,0,AN78,0,0,0,0)~
';
    'VSS'<754>:'(0,0,0,0,0,0,0,0,0,0,0,0,0,0,0,0,0,0,0,0,0,0,0,0,0,AP5,0,0,0,0)';
    'VSS'<753>:'(0,0,0,0,0,0,0,0,0,0,0,0,0,0,0,0,0,0,0,0,0,0,0,0,0,AP9,0,0,0,0)';
    'VSS'<752>:'(0,0,0,0,0,0,0,0,0,0,0,0,0,0,0,0,0,0,0,0,0,0,0,0,0,AP13,0,0,0,0)~
';
    'VSS'<751>:'(0,0,0,0,0,0,0,0,0,0,0,0,0,0,0,0,0,0,0,0,0,0,0,0,0,AP19,0,0,0,0)~
';
    'VSS'<750>:'(0,0,0,0,0,0,0,0,0,0,0,0,0,0,0,0,0,0,0,0,0,0,0,0,0,AP31,0,0,0,0)~
';
    'VSS'<749>:'(0,0,0,0,0,0,0,0,0,0,0,0,0,0,0,0,0,0,0,0,0,0,0,0,0,AP59,0,0,0,0)~
';
    'VSS'<748>:'(0,0,0,0,0,0,0,0,0,0,0,0,0,0,0,0,0,0,0,0,0,0,0,0,0,AP63,0,0,0,0)~
';
    'VSS'<747>:'(0,0,0,0,0,0,0,0,0,0,0,0,0,0,0,0,0,0,0,0,0,0,0,0,0,AP65,0,0,0,0)~
';
    'VSS'<746>:'(0,0,0,0,0,0,0,0,0,0,0,0,0,0,0,0,0,0,0,0,0,0,0,0,0,AP67,0,0,0,0)~
';
    'VSS'<745>:'(0,0,0,0,0,0,0,0,0,0,0,0,0,0,0,0,0,0,0,0,0,0,0,0,0,AP69,0,0,0,0)~
';
    'VSS'<744>:'(0,0,0,0,0,0,0,0,0,0,0,0,0,0,0,0,0,0,0,0,0,0,0,0,0,AP73,0,0,0,0)~
';
    'VSS'<743>:'(0,0,0,0,0,0,0,0,0,0,0,0,0,0,0,0,0,0,0,0,0,0,0,0,0,AP75,0,0,0,0)~
';
    'VSS'<742>:'(0,0,0,0,0,0,0,0,0,0,0,0,0,0,0,0,0,0,0,0,0,0,0,0,0,AP81,0,0,0,0)~
';
    'VSS'<741>:'(0,0,0,0,0,0,0,0,0,0,0,0,0,0,0,0,0,0,0,0,0,0,0,0,0,AP83,0,0,0,0)~
';
    'VSS'<740>:'(0,0,0,0,0,0,0,0,0,0,0,0,0,0,0,0,0,0,0,0,0,0,0,0,0,AP85,0,0,0,0)~
';
    'VSS'<739>:'(0,0,0,0,0,0,0,0,0,0,0,0,0,0,0,0,0,0,0,0,0,0,0,0,0,AR10,0,0,0,0)~
';
    'VSS'<738>:'(0,0,0,0,0,0,0,0,0,0,0,0,0,0,0,0,0,0,0,0,0,0,0,0,0,AR24,0,0,0,0)~
';
    'VSS'<737>:'(0,0,0,0,0,0,0,0,0,0,0,0,0,0,0,0,0,0,0,0,0,0,0,0,0,AR30,0,0,0,0)~
';
    'VSS'<736>:'(0,0,0,0,0,0,0,0,0,0,0,0,0,0,0,0,0,0,0,0,0,0,0,0,0,AR60,0,0,0,0)~
';
    'VSS'<735>:'(0,0,0,0,0,0,0,0,0,0,0,0,0,0,0,0,0,0,0,0,0,0,0,0,0,AR72,0,0,0,0)~
';
    'VSS'<734>:'(0,0,0,0,0,0,0,0,0,0,0,0,0,0,0,0,0,0,0,0,0,0,0,0,0,AR78,0,0,0,0)~
';
    'VSS'<733>:'(0,0,0,0,0,0,0,0,0,0,0,0,0,0,0,0,0,0,0,0,0,0,0,0,0,AC48,0,0,0,0)~
';
    'VSS'<732>:'(0,0,0,0,0,0,0,0,0,0,0,0,0,0,0,0,0,0,0,0,0,0,0,0,0,P63,0,0,0,0)';
    'VSS'<731>:'(0,0,0,0,0,0,0,0,0,0,0,0,0,0,0,0,0,0,0,0,0,0,0,0,0,AT15,0,0,0,0)~
';
    'VSS'<730>:'(0,0,0,0,0,0,0,0,0,0,0,0,0,0,0,0,0,0,0,0,0,0,0,0,0,AT17,0,0,0,0)~
';
    'VSS'<729>:'(0,0,0,0,0,0,0,0,0,0,0,0,0,0,0,0,0,0,0,0,0,0,0,0,0,AT21,0,0,0,0)~
';
    'VSS'<728>:'(0,0,0,0,0,0,0,0,0,0,0,0,0,0,0,0,0,0,0,0,0,0,0,0,0,AT27,0,0,0,0)~
';
    'VSS'<727>:'(0,0,0,0,0,0,0,0,0,0,0,0,0,0,0,0,0,0,0,0,0,0,0,0,0,AT61,0,0,0,0)~
';
    'VSS'<726>:'(0,0,0,0,0,0,0,0,0,0,0,0,0,0,0,0,0,0,0,0,0,0,0,0,0,AT63,0,0,0,0)~
';
    'VSS'<725>:'(0,0,0,0,0,0,0,0,0,0,0,0,0,0,0,0,0,0,0,0,0,0,0,0,0,AT69,0,0,0,0)~
';
    'VSS'<724>:'(0,0,0,0,0,0,0,0,0,0,0,0,0,0,0,0,0,0,0,0,0,0,0,0,0,AT73,0,0,0,0)~
';
    'VSS'<723>:'(0,0,0,0,0,0,0,0,0,0,0,0,0,0,0,0,0,0,0,0,0,0,0,0,0,AT77,0,0,0,0)~
';
    'VSS'<722>:'(0,0,0,0,0,0,0,0,0,0,0,0,0,0,0,0,0,0,0,0,0,0,0,0,0,AT83,0,0,0,0)~
';
    'VSS'<721>:'(0,0,0,0,0,0,0,0,0,0,0,0,0,0,0,0,0,0,0,0,0,0,0,0,0,AT85,0,0,0,0)~
';
    'VSS'<720>:'(0,0,0,0,0,0,0,0,0,0,0,0,0,0,0,0,0,0,0,0,0,0,0,0,0,AU2,0,0,0,0)';
    'VSS'<719>:'(0,0,0,0,0,0,0,0,0,0,0,0,0,0,0,0,0,0,0,0,0,0,0,0,0,AU6,0,0,0,0)';
    'VSS'<718>:'(0,0,0,0,0,0,0,0,0,0,0,0,0,0,0,0,0,0,0,0,0,0,0,0,0,AU26,0,0,0,0)~
';
    'VSS'<717>:'(0,0,0,0,0,0,0,0,0,0,0,0,0,0,0,0,0,0,0,0,0,0,0,0,0,AU28,0,0,0,0)~
';
    'VSS'<716>:'(0,0,0,0,0,0,0,0,0,0,0,0,0,0,0,0,0,0,0,0,0,0,0,0,0,AU62,0,0,0,0)~
';
    'VSS'<715>:'(0,0,0,0,0,0,0,0,0,0,0,0,0,0,0,0,0,0,0,0,0,0,0,0,0,AU64,0,0,0,0)~
';
    'VSS'<714>:'(0,0,0,0,0,0,0,0,0,0,0,0,0,0,0,0,0,0,0,0,0,0,0,0,0,AU68,0,0,0,0)~
';
    'VSS'<713>:'(0,0,0,0,0,0,0,0,0,0,0,0,0,0,0,0,0,0,0,0,0,0,0,0,0,AU74,0,0,0,0)~
';
    'VSS'<712>:'(0,0,0,0,0,0,0,0,0,0,0,0,0,0,0,0,0,0,0,0,0,0,0,0,0,AU76,0,0,0,0)~
';
    'VSS'<711>:'(0,0,0,0,0,0,0,0,0,0,0,0,0,0,0,0,0,0,0,0,0,0,0,0,0,AU78,0,0,0,0)~
';
    'VSS'<710>:'(0,0,0,0,0,0,0,0,0,0,0,0,0,0,0,0,0,0,0,0,0,0,0,0,0,AU80,0,0,0,0)~
';
    'VSS'<709>:'(0,0,0,0,0,0,0,0,0,0,0,0,0,0,0,0,0,0,0,0,0,0,0,0,0,AU84,0,0,0,0)~
';
    'VSS'<708>:'(0,0,0,0,0,0,0,0,0,0,0,0,0,0,0,0,0,0,0,0,0,0,0,0,0,AU86,0,0,0,0)~
';
    'VSS'<707>:'(0,0,0,0,0,0,0,0,0,0,0,0,0,0,0,0,0,0,0,0,0,0,0,0,0,AV1,0,0,0,0)';
    'VSS'<706>:'(0,0,0,0,0,0,0,0,0,0,0,0,0,0,0,0,0,0,0,0,0,0,0,0,0,AV3,0,0,0,0)';
    'VSS'<705>:'(0,0,0,0,0,0,0,0,0,0,0,0,0,0,0,0,0,0,0,0,0,0,0,0,0,AV7,0,0,0,0)';
    'VSS'<704>:'(0,0,0,0,0,0,0,0,0,0,0,0,0,0,0,0,0,0,0,0,0,0,0,0,0,AV11,0,0,0,0)~
';
    'VSS'<703>:'(0,0,0,0,0,0,0,0,0,0,0,0,0,0,0,0,0,0,0,0,0,0,0,0,0,AV13,0,0,0,0)~
';
    'VSS'<702>:'(0,0,0,0,0,0,0,0,0,0,0,0,0,0,0,0,0,0,0,0,0,0,0,0,0,AV19,0,0,0,0)~
';
    'VSS'<701>:'(0,0,0,0,0,0,0,0,0,0,0,0,0,0,0,0,0,0,0,0,0,0,0,0,0,AV23,0,0,0,0)~
';
    'VSS'<700>:'(0,0,0,0,0,0,0,0,0,0,0,0,0,0,0,0,0,0,0,0,0,0,0,0,0,AV25,0,0,0,0)~
';
    'VSS'<699>:'(0,0,0,0,0,0,0,0,0,0,0,0,0,0,0,0,0,0,0,0,0,0,0,0,0,AV63,0,0,0,0)~
';
    'VSS'<698>:'(0,0,0,0,0,0,0,0,0,0,0,0,0,0,0,0,0,0,0,0,0,0,0,0,0,AV65,0,0,0,0)~
';
    'VSS'<697>:'(0,0,0,0,0,0,0,0,0,0,0,0,0,0,0,0,0,0,0,0,0,0,0,0,0,AV67,0,0,0,0)~
';
    'VSS'<696>:'(0,0,0,0,0,0,0,0,0,0,0,0,0,0,0,0,0,0,0,0,0,0,0,0,0,AV75,0,0,0,0)~
';
    'VSS'<695>:'(0,0,0,0,0,0,0,0,0,0,0,0,0,0,0,0,0,0,0,0,0,0,0,0,0,AV83,0,0,0,0)~
';
    'VSS'<694>:'(0,0,0,0,0,0,0,0,0,0,0,0,0,0,0,0,0,0,0,0,0,0,0,0,0,AW2,0,0,0,0)';
    'VSS'<693>:'(0,0,0,0,0,0,0,0,0,0,0,0,0,0,0,0,0,0,0,0,0,0,0,0,0,AW10,0,0,0,0)~
';
    'VSS'<692>:'(0,0,0,0,0,0,0,0,0,0,0,0,0,0,0,0,0,0,0,0,0,0,0,0,0,AW62,0,0,0,0)~
';
    'VSS'<691>:'(0,0,0,0,0,0,0,0,0,0,0,0,0,0,0,0,0,0,0,0,0,0,0,0,0,AW66,0,0,0,0)~
';
    'VSS'<690>:'(0,0,0,0,0,0,0,0,0,0,0,0,0,0,0,0,0,0,0,0,0,0,0,0,0,AW68,0,0,0,0)~
';
    'VSS'<689>:'(0,0,0,0,0,0,0,0,0,0,0,0,0,0,0,0,0,0,0,0,0,0,0,0,0,AW70,0,0,0,0)~
';
    'VSS'<688>:'(0,0,0,0,0,0,0,0,0,0,0,0,0,0,0,0,0,0,0,0,0,0,0,0,0,AW72,0,0,0,0)~
';
    'VSS'<687>:'(0,0,0,0,0,0,0,0,0,0,0,0,0,0,0,0,0,0,0,0,0,0,0,0,0,AW74,0,0,0,0)~
';
    'VSS'<686>:'(0,0,0,0,0,0,0,0,0,0,0,0,0,0,0,0,0,0,0,0,0,0,0,0,0,AW78,0,0,0,0)~
';
    'VSS'<685>:'(0,0,0,0,0,0,0,0,0,0,0,0,0,0,0,0,0,0,0,0,0,0,0,0,0,AW82,0,0,0,0)~
';
    'VSS'<684>:'(0,0,0,0,0,0,0,0,0,0,0,0,0,0,0,0,0,0,0,0,0,0,0,0,0,AW84,0,0,0,0)~
';
    'VSS'<683>:'(0,0,0,0,0,0,0,0,0,0,0,0,0,0,0,0,0,0,0,0,0,0,0,0,0,AY5,0,0,0,0)';
    'VSS'<682>:'(0,0,0,0,0,0,0,0,0,0,0,0,0,0,0,0,0,0,0,0,0,0,0,0,0,AY15,0,0,0,0)~
';
    'VSS'<681>:'(0,0,0,0,0,0,0,0,0,0,0,0,0,0,0,0,0,0,0,0,0,0,0,0,0,AY17,0,0,0,0)~
';
    'VSS'<680>:'(0,0,0,0,0,0,0,0,0,0,0,0,0,0,0,0,0,0,0,0,0,0,0,0,0,AY21,0,0,0,0)~
';
    'VSS'<679>:'(0,0,0,0,0,0,0,0,0,0,0,0,0,0,0,0,0,0,0,0,0,0,0,0,0,AY23,0,0,0,0)~
';
    'VSS'<678>:'(0,0,0,0,0,0,0,0,0,0,0,0,0,0,0,0,0,0,0,0,0,0,0,0,0,AY25,0,0,0,0)~
';
    'VSS'<677>:'(0,0,0,0,0,0,0,0,0,0,0,0,0,0,0,0,0,0,0,0,0,0,0,0,0,AY63,0,0,0,0)~
';
    'VSS'<676>:'(0,0,0,0,0,0,0,0,0,0,0,0,0,0,0,0,0,0,0,0,0,0,0,0,0,AY79,0,0,0,0)~
';
    'VSS'<675>:'(0,0,0,0,0,0,0,0,0,0,0,0,0,0,0,0,0,0,0,0,0,0,0,0,0,AY81,0,0,0,0)~
';
    'VSS'<674>:'(0,0,0,0,0,0,0,0,0,0,0,0,0,0,0,0,0,0,0,0,0,0,0,0,0,BA2,0,0,0,0)';
    'VSS'<673>:'(0,0,0,0,0,0,0,0,0,0,0,0,0,0,0,0,0,0,0,0,0,0,0,0,0,BA6,0,0,0,0)';
    'VSS'<672>:'(0,0,0,0,0,0,0,0,0,0,0,0,0,0,0,0,0,0,0,0,0,0,0,0,0,BA12,0,0,0,0)~
';
    'VSS'<671>:'(0,0,0,0,0,0,0,0,0,0,0,0,0,0,0,0,0,0,0,0,0,0,0,0,0,BA62,0,0,0,0)~
';
    'VSS'<670>:'(0,0,0,0,0,0,0,0,0,0,0,0,0,0,0,0,0,0,0,0,0,0,0,0,0,BA68,0,0,0,0)~
';
    'VSS'<669>:'(0,0,0,0,0,0,0,0,0,0,0,0,0,0,0,0,0,0,0,0,0,0,0,0,0,BA74,0,0,0,0)~
';
    'VSS'<668>:'(0,0,0,0,0,0,0,0,0,0,0,0,0,0,0,0,0,0,0,0,0,0,0,0,0,BA80,0,0,0,0)~
';
    'VSS'<667>:'(0,0,0,0,0,0,0,0,0,0,0,0,0,0,0,0,0,0,0,0,0,0,0,0,0,BA84,0,0,0,0)~
';
    'VSS'<666>:'(0,0,0,0,0,0,0,0,0,0,0,0,0,0,0,0,0,0,0,0,0,0,0,0,0,BB19,0,0,0,0)~
';
    'VSS'<665>:'(0,0,0,0,0,0,0,0,0,0,0,0,0,0,0,0,0,0,0,0,0,0,0,0,0,BB23,0,0,0,0)~
';
    'VSS'<664>:'(0,0,0,0,0,0,0,0,0,0,0,0,0,0,0,0,0,0,0,0,0,0,0,0,0,BB63,0,0,0,0)~
';
    'VSS'<663>:'(0,0,0,0,0,0,0,0,0,0,0,0,0,0,0,0,0,0,0,0,0,0,0,0,0,BB69,0,0,0,0)~
';
    'VSS'<662>:'(0,0,0,0,0,0,0,0,0,0,0,0,0,0,0,0,0,0,0,0,0,0,0,0,0,BB73,0,0,0,0)~
';
    'VSS'<661>:'(0,0,0,0,0,0,0,0,0,0,0,0,0,0,0,0,0,0,0,0,0,0,0,0,0,BB75,0,0,0,0)~
';
    'VSS'<660>:'(0,0,0,0,0,0,0,0,0,0,0,0,0,0,0,0,0,0,0,0,0,0,0,0,0,BB77,0,0,0,0)~
';
    'VSS'<659>:'(0,0,0,0,0,0,0,0,0,0,0,0,0,0,0,0,0,0,0,0,0,0,0,0,0,BB79,0,0,0,0)~
';
    'VSS'<658>:'(0,0,0,0,0,0,0,0,0,0,0,0,0,0,0,0,0,0,0,0,0,0,0,0,0,BB81,0,0,0,0)~
';
    'VSS'<657>:'(0,0,0,0,0,0,0,0,0,0,0,0,0,0,0,0,0,0,0,0,0,0,0,0,0,BB83,0,0,0,0)~
';
    'VSS'<656>:'(0,0,0,0,0,0,0,0,0,0,0,0,0,0,0,0,0,0,0,0,0,0,0,0,0,BC4,0,0,0,0)';
    'VSS'<655>:'(0,0,0,0,0,0,0,0,0,0,0,0,0,0,0,0,0,0,0,0,0,0,0,0,0,BC8,0,0,0,0)';
    'VSS'<654>:'(0,0,0,0,0,0,0,0,0,0,0,0,0,0,0,0,0,0,0,0,0,0,0,0,0,BC12,0,0,0,0)~
';
    'VSS'<653>:'(0,0,0,0,0,0,0,0,0,0,0,0,0,0,0,0,0,0,0,0,0,0,0,0,0,BC16,0,0,0,0)~
';
    'VSS'<652>:'(0,0,0,0,0,0,0,0,0,0,0,0,0,0,0,0,0,0,0,0,0,0,0,0,0,BC70,0,0,0,0)~
';
    'VSS'<651>:'(0,0,0,0,0,0,0,0,0,0,0,0,0,0,0,0,0,0,0,0,0,0,0,0,0,BC72,0,0,0,0)~
';
    'VSS'<650>:'(0,0,0,0,0,0,0,0,0,0,0,0,0,0,0,0,0,0,0,0,0,0,0,0,0,BC74,0,0,0,0)~
';
    'VSS'<649>:'(0,0,0,0,0,0,0,0,0,0,0,0,0,0,0,0,0,0,0,0,0,0,0,0,0,BC76,0,0,0,0)~
';
    'VSS'<648>:'(0,0,0,0,0,0,0,0,0,0,0,0,0,0,0,0,0,0,0,0,0,0,0,0,0,BC78,0,0,0,0)~
';
    'VSS'<647>:'(0,0,0,0,0,0,0,0,0,0,0,0,0,0,0,0,0,0,0,0,0,0,0,0,0,BC80,0,0,0,0)~
';
    'VSS'<646>:'(0,0,0,0,0,0,0,0,0,0,0,0,0,0,0,0,0,0,0,0,0,0,0,0,0,BC82,0,0,0,0)~
';
    'VSS'<645>:'(0,0,0,0,0,0,0,0,0,0,0,0,0,0,0,0,0,0,0,0,0,0,0,0,0,BD5,0,0,0,0)';
    'VSS'<644>:'(0,0,0,0,0,0,0,0,0,0,0,0,0,0,0,0,0,0,0,0,0,0,0,0,0,BD11,0,0,0,0)~
';
    'VSS'<643>:'(0,0,0,0,0,0,0,0,0,0,0,0,0,0,0,0,0,0,0,0,0,0,0,0,0,BD15,0,0,0,0)~
';
    'VSS'<642>:'(0,0,0,0,0,0,0,0,0,0,0,0,0,0,0,0,0,0,0,0,0,0,0,0,0,BD21,0,0,0,0)~
';
    'VSS'<641>:'(0,0,0,0,0,0,0,0,0,0,0,0,0,0,0,0,0,0,0,0,0,0,0,0,0,BD27,0,0,0,0)~
';
    'VSS'<640>:'(0,0,0,0,0,0,0,0,0,0,0,0,0,0,0,0,0,0,0,0,0,0,0,0,0,BD63,0,0,0,0)~
';
    'VSS'<639>:'(0,0,0,0,0,0,0,0,0,0,0,0,0,0,0,0,0,0,0,0,0,0,0,0,0,BD71,0,0,0,0)~
';
    'VSS'<638>:'(0,0,0,0,0,0,0,0,0,0,0,0,0,0,0,0,0,0,0,0,0,0,0,0,0,BE4,0,0,0,0)';
    'VSS'<637>:'(0,0,0,0,0,0,0,0,0,0,0,0,0,0,0,0,0,0,0,0,0,0,0,0,0,BE6,0,0,0,0)';
    'VSS'<636>:'(0,0,0,0,0,0,0,0,0,0,0,0,0,0,0,0,0,0,0,0,0,0,0,0,0,BE8,0,0,0,0)';
    'VSS'<635>:'(0,0,0,0,0,0,0,0,0,0,0,0,0,0,0,0,0,0,0,0,0,0,0,0,0,BE10,0,0,0,0)~
';
    'VSS'<634>:'(0,0,0,0,0,0,0,0,0,0,0,0,0,0,0,0,0,0,0,0,0,0,0,0,0,BE26,0,0,0,0)~
';
    'VSS'<633>:'(0,0,0,0,0,0,0,0,0,0,0,0,0,0,0,0,0,0,0,0,0,0,0,0,0,BE64,0,0,0,0)~
';
    'VSS'<632>:'(0,0,0,0,0,0,0,0,0,0,0,0,0,0,0,0,0,0,0,0,0,0,0,0,0,BE66,0,0,0,0)~
';
    'VSS'<631>:'(0,0,0,0,0,0,0,0,0,0,0,0,0,0,0,0,0,0,0,0,0,0,0,0,0,BE68,0,0,0,0)~
';
    'VSS'<630>:'(0,0,0,0,0,0,0,0,0,0,0,0,0,0,0,0,0,0,0,0,0,0,0,0,0,BE70,0,0,0,0)~
';
    'VSS'<629>:'(0,0,0,0,0,0,0,0,0,0,0,0,0,0,0,0,0,0,0,0,0,0,0,0,0,BF9,0,0,0,0)';
    'VSS'<628>:'(0,0,0,0,0,0,0,0,0,0,0,0,0,0,0,0,0,0,0,0,0,0,0,0,0,BF15,0,0,0,0)~
';
    'VSS'<627>:'(0,0,0,0,0,0,0,0,0,0,0,0,0,0,0,0,0,0,0,0,0,0,0,0,0,BF17,0,0,0,0)~
';
    'VSS'<626>:'(0,0,0,0,0,0,0,0,0,0,0,0,0,0,0,0,0,0,0,0,0,0,0,0,0,BF19,0,0,0,0)~
';
    'VSS'<625>:'(0,0,0,0,0,0,0,0,0,0,0,0,0,0,0,0,0,0,0,0,0,0,0,0,0,BF25,0,0,0,0)~
';
    'VSS'<624>:'(0,0,0,0,0,0,0,0,0,0,0,0,0,0,0,0,0,0,0,0,0,0,0,0,0,BF63,0,0,0,0)~
';
    'VSS'<623>:'(0,0,0,0,0,0,0,0,0,0,0,0,0,0,0,0,0,0,0,0,0,0,0,0,0,BF65,0,0,0,0)~
';
    'VSS'<622>:'(0,0,0,0,0,0,0,0,0,0,0,0,0,0,0,0,0,0,0,0,0,0,0,0,0,BF67,0,0,0,0)~
';
    'VSS'<621>:'(0,0,0,0,0,0,0,0,0,0,0,0,0,0,0,0,0,0,0,0,0,0,0,0,0,BF69,0,0,0,0)~
';
    'VSS'<620>:'(0,0,0,0,0,0,0,0,0,0,0,0,0,0,0,0,0,0,0,0,0,0,0,0,0,BF71,0,0,0,0)~
';
    'VSS'<619>:'(0,0,0,0,0,0,0,0,0,0,0,0,0,0,0,0,0,0,0,0,0,0,0,0,0,BG6,0,0,0,0)';
    'VSS'<618>:'(0,0,0,0,0,0,0,0,0,0,0,0,0,0,0,0,0,0,0,0,0,0,0,0,0,BG8,0,0,0,0)';
    'VSS'<617>:'(0,0,0,0,0,0,0,0,0,0,0,0,0,0,0,0,0,0,0,0,0,0,0,0,0,BG10,0,0,0,0)~
';
    'VSS'<616>:'(0,0,0,0,0,0,0,0,0,0,0,0,0,0,0,0,0,0,0,0,0,0,0,0,0,BG22,0,0,0,0)~
';
    'VSS'<615>:'(0,0,0,0,0,0,0,0,0,0,0,0,0,0,0,0,0,0,0,0,0,0,0,0,0,BG24,0,0,0,0)~
';
    'VSS'<614>:'(0,0,0,0,0,0,0,0,0,0,0,0,0,0,0,0,0,0,0,0,0,0,0,0,0,BG72,0,0,0,0)~
';
    'VSS'<613>:'(0,0,0,0,0,0,0,0,0,0,0,0,0,0,0,0,0,0,0,0,0,0,0,0,0,0,BG74,0,0,0)~
';
    'VSS'<612>:'(0,0,0,0,0,0,0,0,0,0,0,0,0,0,0,0,0,0,0,0,0,0,0,0,0,0,BG76,0,0,0)~
';
    'VSS'<611>:'(0,0,0,0,0,0,0,0,0,0,0,0,0,0,0,0,0,0,0,0,0,0,0,0,0,0,BG78,0,0,0)~
';
    'VSS'<610>:'(0,0,0,0,0,0,0,0,0,0,0,0,0,0,0,0,0,0,0,0,0,0,0,0,0,0,BG80,0,0,0)~
';
    'VSS'<609>:'(0,0,0,0,0,0,0,0,0,0,0,0,0,0,0,0,0,0,0,0,0,0,0,0,0,0,BG82,0,0,0)~
';
    'VSS'<608>:'(0,0,0,0,0,0,0,0,0,0,0,0,0,0,0,0,0,0,0,0,0,0,0,0,0,0,BH7,0,0,0)';
    'VSS'<607>:'(0,0,0,0,0,0,0,0,0,0,0,0,0,0,0,0,0,0,0,0,0,0,0,0,0,0,BH9,0,0,0)';
    'VSS'<606>:'(0,0,0,0,0,0,0,0,0,0,0,0,0,0,0,0,0,0,0,0,0,0,0,0,0,0,BH11,0,0,0)~
';
    'VSS'<605>:'(0,0,0,0,0,0,0,0,0,0,0,0,0,0,0,0,0,0,0,0,0,0,0,0,0,0,BH15,0,0,0)~
';
    'VSS'<604>:'(0,0,0,0,0,0,0,0,0,0,0,0,0,0,0,0,0,0,0,0,0,0,0,0,0,0,BH21,0,0,0)~
';
    'VSS'<603>:'(0,0,0,0,0,0,0,0,0,0,0,0,0,0,0,0,0,0,0,0,0,0,0,0,0,0,BJ4,0,0,0)';
    'VSS'<602>:'(0,0,0,0,0,0,0,0,0,0,0,0,0,0,0,0,0,0,0,0,0,0,0,0,0,0,BJ6,0,0,0)';
    'VSS'<601>:'(0,0,0,0,0,0,0,0,0,0,0,0,0,0,0,0,0,0,0,0,0,0,0,0,0,0,BK3,0,0,0)';
    'VSS'<600>:'(0,0,0,0,0,0,0,0,0,0,0,0,0,0,0,0,0,0,0,0,0,0,0,0,0,0,BK7,0,0,0)';
    'VSS'<599>:'(0,0,0,0,0,0,0,0,0,0,0,0,0,0,0,0,0,0,0,0,0,0,0,0,0,0,BK11,0,0,0)~
';
    'VSS'<598>:'(0,0,0,0,0,0,0,0,0,0,0,0,0,0,0,0,0,0,0,0,0,0,0,0,0,0,BK19,0,0,0)~
';
    'VSS'<597>:'(0,0,0,0,0,0,0,0,0,0,0,0,0,0,0,0,0,0,0,0,0,0,0,0,0,0,BL6,0,0,0)';
    'VSS'<596>:'(0,0,0,0,0,0,0,0,0,0,0,0,0,0,0,0,0,0,0,0,0,0,0,0,0,0,BL10,0,0,0)~
';
    'VSS'<595>:'(0,0,0,0,0,0,0,0,0,0,0,0,0,0,0,0,0,0,0,0,0,0,0,0,0,0,BL12,0,0,0)~
';
    'VSS'<594>:'(0,0,0,0,0,0,0,0,0,0,0,0,0,0,0,0,0,0,0,0,0,0,0,0,0,0,P61,0,0,0)';
    'VSS'<593>:'(0,0,0,0,0,0,0,0,0,0,0,0,0,0,0,0,0,0,0,0,0,0,0,0,0,0,BL22,0,0,0)~
';
    'VSS'<592>:'(0,0,0,0,0,0,0,0,0,0,0,0,0,0,0,0,0,0,0,0,0,0,0,0,0,0,BL24,0,0,0)~
';
    'VSS'<591>:'(0,0,0,0,0,0,0,0,0,0,0,0,0,0,0,0,0,0,0,0,0,0,0,0,0,0,BL64,0,0,0)~
';
    'VSS'<590>:'(0,0,0,0,0,0,0,0,0,0,0,0,0,0,0,0,0,0,0,0,0,0,0,0,0,0,BL66,0,0,0)~
';
    'VSS'<589>:'(0,0,0,0,0,0,0,0,0,0,0,0,0,0,0,0,0,0,0,0,0,0,0,0,0,0,BL68,0,0,0)~
';
    'VSS'<588>:'(0,0,0,0,0,0,0,0,0,0,0,0,0,0,0,0,0,0,0,0,0,0,0,0,0,0,BL70,0,0,0)~
';
    'VSS'<587>:'(0,0,0,0,0,0,0,0,0,0,0,0,0,0,0,0,0,0,0,0,0,0,0,0,0,0,BL72,0,0,0)~
';
    'VSS'<586>:'(0,0,0,0,0,0,0,0,0,0,0,0,0,0,0,0,0,0,0,0,0,0,0,0,0,0,BL74,0,0,0)~
';
    'VSS'<585>:'(0,0,0,0,0,0,0,0,0,0,0,0,0,0,0,0,0,0,0,0,0,0,0,0,0,0,BL76,0,0,0)~
';
    'VSS'<584>:'(0,0,0,0,0,0,0,0,0,0,0,0,0,0,0,0,0,0,0,0,0,0,0,0,0,0,BL78,0,0,0)~
';
    'VSS'<583>:'(0,0,0,0,0,0,0,0,0,0,0,0,0,0,0,0,0,0,0,0,0,0,0,0,0,0,BL80,0,0,0)~
';
    'VSS'<582>:'(0,0,0,0,0,0,0,0,0,0,0,0,0,0,0,0,0,0,0,0,0,0,0,0,0,0,BL82,0,0,0)~
';
    'VSS'<581>:'(0,0,0,0,0,0,0,0,0,0,0,0,0,0,0,0,0,0,0,0,0,0,0,0,0,0,BM9,0,0,0)';
    'VSS'<580>:'(0,0,0,0,0,0,0,0,0,0,0,0,0,0,0,0,0,0,0,0,0,0,0,0,0,0,BM13,0,0,0)~
';
    'VSS'<579>:'(0,0,0,0,0,0,0,0,0,0,0,0,0,0,0,0,0,0,0,0,0,0,0,0,0,0,BM15,0,0,0)~
';
    'VSS'<578>:'(0,0,0,0,0,0,0,0,0,0,0,0,0,0,0,0,0,0,0,0,0,0,0,0,0,0,P59,0,0,0)';
    'VSS'<577>:'(0,0,0,0,0,0,0,0,0,0,0,0,0,0,0,0,0,0,0,0,0,0,0,0,0,0,BM25,0,0,0)~
';
    'VSS'<576>:'(0,0,0,0,0,0,0,0,0,0,0,0,0,0,0,0,0,0,0,0,0,0,0,0,0,0,BN6,0,0,0)';
    'VSS'<575>:'(0,0,0,0,0,0,0,0,0,0,0,0,0,0,0,0,0,0,0,0,0,0,0,0,0,0,BN10,0,0,0)~
';
    'VSS'<574>:'(0,0,0,0,0,0,0,0,0,0,0,0,0,0,0,0,0,0,0,0,0,0,0,0,0,0,BN20,0,0,0)~
';
    'VSS'<573>:'(0,0,0,0,0,0,0,0,0,0,0,0,0,0,0,0,0,0,0,0,0,0,0,0,0,0,BN26,0,0,0)~
';
    'VSS'<572>:'(0,0,0,0,0,0,0,0,0,0,0,0,0,0,0,0,0,0,0,0,0,0,0,0,0,0,BP3,0,0,0)';
    'VSS'<571>:'(0,0,0,0,0,0,0,0,0,0,0,0,0,0,0,0,0,0,0,0,0,0,0,0,0,0,BP27,0,0,0)~
';
    'VSS'<570>:'(0,0,0,0,0,0,0,0,0,0,0,0,0,0,0,0,0,0,0,0,0,0,0,0,0,0,BR6,0,0,0)';
    'VSS'<569>:'(0,0,0,0,0,0,0,0,0,0,0,0,0,0,0,0,0,0,0,0,0,0,0,0,0,0,BR10,0,0,0)~
';
    'VSS'<568>:'(0,0,0,0,0,0,0,0,0,0,0,0,0,0,0,0,0,0,0,0,0,0,0,0,0,0,BR16,0,0,0)~
';
    'VSS'<567>:'(0,0,0,0,0,0,0,0,0,0,0,0,0,0,0,0,0,0,0,0,0,0,0,0,0,0,P57,0,0,0)';
    'VSS'<566>:'(0,0,0,0,0,0,0,0,0,0,0,0,0,0,0,0,0,0,0,0,0,0,0,0,0,0,BR64,0,0,0)~
';
    'VSS'<565>:'(0,0,0,0,0,0,0,0,0,0,0,0,0,0,0,0,0,0,0,0,0,0,0,0,0,0,BR66,0,0,0)~
';
    'VSS'<564>:'(0,0,0,0,0,0,0,0,0,0,0,0,0,0,0,0,0,0,0,0,0,0,0,0,0,0,BR68,0,0,0)~
';
    'VSS'<563>:'(0,0,0,0,0,0,0,0,0,0,0,0,0,0,0,0,0,0,0,0,0,0,0,0,0,0,BR70,0,0,0)~
';
    'VSS'<562>:'(0,0,0,0,0,0,0,0,0,0,0,0,0,0,0,0,0,0,0,0,0,0,0,0,0,0,BR72,0,0,0)~
';
    'VSS'<561>:'(0,0,0,0,0,0,0,0,0,0,0,0,0,0,0,0,0,0,0,0,0,0,0,0,0,0,BR74,0,0,0)~
';
    'VSS'<560>:'(0,0,0,0,0,0,0,0,0,0,0,0,0,0,0,0,0,0,0,0,0,0,0,0,0,0,BR76,0,0,0)~
';
    'VSS'<559>:'(0,0,0,0,0,0,0,0,0,0,0,0,0,0,0,0,0,0,0,0,0,0,0,0,0,0,BR78,0,0,0)~
';
    'VSS'<558>:'(0,0,0,0,0,0,0,0,0,0,0,0,0,0,0,0,0,0,0,0,0,0,0,0,0,0,BR80,0,0,0)~
';
    'VSS'<557>:'(0,0,0,0,0,0,0,0,0,0,0,0,0,0,0,0,0,0,0,0,0,0,0,0,0,0,BR82,0,0,0)~
';
    'VSS'<556>:'(0,0,0,0,0,0,0,0,0,0,0,0,0,0,0,0,0,0,0,0,0,0,0,0,0,0,BT3,0,0,0)';
    'VSS'<555>:'(0,0,0,0,0,0,0,0,0,0,0,0,0,0,0,0,0,0,0,0,0,0,0,0,0,0,BT5,0,0,0)';
    'VSS'<554>:'(0,0,0,0,0,0,0,0,0,0,0,0,0,0,0,0,0,0,0,0,0,0,0,0,0,0,BT21,0,0,0)~
';
    'VSS'<553>:'(0,0,0,0,0,0,0,0,0,0,0,0,0,0,0,0,0,0,0,0,0,0,0,0,0,0,BT23,0,0,0)~
';
    'VSS'<552>:'(0,0,0,0,0,0,0,0,0,0,0,0,0,0,0,0,0,0,0,0,0,0,0,0,0,0,BT25,0,0,0)~
';
    'VSS'<551>:'(0,0,0,0,0,0,0,0,0,0,0,0,0,0,0,0,0,0,0,0,0,0,0,0,0,0,BU8,0,0,0)';
    'VSS'<550>:'(0,0,0,0,0,0,0,0,0,0,0,0,0,0,0,0,0,0,0,0,0,0,0,0,0,0,BV5,0,0,0)';
    'VSS'<549>:'(0,0,0,0,0,0,0,0,0,0,0,0,0,0,0,0,0,0,0,0,0,0,0,0,0,0,BU10,0,0,0)~
';
    'VSS'<548>:'(0,0,0,0,0,0,0,0,0,0,0,0,0,0,0,0,0,0,0,0,0,0,0,0,0,0,BV17,0,0,0)~
';
    'VSS'<547>:'(0,0,0,0,0,0,0,0,0,0,0,0,0,0,0,0,0,0,0,0,0,0,0,0,0,0,BV25,0,0,0)~
';
    'VSS'<546>:'(0,0,0,0,0,0,0,0,0,0,0,0,0,0,0,0,0,0,0,0,0,0,0,0,0,0,BW6,0,0,0)';
    'VSS'<545>:'(0,0,0,0,0,0,0,0,0,0,0,0,0,0,0,0,0,0,0,0,0,0,0,0,0,0,P55,0,0,0)';
    'VSS'<544>:'(0,0,0,0,0,0,0,0,0,0,0,0,0,0,0,0,0,0,0,0,0,0,0,0,0,0,BW12,0,0,0)~
';
    'VSS'<543>:'(0,0,0,0,0,0,0,0,0,0,0,0,0,0,0,0,0,0,0,0,0,0,0,0,0,0,BW14,0,0,0)~
';
    'VSS'<542>:'(0,0,0,0,0,0,0,0,0,0,0,0,0,0,0,0,0,0,0,0,0,0,0,0,0,0,BW16,0,0,0)~
';
    'VSS'<541>:'(0,0,0,0,0,0,0,0,0,0,0,0,0,0,0,0,0,0,0,0,0,0,0,0,0,0,BW18,0,0,0)~
';
    'VSS'<540>:'(0,0,0,0,0,0,0,0,0,0,0,0,0,0,0,0,0,0,0,0,0,0,0,0,0,0,BW26,0,0,0)~
';
    'VSS'<539>:'(0,0,0,0,0,0,0,0,0,0,0,0,0,0,0,0,0,0,0,0,0,0,0,0,0,0,BW72,0,0,0)~
';
    'VSS'<538>:'(0,0,0,0,0,0,0,0,0,0,0,0,0,0,0,0,0,0,0,0,0,0,0,0,0,0,BW74,0,0,0)~
';
    'VSS'<537>:'(0,0,0,0,0,0,0,0,0,0,0,0,0,0,0,0,0,0,0,0,0,0,0,0,0,0,BW76,0,0,0)~
';
    'VSS'<536>:'(0,0,0,0,0,0,0,0,0,0,0,0,0,0,0,0,0,0,0,0,0,0,0,0,0,0,BW78,0,0,0)~
';
    'VSS'<535>:'(0,0,0,0,0,0,0,0,0,0,0,0,0,0,0,0,0,0,0,0,0,0,0,0,0,0,BW80,0,0,0)~
';
    'VSS'<534>:'(0,0,0,0,0,0,0,0,0,0,0,0,0,0,0,0,0,0,0,0,0,0,0,0,0,0,BW82,0,0,0)~
';
    'VSS'<533>:'(0,0,0,0,0,0,0,0,0,0,0,0,0,0,0,0,0,0,0,0,0,0,0,0,0,0,BY11,0,0,0)~
';
    'VSS'<532>:'(0,0,0,0,0,0,0,0,0,0,0,0,0,0,0,0,0,0,0,0,0,0,0,0,0,0,BY13,0,0,0)~
';
    'VSS'<531>:'(0,0,0,0,0,0,0,0,0,0,0,0,0,0,0,0,0,0,0,0,0,0,0,0,0,0,BY23,0,0,0)~
';
    'VSS'<530>:'(0,0,0,0,0,0,0,0,0,0,0,0,0,0,0,0,0,0,0,0,0,0,0,0,0,0,BY63,0,0,0)~
';
    'VSS'<529>:'(0,0,0,0,0,0,0,0,0,0,0,0,0,0,0,0,0,0,0,0,0,0,0,0,0,0,BY65,0,0,0)~
';
    'VSS'<528>:'(0,0,0,0,0,0,0,0,0,0,0,0,0,0,0,0,0,0,0,0,0,0,0,0,0,0,BY67,0,0,0)~
';
    'VSS'<527>:'(0,0,0,0,0,0,0,0,0,0,0,0,0,0,0,0,0,0,0,0,0,0,0,0,0,0,BY69,0,0,0)~
';
    'VSS'<526>:'(0,0,0,0,0,0,0,0,0,0,0,0,0,0,0,0,0,0,0,0,0,0,0,0,0,0,BY71,0,0,0)~
';
    'VSS'<525>:'(0,0,0,0,0,0,0,0,0,0,0,0,0,0,0,0,0,0,0,0,0,0,0,0,0,0,CA2,0,0,0)';
    'VSS'<524>:'(0,0,0,0,0,0,0,0,0,0,0,0,0,0,0,0,0,0,0,0,0,0,0,0,0,0,CA6,0,0,0)';
    'VSS'<523>:'(0,0,0,0,0,0,0,0,0,0,0,0,0,0,0,0,0,0,0,0,0,0,0,0,0,0,CA8,0,0,0)';
    'VSS'<522>:'(0,0,0,0,0,0,0,0,0,0,0,0,0,0,0,0,0,0,0,0,0,0,0,0,0,0,CA10,0,0,0)~
';
    'VSS'<521>:'(0,0,0,0,0,0,0,0,0,0,0,0,0,0,0,0,0,0,0,0,0,0,0,0,0,0,CA14,0,0,0)~
';
    'VSS'<520>:'(0,0,0,0,0,0,0,0,0,0,0,0,0,0,0,0,0,0,0,0,0,0,0,0,0,0,CA18,0,0,0)~
';
    'VSS'<519>:'(0,0,0,0,0,0,0,0,0,0,0,0,0,0,0,0,0,0,0,0,0,0,0,0,0,0,CA26,0,0,0)~
';
    'VSS'<518>:'(0,0,0,0,0,0,0,0,0,0,0,0,0,0,0,0,0,0,0,0,0,0,0,0,0,0,CA64,0,0,0)~
';
    'VSS'<517>:'(0,0,0,0,0,0,0,0,0,0,0,0,0,0,0,0,0,0,0,0,0,0,0,0,0,0,CA66,0,0,0)~
';
    'VSS'<516>:'(0,0,0,0,0,0,0,0,0,0,0,0,0,0,0,0,0,0,0,0,0,0,0,0,0,0,CA68,0,0,0)~
';
    'VSS'<515>:'(0,0,0,0,0,0,0,0,0,0,0,0,0,0,0,0,0,0,0,0,0,0,0,0,0,0,CA70,0,0,0)~
';
    'VSS'<514>:'(0,0,0,0,0,0,0,0,0,0,0,0,0,0,0,0,0,0,0,0,0,0,0,0,0,0,CB7,0,0,0)';
    'VSS'<513>:'(0,0,0,0,0,0,0,0,0,0,0,0,0,0,0,0,0,0,0,0,0,0,0,0,0,0,CB9,0,0,0)';
    'VSS'<512>:'(0,0,0,0,0,0,0,0,0,0,0,0,0,0,0,0,0,0,0,0,0,0,0,0,0,0,CB27,0,0,0)~
';
    'VSS'<511>:'(0,0,0,0,0,0,0,0,0,0,0,0,0,0,0,0,0,0,0,0,0,0,0,0,0,0,CB63,0,0,0)~
';
    'VSS'<510>:'(0,0,0,0,0,0,0,0,0,0,0,0,0,0,0,0,0,0,0,0,0,0,0,0,0,0,CB71,0,0,0)~
';
    'VSS'<509>:'(0,0,0,0,0,0,0,0,0,0,0,0,0,0,0,0,0,0,0,0,0,0,0,0,0,0,CC4,0,0,0)';
    'VSS'<508>:'(0,0,0,0,0,0,0,0,0,0,0,0,0,0,0,0,0,0,0,0,0,0,0,0,0,0,CC16,0,0,0)~
';
    'VSS'<507>:'(0,0,0,0,0,0,0,0,0,0,0,0,0,0,0,0,0,0,0,0,0,0,0,0,0,0,CC18,0,0,0)~
';
    'VSS'<506>:'(0,0,0,0,0,0,0,0,0,0,0,0,0,0,0,0,0,0,0,0,0,0,0,0,0,0,CC24,0,0,0)~
';
    'VSS'<505>:'(0,0,0,0,0,0,0,0,0,0,0,0,0,0,0,0,0,0,0,0,0,0,0,0,0,0,CC64,0,0,0)~
';
    'VSS'<504>:'(0,0,0,0,0,0,0,0,0,0,0,0,0,0,0,0,0,0,0,0,0,0,0,0,0,0,CC72,0,0,0)~
';
    'VSS'<503>:'(0,0,0,0,0,0,0,0,0,0,0,0,0,0,0,0,0,0,0,0,0,0,0,0,0,0,CC74,0,0,0)~
';
    'VSS'<502>:'(0,0,0,0,0,0,0,0,0,0,0,0,0,0,0,0,0,0,0,0,0,0,0,0,0,0,CC76,0,0,0)~
';
    'VSS'<501>:'(0,0,0,0,0,0,0,0,0,0,0,0,0,0,0,0,0,0,0,0,0,0,0,0,0,0,CC78,0,0,0)~
';
    'VSS'<500>:'(0,0,0,0,0,0,0,0,0,0,0,0,0,0,0,0,0,0,0,0,0,0,0,0,0,0,CC80,0,0,0)~
';
    'VSS'<499>:'(0,0,0,0,0,0,0,0,0,0,0,0,0,0,0,0,0,0,0,0,0,0,0,0,0,0,CC82,0,0,0)~
';
    'VSS'<498>:'(0,0,0,0,0,0,0,0,0,0,0,0,0,0,0,0,0,0,0,0,0,0,0,0,0,0,CD5,0,0,0)';
    'VSS'<497>:'(0,0,0,0,0,0,0,0,0,0,0,0,0,0,0,0,0,0,0,0,0,0,0,0,0,0,CD13,0,0,0)~
';
    'VSS'<496>:'(0,0,0,0,0,0,0,0,0,0,0,0,0,0,0,0,0,0,0,0,0,0,0,0,0,0,CD63,0,0,0)~
';
    'VSS'<495>:'(0,0,0,0,0,0,0,0,0,0,0,0,0,0,0,0,0,0,0,0,0,0,0,0,0,0,CD73,0,0,0)~
';
    'VSS'<494>:'(0,0,0,0,0,0,0,0,0,0,0,0,0,0,0,0,0,0,0,0,0,0,0,0,0,0,CD75,0,0,0)~
';
    'VSS'<493>:'(0,0,0,0,0,0,0,0,0,0,0,0,0,0,0,0,0,0,0,0,0,0,0,0,0,0,CD77,0,0,0)~
';
    'VSS'<492>:'(0,0,0,0,0,0,0,0,0,0,0,0,0,0,0,0,0,0,0,0,0,0,0,0,0,0,CD79,0,0,0)~
';
    'VSS'<491>:'(0,0,0,0,0,0,0,0,0,0,0,0,0,0,0,0,0,0,0,0,0,0,0,0,0,0,CD81,0,0,0)~
';
    'VSS'<490>:'(0,0,0,0,0,0,0,0,0,0,0,0,0,0,0,0,0,0,0,0,0,0,0,0,0,0,CE10,0,0,0)~
';
    'VSS'<489>:'(0,0,0,0,0,0,0,0,0,0,0,0,0,0,0,0,0,0,0,0,0,0,0,0,0,0,CE14,0,0,0)~
';
    'VSS'<488>:'(0,0,0,0,0,0,0,0,0,0,0,0,0,0,0,0,0,0,0,0,0,0,0,0,0,0,CE20,0,0,0)~
';
    'VSS'<487>:'(0,0,0,0,0,0,0,0,0,0,0,0,0,0,0,0,0,0,0,0,0,0,0,0,0,0,CE26,0,0,0)~
';
    'VSS'<486>:'(0,0,0,0,0,0,0,0,0,0,0,0,0,0,0,0,0,0,0,0,0,0,0,0,0,0,CE62,0,0,0)~
';
    'VSS'<485>:'(0,0,0,0,0,0,0,0,0,0,0,0,0,0,0,0,0,0,0,0,0,0,0,0,0,0,CE70,0,0,0)~
';
    'VSS'<484>:'(0,0,0,0,0,0,0,0,0,0,0,0,0,0,0,0,0,0,0,0,0,0,0,0,0,0,CE82,0,0,0)~
';
    'VSS'<483>:'(0,0,0,0,0,0,0,0,0,0,0,0,0,0,0,0,0,0,0,0,0,0,0,0,0,0,P53,0,0,0)';
    'VSS'<482>:'(0,0,0,0,0,0,0,0,0,0,0,0,0,0,0,0,0,0,0,0,0,0,0,0,0,0,CF9,0,0,0)';
    'VSS'<481>:'(0,0,0,0,0,0,0,0,0,0,0,0,0,0,0,0,0,0,0,0,0,0,0,0,0,0,CF63,0,0,0)~
';
    'VSS'<480>:'(0,0,0,0,0,0,0,0,0,0,0,0,0,0,0,0,0,0,0,0,0,0,0,0,0,0,CF69,0,0,0)~
';
    'VSS'<479>:'(0,0,0,0,0,0,0,0,0,0,0,0,0,0,0,0,0,0,0,0,0,0,0,0,0,0,CF71,0,0,0)~
';
    'VSS'<478>:'(0,0,0,0,0,0,0,0,0,0,0,0,0,0,0,0,0,0,0,0,0,0,0,0,0,0,CF77,0,0,0)~
';
    'VSS'<477>:'(0,0,0,0,0,0,0,0,0,0,0,0,0,0,0,0,0,0,0,0,0,0,0,0,0,0,CF83,0,0,0)~
';
    'VSS'<476>:'(0,0,0,0,0,0,0,0,0,0,0,0,0,0,0,0,0,0,0,0,0,0,0,0,0,0,P51,0,0,0)';
    'VSS'<475>:'(0,0,0,0,0,0,0,0,0,0,0,0,0,0,0,0,0,0,0,0,0,0,0,0,0,0,CG18,0,0,0)~
';
    'VSS'<474>:'(0,0,0,0,0,0,0,0,0,0,0,0,0,0,0,0,0,0,0,0,0,0,0,0,0,0,CG22,0,0,0)~
';
    'VSS'<473>:'(0,0,0,0,0,0,0,0,0,0,0,0,0,0,0,0,0,0,0,0,0,0,0,0,0,0,CG62,0,0,0)~
';
    'VSS'<472>:'(0,0,0,0,0,0,0,0,0,0,0,0,0,0,0,0,0,0,0,0,0,0,0,0,0,0,CG68,0,0,0)~
';
    'VSS'<471>:'(0,0,0,0,0,0,0,0,0,0,0,0,0,0,0,0,0,0,0,0,0,0,0,0,0,0,CG72,0,0,0)~
';
    'VSS'<470>:'(0,0,0,0,0,0,0,0,0,0,0,0,0,0,0,0,0,0,0,0,0,0,0,0,0,0,CG80,0,0,0)~
';
    'VSS'<469>:'(0,0,0,0,0,0,0,0,0,0,0,0,0,0,0,0,0,0,0,0,0,0,0,0,0,0,CH1,0,0,0)';
    'VSS'<468>:'(0,0,0,0,0,0,0,0,0,0,0,0,0,0,0,0,0,0,0,0,0,0,0,0,0,0,CH3,0,0,0)';
    'VSS'<467>:'(0,0,0,0,0,0,0,0,0,0,0,0,0,0,0,0,0,0,0,0,0,0,0,0,0,0,CH15,0,0,0)~
';
    'VSS'<466>:'(0,0,0,0,0,0,0,0,0,0,0,0,0,0,0,0,0,0,0,0,0,0,0,0,0,0,CH19,0,0,0)~
';
    'VSS'<465>:'(0,0,0,0,0,0,0,0,0,0,0,0,0,0,0,0,0,0,0,0,0,0,0,0,0,0,CH63,0,0,0)~
';
    'VSS'<464>:'(0,0,0,0,0,0,0,0,0,0,0,0,0,0,0,0,0,0,0,0,0,0,0,0,0,0,CH67,0,0,0)~
';
    'VSS'<463>:'(0,0,0,0,0,0,0,0,0,0,0,0,0,0,0,0,0,0,0,0,0,0,0,0,0,0,CH73,0,0,0)~
';
    'VSS'<462>:'(0,0,0,0,0,0,0,0,0,0,0,0,0,0,0,0,0,0,0,0,0,0,0,0,0,0,CH79,0,0,0)~
';
    'VSS'<461>:'(0,0,0,0,0,0,0,0,0,0,0,0,0,0,0,0,0,0,0,0,0,0,0,0,0,0,CH81,0,0,0)~
';
    'VSS'<460>:'(0,0,0,0,0,0,0,0,0,0,0,0,0,0,0,0,0,0,0,0,0,0,0,0,0,0,CH83,0,0,0)~
';
    'VSS'<459>:'(0,0,0,0,0,0,0,0,0,0,0,0,0,0,0,0,0,0,0,0,0,0,0,0,0,0,CJ2,0,0,0)';
    'VSS'<458>:'(0,0,0,0,0,0,0,0,0,0,0,0,0,0,0,0,0,0,0,0,0,0,0,0,0,0,CJ6,0,0,0)';
    'VSS'<457>:'(0,0,0,0,0,0,0,0,0,0,0,0,0,0,0,0,0,0,0,0,0,0,0,0,0,0,CJ8,0,0,0)';
    'VSS'<456>:'(0,0,0,0,0,0,0,0,0,0,0,0,0,0,0,0,0,0,0,0,0,0,0,0,0,0,CJ10,0,0,0)~
';
    'VSS'<455>:'(0,0,0,0,0,0,0,0,0,0,0,0,0,0,0,0,0,0,0,0,0,0,0,0,0,0,CJ12,0,0,0)~
';
    'VSS'<454>:'(0,0,0,0,0,0,0,0,0,0,0,0,0,0,0,0,0,0,0,0,0,0,0,0,0,0,P49,0,0,0)';
    'VSS'<453>:'(0,0,0,0,0,0,0,0,0,0,0,0,0,0,0,0,0,0,0,0,0,0,0,0,0,0,0,P47,0,0)';
    'VSS'<452>:'(0,0,0,0,0,0,0,0,0,0,0,0,0,0,0,0,0,0,0,0,0,0,0,0,0,0,0,CJ62,0,0)~
';
    'VSS'<451>:'(0,0,0,0,0,0,0,0,0,0,0,0,0,0,0,0,0,0,0,0,0,0,0,0,0,0,0,CJ74,0,0)~
';
    'VSS'<450>:'(0,0,0,0,0,0,0,0,0,0,0,0,0,0,0,0,0,0,0,0,0,0,0,0,0,0,0,CJ76,0,0)~
';
    'VSS'<449>:'(0,0,0,0,0,0,0,0,0,0,0,0,0,0,0,0,0,0,0,0,0,0,0,0,0,0,0,CJ78,0,0)~
';
    'VSS'<448>:'(0,0,0,0,0,0,0,0,0,0,0,0,0,0,0,0,0,0,0,0,0,0,0,0,0,0,0,CJ82,0,0)~
';
    'VSS'<447>:'(0,0,0,0,0,0,0,0,0,0,0,0,0,0,0,0,0,0,0,0,0,0,0,0,0,0,0,CJ84,0,0)~
';
    'VSS'<446>:'(0,0,0,0,0,0,0,0,0,0,0,0,0,0,0,0,0,0,0,0,0,0,0,0,0,0,0,CJ86,0,0)~
';
    'VSS'<445>:'(0,0,0,0,0,0,0,0,0,0,0,0,0,0,0,0,0,0,0,0,0,0,0,0,0,0,0,CK11,0,0)~
';
    'VSS'<444>:'(0,0,0,0,0,0,0,0,0,0,0,0,0,0,0,0,0,0,0,0,0,0,0,0,0,0,0,CK15,0,0)~
';
    'VSS'<443>:'(0,0,0,0,0,0,0,0,0,0,0,0,0,0,0,0,0,0,0,0,0,0,0,0,0,0,0,CK21,0,0)~
';
    'VSS'<442>:'(0,0,0,0,0,0,0,0,0,0,0,0,0,0,0,0,0,0,0,0,0,0,0,0,0,0,0,CK27,0,0)~
';
    'VSS'<441>:'(0,0,0,0,0,0,0,0,0,0,0,0,0,0,0,0,0,0,0,0,0,0,0,0,0,0,0,CK63,0,0)~
';
    'VSS'<440>:'(0,0,0,0,0,0,0,0,0,0,0,0,0,0,0,0,0,0,0,0,0,0,0,0,0,0,0,CK65,0,0)~
';
    'VSS'<439>:'(0,0,0,0,0,0,0,0,0,0,0,0,0,0,0,0,0,0,0,0,0,0,0,0,0,0,0,CK67,0,0)~
';
    'VSS'<438>:'(0,0,0,0,0,0,0,0,0,0,0,0,0,0,0,0,0,0,0,0,0,0,0,0,0,0,0,CK69,0,0)~
';
    'VSS'<437>:'(0,0,0,0,0,0,0,0,0,0,0,0,0,0,0,0,0,0,0,0,0,0,0,0,0,0,0,CK71,0,0)~
';
    'VSS'<436>:'(0,0,0,0,0,0,0,0,0,0,0,0,0,0,0,0,0,0,0,0,0,0,0,0,0,0,0,CK73,0,0)~
';
    'VSS'<435>:'(0,0,0,0,0,0,0,0,0,0,0,0,0,0,0,0,0,0,0,0,0,0,0,0,0,0,0,CK75,0,0)~
';
    'VSS'<434>:'(0,0,0,0,0,0,0,0,0,0,0,0,0,0,0,0,0,0,0,0,0,0,0,0,0,0,0,CK83,0,0)~
';
    'VSS'<433>:'(0,0,0,0,0,0,0,0,0,0,0,0,0,0,0,0,0,0,0,0,0,0,0,0,0,0,0,CK85,0,0)~
';
    'VSS'<432>:'(0,0,0,0,0,0,0,0,0,0,0,0,0,0,0,0,0,0,0,0,0,0,0,0,0,0,0,CL8,0,0)';
    'VSS'<431>:'(0,0,0,0,0,0,0,0,0,0,0,0,0,0,0,0,0,0,0,0,0,0,0,0,0,0,0,CL14,0,0)~
';
    'VSS'<430>:'(0,0,0,0,0,0,0,0,0,0,0,0,0,0,0,0,0,0,0,0,0,0,0,0,0,0,0,CL18,0,0)~
';
    'VSS'<429>:'(0,0,0,0,0,0,0,0,0,0,0,0,0,0,0,0,0,0,0,0,0,0,0,0,0,0,0,P45,0,0)';
    'VSS'<428>:'(0,0,0,0,0,0,0,0,0,0,0,0,0,0,0,0,0,0,0,0,0,0,0,0,0,0,0,H63,0,0)';
    'VSS'<427>:'(0,0,0,0,0,0,0,0,0,0,0,0,0,0,0,0,0,0,0,0,0,0,0,0,0,0,0,CL62,0,0)~
';
    'VSS'<426>:'(0,0,0,0,0,0,0,0,0,0,0,0,0,0,0,0,0,0,0,0,0,0,0,0,0,0,0,CL64,0,0)~
';
    'VSS'<425>:'(0,0,0,0,0,0,0,0,0,0,0,0,0,0,0,0,0,0,0,0,0,0,0,0,0,0,0,CL66,0,0)~
';
    'VSS'<424>:'(0,0,0,0,0,0,0,0,0,0,0,0,0,0,0,0,0,0,0,0,0,0,0,0,0,0,0,CL74,0,0)~
';
    'VSS'<423>:'(0,0,0,0,0,0,0,0,0,0,0,0,0,0,0,0,0,0,0,0,0,0,0,0,0,0,0,CL76,0,0)~
';
    'VSS'<422>:'(0,0,0,0,0,0,0,0,0,0,0,0,0,0,0,0,0,0,0,0,0,0,0,0,0,0,0,CL78,0,0)~
';
    'VSS'<421>:'(0,0,0,0,0,0,0,0,0,0,0,0,0,0,0,0,0,0,0,0,0,0,0,0,0,0,0,CL80,0,0)~
';
    'VSS'<420>:'(0,0,0,0,0,0,0,0,0,0,0,0,0,0,0,0,0,0,0,0,0,0,0,0,0,0,0,CM19,0,0)~
';
    'VSS'<419>:'(0,0,0,0,0,0,0,0,0,0,0,0,0,0,0,0,0,0,0,0,0,0,0,0,0,0,0,CM29,0,0)~
';
    'VSS'<418>:'(0,0,0,0,0,0,0,0,0,0,0,0,0,0,0,0,0,0,0,0,0,0,0,0,0,0,0,CM5,0,0)';
    'VSS'<417>:'(0,0,0,0,0,0,0,0,0,0,0,0,0,0,0,0,0,0,0,0,0,0,0,0,0,0,0,CM31,0,0)~
';
    'VSS'<416>:'(0,0,0,0,0,0,0,0,0,0,0,0,0,0,0,0,0,0,0,0,0,0,0,0,0,0,0,CM61,0,0)~
';
    'VSS'<415>:'(0,0,0,0,0,0,0,0,0,0,0,0,0,0,0,0,0,0,0,0,0,0,0,0,0,0,0,CM63,0,0)~
';
    'VSS'<414>:'(0,0,0,0,0,0,0,0,0,0,0,0,0,0,0,0,0,0,0,0,0,0,0,0,0,0,0,CM67,0,0)~
';
    'VSS'<413>:'(0,0,0,0,0,0,0,0,0,0,0,0,0,0,0,0,0,0,0,0,0,0,0,0,0,0,0,CM73,0,0)~
';
    'VSS'<412>:'(0,0,0,0,0,0,0,0,0,0,0,0,0,0,0,0,0,0,0,0,0,0,0,0,0,0,0,CM77,0,0)~
';
    'VSS'<411>:'(0,0,0,0,0,0,0,0,0,0,0,0,0,0,0,0,0,0,0,0,0,0,0,0,0,0,0,CM83,0,0)~
';
    'VSS'<410>:'(0,0,0,0,0,0,0,0,0,0,0,0,0,0,0,0,0,0,0,0,0,0,0,0,0,0,0,CM85,0,0)~
';
    'VSS'<409>:'(0,0,0,0,0,0,0,0,0,0,0,0,0,0,0,0,0,0,0,0,0,0,0,0,0,0,0,CN2,0,0)';
    'VSS'<408>:'(0,0,0,0,0,0,0,0,0,0,0,0,0,0,0,0,0,0,0,0,0,0,0,0,0,0,0,CN12,0,0)~
';
    'VSS'<407>:'(0,0,0,0,0,0,0,0,0,0,0,0,0,0,0,0,0,0,0,0,0,0,0,0,0,0,0,H61,0,0)';
    'VSS'<406>:'(0,0,0,0,0,0,0,0,0,0,0,0,0,0,0,0,0,0,0,0,0,0,0,0,0,0,0,CN26,0,0)~
';
    'VSS'<405>:'(0,0,0,0,0,0,0,0,0,0,0,0,0,0,0,0,0,0,0,0,0,0,0,0,0,0,0,CN32,0,0)~
';
    'VSS'<404>:'(0,0,0,0,0,0,0,0,0,0,0,0,0,0,0,0,0,0,0,0,0,0,0,0,0,0,0,CN60,0,0)~
';
    'VSS'<403>:'(0,0,0,0,0,0,0,0,0,0,0,0,0,0,0,0,0,0,0,0,0,0,0,0,0,0,0,CN62,0,0)~
';
    'VSS'<402>:'(0,0,0,0,0,0,0,0,0,0,0,0,0,0,0,0,0,0,0,0,0,0,0,0,0,0,0,CN68,0,0)~
';
    'VSS'<401>:'(0,0,0,0,0,0,0,0,0,0,0,0,0,0,0,0,0,0,0,0,0,0,0,0,0,0,0,CN78,0,0)~
';
    'VSS'<400>:'(0,0,0,0,0,0,0,0,0,0,0,0,0,0,0,0,0,0,0,0,0,0,0,0,0,0,0,CP1,0,0)';
    'VSS'<399>:'(0,0,0,0,0,0,0,0,0,0,0,0,0,0,0,0,0,0,0,0,0,0,0,0,0,0,0,H59,0,0)';
    'VSS'<398>:'(0,0,0,0,0,0,0,0,0,0,0,0,0,0,0,0,0,0,0,0,0,0,0,0,0,0,0,CP25,0,0)~
';
    'VSS'<397>:'(0,0,0,0,0,0,0,0,0,0,0,0,0,0,0,0,0,0,0,0,0,0,0,0,0,0,0,CP59,0,0)~
';
    'VSS'<396>:'(0,0,0,0,0,0,0,0,0,0,0,0,0,0,0,0,0,0,0,0,0,0,0,0,0,0,0,CP69,0,0)~
';
    'VSS'<395>:'(0,0,0,0,0,0,0,0,0,0,0,0,0,0,0,0,0,0,0,0,0,0,0,0,0,0,0,CP73,0,0)~
';
    'VSS'<394>:'(0,0,0,0,0,0,0,0,0,0,0,0,0,0,0,0,0,0,0,0,0,0,0,0,0,0,0,CP75,0,0)~
';
    'VSS'<393>:'(0,0,0,0,0,0,0,0,0,0,0,0,0,0,0,0,0,0,0,0,0,0,0,0,0,0,0,CP81,0,0)~
';
    'VSS'<392>:'(0,0,0,0,0,0,0,0,0,0,0,0,0,0,0,0,0,0,0,0,0,0,0,0,0,0,0,CP83,0,0)~
';
    'VSS'<391>:'(0,0,0,0,0,0,0,0,0,0,0,0,0,0,0,0,0,0,0,0,0,0,0,0,0,0,0,CR6,0,0)';
    'VSS'<390>:'(0,0,0,0,0,0,0,0,0,0,0,0,0,0,0,0,0,0,0,0,0,0,0,0,0,0,0,CR10,0,0)~
';
    'VSS'<389>:'(0,0,0,0,0,0,0,0,0,0,0,0,0,0,0,0,0,0,0,0,0,0,0,0,0,0,0,CR22,0,0)~
';
    'VSS'<388>:'(0,0,0,0,0,0,0,0,0,0,0,0,0,0,0,0,0,0,0,0,0,0,0,0,0,0,0,CR24,0,0)~
';
    'VSS'<387>:'(0,0,0,0,0,0,0,0,0,0,0,0,0,0,0,0,0,0,0,0,0,0,0,0,0,0,0,CR32,0,0)~
';
    'VSS'<386>:'(0,0,0,0,0,0,0,0,0,0,0,0,0,0,0,0,0,0,0,0,0,0,0,0,0,0,0,CR58,0,0)~
';
    'VSS'<385>:'(0,0,0,0,0,0,0,0,0,0,0,0,0,0,0,0,0,0,0,0,0,0,0,0,0,0,0,CR62,0,0)~
';
    'VSS'<384>:'(0,0,0,0,0,0,0,0,0,0,0,0,0,0,0,0,0,0,0,0,0,0,0,0,0,0,0,CR64,0,0)~
';
    'VSS'<383>:'(0,0,0,0,0,0,0,0,0,0,0,0,0,0,0,0,0,0,0,0,0,0,0,0,0,0,0,CR66,0,0)~
';
    'VSS'<382>:'(0,0,0,0,0,0,0,0,0,0,0,0,0,0,0,0,0,0,0,0,0,0,0,0,0,0,0,CR68,0,0)~
';
    'VSS'<381>:'(0,0,0,0,0,0,0,0,0,0,0,0,0,0,0,0,0,0,0,0,0,0,0,0,0,0,0,CR78,0,0)~
';
    'VSS'<380>:'(0,0,0,0,0,0,0,0,0,0,0,0,0,0,0,0,0,0,0,0,0,0,0,0,0,0,0,CR86,0,0)~
';
    'VSS'<379>:'(0,0,0,0,0,0,0,0,0,0,0,0,0,0,0,0,0,0,0,0,0,0,0,0,0,0,0,H57,0,0)';
    'VSS'<378>:'(0,0,0,0,0,0,0,0,0,0,0,0,0,0,0,0,0,0,0,0,0,0,0,0,0,0,0,CT13,0,0)~
';
    'VSS'<377>:'(0,0,0,0,0,0,0,0,0,0,0,0,0,0,0,0,0,0,0,0,0,0,0,0,0,0,0,CT19,0,0)~
';
    'VSS'<376>:'(0,0,0,0,0,0,0,0,0,0,0,0,0,0,0,0,0,0,0,0,0,0,0,0,0,0,0,CT27,0,0)~
';
    'VSS'<375>:'(0,0,0,0,0,0,0,0,0,0,0,0,0,0,0,0,0,0,0,0,0,0,0,0,0,0,0,CT29,0,0)~
';
    'VSS'<374>:'(0,0,0,0,0,0,0,0,0,0,0,0,0,0,0,0,0,0,0,0,0,0,0,0,0,0,0,CT33,0,0)~
';
    'VSS'<373>:'(0,0,0,0,0,0,0,0,0,0,0,0,0,0,0,0,0,0,0,0,0,0,0,0,0,0,0,CT35,0,0)~
';
    'VSS'<372>:'(0,0,0,0,0,0,0,0,0,0,0,0,0,0,0,0,0,0,0,0,0,0,0,0,0,0,0,CT57,0,0)~
';
    'VSS'<371>:'(0,0,0,0,0,0,0,0,0,0,0,0,0,0,0,0,0,0,0,0,0,0,0,0,0,0,0,CT73,0,0)~
';
    'VSS'<370>:'(0,0,0,0,0,0,0,0,0,0,0,0,0,0,0,0,0,0,0,0,0,0,0,0,0,0,0,CT79,0,0)~
';
    'VSS'<369>:'(0,0,0,0,0,0,0,0,0,0,0,0,0,0,0,0,0,0,0,0,0,0,0,0,0,0,0,CT83,0,0)~
';
    'VSS'<368>:'(0,0,0,0,0,0,0,0,0,0,0,0,0,0,0,0,0,0,0,0,0,0,0,0,0,0,0,CT85,0,0)~
';
    'VSS'<367>:'(0,0,0,0,0,0,0,0,0,0,0,0,0,0,0,0,0,0,0,0,0,0,0,0,0,0,0,CU4,0,0)';
    'VSS'<366>:'(0,0,0,0,0,0,0,0,0,0,0,0,0,0,0,0,0,0,0,0,0,0,0,0,0,0,0,CU22,0,0)~
';
    'VSS'<365>:'(0,0,0,0,0,0,0,0,0,0,0,0,0,0,0,0,0,0,0,0,0,0,0,0,0,0,0,CU28,0,0)~
';
    'VSS'<364>:'(0,0,0,0,0,0,0,0,0,0,0,0,0,0,0,0,0,0,0,0,0,0,0,0,0,0,0,CU30,0,0)~
';
    'VSS'<363>:'(0,0,0,0,0,0,0,0,0,0,0,0,0,0,0,0,0,0,0,0,0,0,0,0,0,0,0,CU34,0,0)~
';
    'VSS'<362>:'(0,0,0,0,0,0,0,0,0,0,0,0,0,0,0,0,0,0,0,0,0,0,0,0,0,0,0,CU36,0,0)~
';
    'VSS'<361>:'(0,0,0,0,0,0,0,0,0,0,0,0,0,0,0,0,0,0,0,0,0,0,0,0,0,0,0,CU56,0,0)~
';
    'VSS'<360>:'(0,0,0,0,0,0,0,0,0,0,0,0,0,0,0,0,0,0,0,0,0,0,0,0,0,0,0,CU62,0,0)~
';
    'VSS'<359>:'(0,0,0,0,0,0,0,0,0,0,0,0,0,0,0,0,0,0,0,0,0,0,0,0,0,0,0,CU68,0,0)~
';
    'VSS'<358>:'(0,0,0,0,0,0,0,0,0,0,0,0,0,0,0,0,0,0,0,0,0,0,0,0,0,0,0,CU76,0,0)~
';
    'VSS'<357>:'(0,0,0,0,0,0,0,0,0,0,0,0,0,0,0,0,0,0,0,0,0,0,0,0,0,0,0,CU78,0,0)~
';
    'VSS'<356>:'(0,0,0,0,0,0,0,0,0,0,0,0,0,0,0,0,0,0,0,0,0,0,0,0,0,0,0,CU80,0,0)~
';
    'VSS'<355>:'(0,0,0,0,0,0,0,0,0,0,0,0,0,0,0,0,0,0,0,0,0,0,0,0,0,0,0,CU82,0,0)~
';
    'VSS'<354>:'(0,0,0,0,0,0,0,0,0,0,0,0,0,0,0,0,0,0,0,0,0,0,0,0,0,0,0,CU86,0,0)~
';
    'VSS'<353>:'(0,0,0,0,0,0,0,0,0,0,0,0,0,0,0,0,0,0,0,0,0,0,0,0,0,0,0,CV1,0,0)';
    'VSS'<352>:'(0,0,0,0,0,0,0,0,0,0,0,0,0,0,0,0,0,0,0,0,0,0,0,0,0,0,0,H55,0,0)';
    'VSS'<351>:'(0,0,0,0,0,0,0,0,0,0,0,0,0,0,0,0,0,0,0,0,0,0,0,0,0,0,0,CV17,0,0)~
';
    'VSS'<350>:'(0,0,0,0,0,0,0,0,0,0,0,0,0,0,0,0,0,0,0,0,0,0,0,0,0,0,0,CV25,0,0)~
';
    'VSS'<349>:'(0,0,0,0,0,0,0,0,0,0,0,0,0,0,0,0,0,0,0,0,0,0,0,0,0,0,0,CV27,0,0)~
';
    'VSS'<348>:'(0,0,0,0,0,0,0,0,0,0,0,0,0,0,0,0,0,0,0,0,0,0,0,0,0,0,0,CV31,0,0)~
';
    'VSS'<347>:'(0,0,0,0,0,0,0,0,0,0,0,0,0,0,0,0,0,0,0,0,0,0,0,0,0,0,0,CV33,0,0)~
';
    'VSS'<346>:'(0,0,0,0,0,0,0,0,0,0,0,0,0,0,0,0,0,0,0,0,0,0,0,0,0,0,0,CV37,0,0)~
';
    'VSS'<345>:'(0,0,0,0,0,0,0,0,0,0,0,0,0,0,0,0,0,0,0,0,0,0,0,0,0,0,0,CV39,0,0)~
';
    'VSS'<344>:'(0,0,0,0,0,0,0,0,0,0,0,0,0,0,0,0,0,0,0,0,0,0,0,0,0,0,0,CV41,0,0)~
';
    'VSS'<343>:'(0,0,0,0,0,0,0,0,0,0,0,0,0,0,0,0,0,0,0,0,0,0,0,0,0,0,0,CV53,0,0)~
';
    'VSS'<342>:'(0,0,0,0,0,0,0,0,0,0,0,0,0,0,0,0,0,0,0,0,0,0,0,0,0,0,0,CV55,0,0)~
';
    'VSS'<341>:'(0,0,0,0,0,0,0,0,0,0,0,0,0,0,0,0,0,0,0,0,0,0,0,0,0,0,0,CV63,0,0)~
';
    'VSS'<340>:'(0,0,0,0,0,0,0,0,0,0,0,0,0,0,0,0,0,0,0,0,0,0,0,0,0,0,0,CV67,0,0)~
';
    'VSS'<339>:'(0,0,0,0,0,0,0,0,0,0,0,0,0,0,0,0,0,0,0,0,0,0,0,0,0,0,0,CV73,0,0)~
';
    'VSS'<338>:'(0,0,0,0,0,0,0,0,0,0,0,0,0,0,0,0,0,0,0,0,0,0,0,0,0,0,0,CV79,0,0)~
';
    'VSS'<337>:'(0,0,0,0,0,0,0,0,0,0,0,0,0,0,0,0,0,0,0,0,0,0,0,0,0,0,0,CV81,0,0)~
';
    'VSS'<336>:'(0,0,0,0,0,0,0,0,0,0,0,0,0,0,0,0,0,0,0,0,0,0,0,0,0,0,0,CV83,0,0)~
';
    'VSS'<335>:'(0,0,0,0,0,0,0,0,0,0,0,0,0,0,0,0,0,0,0,0,0,0,0,0,0,0,0,CW12,0,0)~
';
    'VSS'<334>:'(0,0,0,0,0,0,0,0,0,0,0,0,0,0,0,0,0,0,0,0,0,0,0,0,0,0,0,CW26,0,0)~
';
    'VSS'<333>:'(0,0,0,0,0,0,0,0,0,0,0,0,0,0,0,0,0,0,0,0,0,0,0,0,0,0,0,CW32,0,0)~
';
    'VSS'<332>:'(0,0,0,0,0,0,0,0,0,0,0,0,0,0,0,0,0,0,0,0,0,0,0,0,0,0,0,CW38,0,0)~
';
    'VSS'<331>:'(0,0,0,0,0,0,0,0,0,0,0,0,0,0,0,0,0,0,0,0,0,0,0,0,0,0,0,CW40,0,0)~
';
    'VSS'<330>:'(0,0,0,0,0,0,0,0,0,0,0,0,0,0,0,0,0,0,0,0,0,0,0,0,0,0,0,CW42,0,0)~
';
    'VSS'<329>:'(0,0,0,0,0,0,0,0,0,0,0,0,0,0,0,0,0,0,0,0,0,0,0,0,0,0,0,CW52,0,0)~
';
    'VSS'<328>:'(0,0,0,0,0,0,0,0,0,0,0,0,0,0,0,0,0,0,0,0,0,0,0,0,0,0,0,CW54,0,0)~
';
    'VSS'<327>:'(0,0,0,0,0,0,0,0,0,0,0,0,0,0,0,0,0,0,0,0,0,0,0,0,0,0,0,CW64,0,0)~
';
    'VSS'<326>:'(0,0,0,0,0,0,0,0,0,0,0,0,0,0,0,0,0,0,0,0,0,0,0,0,0,0,0,CW66,0,0)~
';
    'VSS'<325>:'(0,0,0,0,0,0,0,0,0,0,0,0,0,0,0,0,0,0,0,0,0,0,0,0,0,0,0,CW68,0,0)~
';
    'VSS'<324>:'(0,0,0,0,0,0,0,0,0,0,0,0,0,0,0,0,0,0,0,0,0,0,0,0,0,0,0,CW74,0,0)~
';
    'VSS'<323>:'(0,0,0,0,0,0,0,0,0,0,0,0,0,0,0,0,0,0,0,0,0,0,0,0,0,0,0,CW78,0,0)~
';
    'VSS'<322>:'(0,0,0,0,0,0,0,0,0,0,0,0,0,0,0,0,0,0,0,0,0,0,0,0,0,0,0,CW82,0,0)~
';
    'VSS'<321>:'(0,0,0,0,0,0,0,0,0,0,0,0,0,0,0,0,0,0,0,0,0,0,0,0,0,0,0,CY1,0,0)';
    'VSS'<320>:'(0,0,0,0,0,0,0,0,0,0,0,0,0,0,0,0,0,0,0,0,0,0,0,0,0,0,0,CY9,0,0)';
    'VSS'<319>:'(0,0,0,0,0,0,0,0,0,0,0,0,0,0,0,0,0,0,0,0,0,0,0,0,0,0,0,CY13,0,0)~
';
    'VSS'<318>:'(0,0,0,0,0,0,0,0,0,0,0,0,0,0,0,0,0,0,0,0,0,0,0,0,0,0,0,CY15,0,0)~
';
    'VSS'<317>:'(0,0,0,0,0,0,0,0,0,0,0,0,0,0,0,0,0,0,0,0,0,0,0,0,0,0,0,CY21,0,0)~
';
    'VSS'<316>:'(0,0,0,0,0,0,0,0,0,0,0,0,0,0,0,0,0,0,0,0,0,0,0,0,0,0,0,CY41,0,0)~
';
    'VSS'<315>:'(0,0,0,0,0,0,0,0,0,0,0,0,0,0,0,0,0,0,0,0,0,0,0,0,0,0,0,CY45,0,0)~
';
    'VSS'<314>:'(0,0,0,0,0,0,0,0,0,0,0,0,0,0,0,0,0,0,0,0,0,0,0,0,0,0,0,CY51,0,0)~
';
    'VSS'<313>:'(0,0,0,0,0,0,0,0,0,0,0,0,0,0,0,0,0,0,0,0,0,0,0,0,0,0,0,CY59,0,0)~
';
    'VSS'<312>:'(0,0,0,0,0,0,0,0,0,0,0,0,0,0,0,0,0,0,0,0,0,0,0,0,0,0,0,CY61,0,0)~
';
    'VSS'<311>:'(0,0,0,0,0,0,0,0,0,0,0,0,0,0,0,0,0,0,0,0,0,0,0,0,0,0,0,CY65,0,0)~
';
    'VSS'<310>:'(0,0,0,0,0,0,0,0,0,0,0,0,0,0,0,0,0,0,0,0,0,0,0,0,0,0,0,CY69,0,0)~
';
    'VSS'<309>:'(0,0,0,0,0,0,0,0,0,0,0,0,0,0,0,0,0,0,0,0,0,0,0,0,0,0,0,CY75,0,0)~
';
    'VSS'<308>:'(0,0,0,0,0,0,0,0,0,0,0,0,0,0,0,0,0,0,0,0,0,0,0,0,0,0,0,CY77,0,0)~
';
    'VSS'<307>:'(0,0,0,0,0,0,0,0,0,0,0,0,0,0,0,0,0,0,0,0,0,0,0,0,0,0,0,CY83,0,0)~
';
    'VSS'<306>:'(0,0,0,0,0,0,0,0,0,0,0,0,0,0,0,0,0,0,0,0,0,0,0,0,0,0,0,CY85,0,0)~
';
    'VSS'<305>:'(0,0,0,0,0,0,0,0,0,0,0,0,0,0,0,0,0,0,0,0,0,0,0,0,0,0,0,DA6,0,0)';
    'VSS'<304>:'(0,0,0,0,0,0,0,0,0,0,0,0,0,0,0,0,0,0,0,0,0,0,0,0,0,0,0,H53,0,0)';
    'VSS'<303>:'(0,0,0,0,0,0,0,0,0,0,0,0,0,0,0,0,0,0,0,0,0,0,0,0,0,0,0,DA18,0,0)~
';
    'VSS'<302>:'(0,0,0,0,0,0,0,0,0,0,0,0,0,0,0,0,0,0,0,0,0,0,0,0,0,0,0,DA26,0,0)~
';
    'VSS'<301>:'(0,0,0,0,0,0,0,0,0,0,0,0,0,0,0,0,0,0,0,0,0,0,0,0,0,0,0,DA28,0,0)~
';
    'VSS'<300>:'(0,0,0,0,0,0,0,0,0,0,0,0,0,0,0,0,0,0,0,0,0,0,0,0,0,0,0,DA30,0,0)~
';
    'VSS'<299>:'(0,0,0,0,0,0,0,0,0,0,0,0,0,0,0,0,0,0,0,0,0,0,0,0,0,0,0,DA32,0,0)~
';
    'VSS'<298>:'(0,0,0,0,0,0,0,0,0,0,0,0,0,0,0,0,0,0,0,0,0,0,0,0,0,0,0,DA34,0,0)~
';
    'VSS'<297>:'(0,0,0,0,0,0,0,0,0,0,0,0,0,0,0,0,0,0,0,0,0,0,0,0,0,0,0,DA36,0,0)~
';
    'VSS'<296>:'(0,0,0,0,0,0,0,0,0,0,0,0,0,0,0,0,0,0,0,0,0,0,0,0,0,0,0,DA38,0,0)~
';
    'VSS'<295>:'(0,0,0,0,0,0,0,0,0,0,0,0,0,0,0,0,0,0,0,0,0,0,0,0,0,0,0,DA44,0,0)~
';
    'VSS'<294>:'(0,0,0,0,0,0,0,0,0,0,0,0,0,0,0,0,0,0,0,0,0,0,0,0,0,0,0,DA46,0,0)~
';
    'VSS'<293>:'(0,0,0,0,0,0,0,0,0,0,0,0,0,0,0,0,0,0,0,0,0,0,0,0,0,0,0,0,DA48,0)~
';
    'VSS'<292>:'(0,0,0,0,0,0,0,0,0,0,0,0,0,0,0,0,0,0,0,0,0,0,0,0,0,0,0,0,DA50,0)~
';
    'VSS'<291>:'(0,0,0,0,0,0,0,0,0,0,0,0,0,0,0,0,0,0,0,0,0,0,0,0,0,0,0,0,DA64,0)~
';
    'VSS'<290>:'(0,0,0,0,0,0,0,0,0,0,0,0,0,0,0,0,0,0,0,0,0,0,0,0,0,0,0,0,DA70,0)~
';
    'VSS'<289>:'(0,0,0,0,0,0,0,0,0,0,0,0,0,0,0,0,0,0,0,0,0,0,0,0,0,0,0,0,DA74,0)~
';
    'VSS'<288>:'(0,0,0,0,0,0,0,0,0,0,0,0,0,0,0,0,0,0,0,0,0,0,0,0,0,0,0,0,DA76,0)~
';
    'VSS'<287>:'(0,0,0,0,0,0,0,0,0,0,0,0,0,0,0,0,0,0,0,0,0,0,0,0,0,0,0,0,DA78,0)~
';
    'VSS'<286>:'(0,0,0,0,0,0,0,0,0,0,0,0,0,0,0,0,0,0,0,0,0,0,0,0,0,0,0,0,DA80,0)~
';
    'VSS'<285>:'(0,0,0,0,0,0,0,0,0,0,0,0,0,0,0,0,0,0,0,0,0,0,0,0,0,0,0,0,DB3,0)';
    'VSS'<284>:'(0,0,0,0,0,0,0,0,0,0,0,0,0,0,0,0,0,0,0,0,0,0,0,0,0,0,0,0,DB13,0)~
';
    'VSS'<283>:'(0,0,0,0,0,0,0,0,0,0,0,0,0,0,0,0,0,0,0,0,0,0,0,0,0,0,0,0,DB17,0)~
';
    'VSS'<282>:'(0,0,0,0,0,0,0,0,0,0,0,0,0,0,0,0,0,0,0,0,0,0,0,0,0,0,0,0,DB23,0)~
';
    'VSS'<281>:'(0,0,0,0,0,0,0,0,0,0,0,0,0,0,0,0,0,0,0,0,0,0,0,0,0,0,0,0,DB25,0)~
';
    'VSS'<280>:'(0,0,0,0,0,0,0,0,0,0,0,0,0,0,0,0,0,0,0,0,0,0,0,0,0,0,0,0,DB39,0)~
';
    'VSS'<279>:'(0,0,0,0,0,0,0,0,0,0,0,0,0,0,0,0,0,0,0,0,0,0,0,0,0,0,0,0,DB41,0)~
';
    'VSS'<278>:'(0,0,0,0,0,0,0,0,0,0,0,0,0,0,0,0,0,0,0,0,0,0,0,0,0,0,0,0,DB47,0)~
';
    'VSS'<277>:'(0,0,0,0,0,0,0,0,0,0,0,0,0,0,0,0,0,0,0,0,0,0,0,0,0,0,0,0,DB49,0)~
';
    'VSS'<276>:'(0,0,0,0,0,0,0,0,0,0,0,0,0,0,0,0,0,0,0,0,0,0,0,0,0,0,0,0,DB73,0)~
';
    'VSS'<275>:'(0,0,0,0,0,0,0,0,0,0,0,0,0,0,0,0,0,0,0,0,0,0,0,0,0,0,0,0,DB77,0)~
';
    'VSS'<274>:'(0,0,0,0,0,0,0,0,0,0,0,0,0,0,0,0,0,0,0,0,0,0,0,0,0,0,0,0,DB83,0)~
';
    'VSS'<273>:'(0,0,0,0,0,0,0,0,0,0,0,0,0,0,0,0,0,0,0,0,0,0,0,0,0,0,0,0,DB85,0)~
';
    'VSS'<272>:'(0,0,0,0,0,0,0,0,0,0,0,0,0,0,0,0,0,0,0,0,0,0,0,0,0,0,0,0,DC14,0)~
';
    'VSS'<271>:'(0,0,0,0,0,0,0,0,0,0,0,0,0,0,0,0,0,0,0,0,0,0,0,0,0,0,0,0,DC24,0)~
';
    'VSS'<270>:'(0,0,0,0,0,0,0,0,0,0,0,0,0,0,0,0,0,0,0,0,0,0,0,0,0,0,0,0,DC26,0)~
';
    'VSS'<269>:'(0,0,0,0,0,0,0,0,0,0,0,0,0,0,0,0,0,0,0,0,0,0,0,0,0,0,0,0,DC32,0)~
';
    'VSS'<268>:'(0,0,0,0,0,0,0,0,0,0,0,0,0,0,0,0,0,0,0,0,0,0,0,0,0,0,0,0,DC38,0)~
';
    'VSS'<267>:'(0,0,0,0,0,0,0,0,0,0,0,0,0,0,0,0,0,0,0,0,0,0,0,0,0,0,0,0,DC42,0)~
';
    'VSS'<266>:'(0,0,0,0,0,0,0,0,0,0,0,0,0,0,0,0,0,0,0,0,0,0,0,0,0,0,0,0,DC64,0)~
';
    'VSS'<265>:'(0,0,0,0,0,0,0,0,0,0,0,0,0,0,0,0,0,0,0,0,0,0,0,0,0,0,0,0,DC66,0)~
';
    'VSS'<264>:'(0,0,0,0,0,0,0,0,0,0,0,0,0,0,0,0,0,0,0,0,0,0,0,0,0,0,0,0,DC68,0)~
';
    'VSS'<263>:'(0,0,0,0,0,0,0,0,0,0,0,0,0,0,0,0,0,0,0,0,0,0,0,0,0,0,0,0,DC70,0)~
';
    'VSS'<262>:'(0,0,0,0,0,0,0,0,0,0,0,0,0,0,0,0,0,0,0,0,0,0,0,0,0,0,0,0,DC78,0)~
';
    'VSS'<261>:'(0,0,0,0,0,0,0,0,0,0,0,0,0,0,0,0,0,0,0,0,0,0,0,0,0,0,0,0,DC84,0)~
';
    'VSS'<260>:'(0,0,0,0,0,0,0,0,0,0,0,0,0,0,0,0,0,0,0,0,0,0,0,0,0,0,0,0,DC86,0)~
';
    'VSS'<259>:'(0,0,0,0,0,0,0,0,0,0,0,0,0,0,0,0,0,0,0,0,0,0,0,0,0,0,0,0,DD11,0)~
';
    'VSS'<258>:'(0,0,0,0,0,0,0,0,0,0,0,0,0,0,0,0,0,0,0,0,0,0,0,0,0,0,0,0,DD23,0)~
';
    'VSS'<257>:'(0,0,0,0,0,0,0,0,0,0,0,0,0,0,0,0,0,0,0,0,0,0,0,0,0,0,0,0,DD27,0)~
';
    'VSS'<256>:'(0,0,0,0,0,0,0,0,0,0,0,0,0,0,0,0,0,0,0,0,0,0,0,0,0,0,0,0,DD31,0)~
';
    'VSS'<255>:'(0,0,0,0,0,0,0,0,0,0,0,0,0,0,0,0,0,0,0,0,0,0,0,0,0,0,0,0,DD33,0)~
';
    'VSS'<254>:'(0,0,0,0,0,0,0,0,0,0,0,0,0,0,0,0,0,0,0,0,0,0,0,0,0,0,0,0,DD37,0)~
';
    'VSS'<253>:'(0,0,0,0,0,0,0,0,0,0,0,0,0,0,0,0,0,0,0,0,0,0,0,0,0,0,0,0,DD71,0)~
';
    'VSS'<252>:'(0,0,0,0,0,0,0,0,0,0,0,0,0,0,0,0,0,0,0,0,0,0,0,0,0,0,0,0,DD73,0)~
';
    'VSS'<251>:'(0,0,0,0,0,0,0,0,0,0,0,0,0,0,0,0,0,0,0,0,0,0,0,0,0,0,0,0,DD75,0)~
';
    'VSS'<250>:'(0,0,0,0,0,0,0,0,0,0,0,0,0,0,0,0,0,0,0,0,0,0,0,0,0,0,0,0,DD81,0)~
';
    'VSS'<249>:'(0,0,0,0,0,0,0,0,0,0,0,0,0,0,0,0,0,0,0,0,0,0,0,0,0,0,0,0,DD83,0)~
';
    'VSS'<248>:'(0,0,0,0,0,0,0,0,0,0,0,0,0,0,0,0,0,0,0,0,0,0,0,0,0,0,0,0,DE6,0)';
    'VSS'<247>:'(0,0,0,0,0,0,0,0,0,0,0,0,0,0,0,0,0,0,0,0,0,0,0,0,0,0,0,0,DE8,0)';
    'VSS'<246>:'(0,0,0,0,0,0,0,0,0,0,0,0,0,0,0,0,0,0,0,0,0,0,0,0,0,0,0,0,DE18,0)~
';
    'VSS'<245>:'(0,0,0,0,0,0,0,0,0,0,0,0,0,0,0,0,0,0,0,0,0,0,0,0,0,0,0,0,DE20,0)~
';
    'VSS'<244>:'(0,0,0,0,0,0,0,0,0,0,0,0,0,0,0,0,0,0,0,0,0,0,0,0,0,0,0,0,DE24,0)~
';
    'VSS'<243>:'(0,0,0,0,0,0,0,0,0,0,0,0,0,0,0,0,0,0,0,0,0,0,0,0,0,0,0,0,DE28,0)~
';
    'VSS'<242>:'(0,0,0,0,0,0,0,0,0,0,0,0,0,0,0,0,0,0,0,0,0,0,0,0,0,0,0,0,DE30,0)~
';
    'VSS'<241>:'(0,0,0,0,0,0,0,0,0,0,0,0,0,0,0,0,0,0,0,0,0,0,0,0,0,0,0,0,DE34,0)~
';
    'VSS'<240>:'(0,0,0,0,0,0,0,0,0,0,0,0,0,0,0,0,0,0,0,0,0,0,0,0,0,0,0,0,DE36,0)~
';
    'VSS'<239>:'(0,0,0,0,0,0,0,0,0,0,0,0,0,0,0,0,0,0,0,0,0,0,0,0,0,0,0,0,DE64,0)~
';
    'VSS'<238>:'(0,0,0,0,0,0,0,0,0,0,0,0,0,0,0,0,0,0,0,0,0,0,0,0,0,0,0,0,DE70,0)~
';
    'VSS'<237>:'(0,0,0,0,0,0,0,0,0,0,0,0,0,0,0,0,0,0,0,0,0,0,0,0,0,0,0,0,DE72,0)~
';
    'VSS'<236>:'(0,0,0,0,0,0,0,0,0,0,0,0,0,0,0,0,0,0,0,0,0,0,0,0,0,0,0,0,DE78,0)~
';
    'VSS'<235>:'(0,0,0,0,0,0,0,0,0,0,0,0,0,0,0,0,0,0,0,0,0,0,0,0,0,0,0,0,DF5,0)';
    'VSS'<234>:'(0,0,0,0,0,0,0,0,0,0,0,0,0,0,0,0,0,0,0,0,0,0,0,0,0,0,0,0,DF7,0)';
    'VSS'<233>:'(0,0,0,0,0,0,0,0,0,0,0,0,0,0,0,0,0,0,0,0,0,0,0,0,0,0,0,0,H51,0)';
    'VSS'<232>:'(0,0,0,0,0,0,0,0,0,0,0,0,0,0,0,0,0,0,0,0,0,0,0,0,0,0,0,0,DF19,0)~
';
    'VSS'<231>:'(0,0,0,0,0,0,0,0,0,0,0,0,0,0,0,0,0,0,0,0,0,0,0,0,0,0,0,0,DF29,0)~
';
    'VSS'<230>:'(0,0,0,0,0,0,0,0,0,0,0,0,0,0,0,0,0,0,0,0,0,0,0,0,0,0,0,0,DF35,0)~
';
    'VSS'<229>:'(0,0,0,0,0,0,0,0,0,0,0,0,0,0,0,0,0,0,0,0,0,0,0,0,0,0,0,0,DF37,0)~
';
    'VSS'<228>:'(0,0,0,0,0,0,0,0,0,0,0,0,0,0,0,0,0,0,0,0,0,0,0,0,0,0,0,0,DF39,0)~
';
    'VSS'<227>:'(0,0,0,0,0,0,0,0,0,0,0,0,0,0,0,0,0,0,0,0,0,0,0,0,0,0,0,0,DF41,0)~
';
    'VSS'<226>:'(0,0,0,0,0,0,0,0,0,0,0,0,0,0,0,0,0,0,0,0,0,0,0,0,0,0,0,0,DF65,0)~
';
    'VSS'<225>:'(0,0,0,0,0,0,0,0,0,0,0,0,0,0,0,0,0,0,0,0,0,0,0,0,0,0,0,0,DF69,0)~
';
    'VSS'<224>:'(0,0,0,0,0,0,0,0,0,0,0,0,0,0,0,0,0,0,0,0,0,0,0,0,0,0,0,0,DF73,0)~
';
    'VSS'<223>:'(0,0,0,0,0,0,0,0,0,0,0,0,0,0,0,0,0,0,0,0,0,0,0,0,0,0,0,0,DF79,0)~
';
    'VSS'<222>:'(0,0,0,0,0,0,0,0,0,0,0,0,0,0,0,0,0,0,0,0,0,0,0,0,0,0,0,0,DF83,0)~
';
    'VSS'<221>:'(0,0,0,0,0,0,0,0,0,0,0,0,0,0,0,0,0,0,0,0,0,0,0,0,0,0,0,0,DF85,0)~
';
    'VSS'<220>:'(0,0,0,0,0,0,0,0,0,0,0,0,0,0,0,0,0,0,0,0,0,0,0,0,0,0,0,0,DG2,0)';
    'VSS'<219>:'(0,0,0,0,0,0,0,0,0,0,0,0,0,0,0,0,0,0,0,0,0,0,0,0,0,0,0,0,H49,0)';
    'VSS'<218>:'(0,0,0,0,0,0,0,0,0,0,0,0,0,0,0,0,0,0,0,0,0,0,0,0,0,0,0,0,DG14,0)~
';
    'VSS'<217>:'(0,0,0,0,0,0,0,0,0,0,0,0,0,0,0,0,0,0,0,0,0,0,0,0,0,0,0,0,DG16,0)~
';
    'VSS'<216>:'(0,0,0,0,0,0,0,0,0,0,0,0,0,0,0,0,0,0,0,0,0,0,0,0,0,0,0,0,DG24,0)~
';
    'VSS'<215>:'(0,0,0,0,0,0,0,0,0,0,0,0,0,0,0,0,0,0,0,0,0,0,0,0,0,0,0,0,DG66,0)~
';
    'VSS'<214>:'(0,0,0,0,0,0,0,0,0,0,0,0,0,0,0,0,0,0,0,0,0,0,0,0,0,0,0,0,DG68,0)~
';
    'VSS'<213>:'(0,0,0,0,0,0,0,0,0,0,0,0,0,0,0,0,0,0,0,0,0,0,0,0,0,0,0,0,DG76,0)~
';
    'VSS'<212>:'(0,0,0,0,0,0,0,0,0,0,0,0,0,0,0,0,0,0,0,0,0,0,0,0,0,0,0,0,DG78,0)~
';
    'VSS'<211>:'(0,0,0,0,0,0,0,0,0,0,0,0,0,0,0,0,0,0,0,0,0,0,0,0,0,0,0,0,DG80,0)~
';
    'VSS'<210>:'(0,0,0,0,0,0,0,0,0,0,0,0,0,0,0,0,0,0,0,0,0,0,0,0,0,0,0,0,DG82,0)~
';
    'VSS'<209>:'(0,0,0,0,0,0,0,0,0,0,0,0,0,0,0,0,0,0,0,0,0,0,0,0,0,0,0,0,DH13,0)~
';
    'VSS'<208>:'(0,0,0,0,0,0,0,0,0,0,0,0,0,0,0,0,0,0,0,0,0,0,0,0,0,0,0,0,DH15,0)~
';
    'VSS'<207>:'(0,0,0,0,0,0,0,0,0,0,0,0,0,0,0,0,0,0,0,0,0,0,0,0,0,0,0,0,DH23,0)~
';
    'VSS'<206>:'(0,0,0,0,0,0,0,0,0,0,0,0,0,0,0,0,0,0,0,0,0,0,0,0,0,0,0,0,DH25,0)~
';
    'VSS'<205>:'(0,0,0,0,0,0,0,0,0,0,0,0,0,0,0,0,0,0,0,0,0,0,0,0,0,0,0,0,DH27,0)~
';
    'VSS'<204>:'(0,0,0,0,0,0,0,0,0,0,0,0,0,0,0,0,0,0,0,0,0,0,0,0,0,0,0,0,DH29,0)~
';
    'VSS'<203>:'(0,0,0,0,0,0,0,0,0,0,0,0,0,0,0,0,0,0,0,0,0,0,0,0,0,0,0,0,DH31,0)~
';
    'VSS'<202>:'(0,0,0,0,0,0,0,0,0,0,0,0,0,0,0,0,0,0,0,0,0,0,0,0,0,0,0,0,DH33,0)~
';
    'VSS'<201>:'(0,0,0,0,0,0,0,0,0,0,0,0,0,0,0,0,0,0,0,0,0,0,0,0,0,0,0,0,DH35,0)~
';
    'VSS'<200>:'(0,0,0,0,0,0,0,0,0,0,0,0,0,0,0,0,0,0,0,0,0,0,0,0,0,0,0,0,DH37,0)~
';
    'VSS'<199>:'(0,0,0,0,0,0,0,0,0,0,0,0,0,0,0,0,0,0,0,0,0,0,0,0,0,0,0,0,DH41,0)~
';
    'VSS'<198>:'(0,0,0,0,0,0,0,0,0,0,0,0,0,0,0,0,0,0,0,0,0,0,0,0,0,0,0,0,DH67,0)~
';
    'VSS'<197>:'(0,0,0,0,0,0,0,0,0,0,0,0,0,0,0,0,0,0,0,0,0,0,0,0,0,0,0,0,DH71,0)~
';
    'VSS'<196>:'(0,0,0,0,0,0,0,0,0,0,0,0,0,0,0,0,0,0,0,0,0,0,0,0,0,0,0,0,DH73,0)~
';
    'VSS'<195>:'(0,0,0,0,0,0,0,0,0,0,0,0,0,0,0,0,0,0,0,0,0,0,0,0,0,0,0,0,DH79,0)~
';
    'VSS'<194>:'(0,0,0,0,0,0,0,0,0,0,0,0,0,0,0,0,0,0,0,0,0,0,0,0,0,0,0,0,DH81,0)~
';
    'VSS'<193>:'(0,0,0,0,0,0,0,0,0,0,0,0,0,0,0,0,0,0,0,0,0,0,0,0,0,0,0,0,DH83,0)~
';
    'VSS'<192>:'(0,0,0,0,0,0,0,0,0,0,0,0,0,0,0,0,0,0,0,0,0,0,0,0,0,0,0,0,DJ2,0)';
    'VSS'<191>:'(0,0,0,0,0,0,0,0,0,0,0,0,0,0,0,0,0,0,0,0,0,0,0,0,0,0,0,0,DJ10,0)~
';
    'VSS'<190>:'(0,0,0,0,0,0,0,0,0,0,0,0,0,0,0,0,0,0,0,0,0,0,0,0,0,0,0,0,H47,0)';
    'VSS'<189>:'(0,0,0,0,0,0,0,0,0,0,0,0,0,0,0,0,0,0,0,0,0,0,0,0,0,0,0,0,DJ22,0)~
';
    'VSS'<188>:'(0,0,0,0,0,0,0,0,0,0,0,0,0,0,0,0,0,0,0,0,0,0,0,0,0,0,0,0,DJ38,0)~
';
    'VSS'<187>:'(0,0,0,0,0,0,0,0,0,0,0,0,0,0,0,0,0,0,0,0,0,0,0,0,0,0,0,0,DJ42,0)~
';
    'VSS'<186>:'(0,0,0,0,0,0,0,0,0,0,0,0,0,0,0,0,0,0,0,0,0,0,0,0,0,0,0,0,DJ68,0)~
';
    'VSS'<185>:'(0,0,0,0,0,0,0,0,0,0,0,0,0,0,0,0,0,0,0,0,0,0,0,0,0,0,0,0,DJ74,0)~
';
    'VSS'<184>:'(0,0,0,0,0,0,0,0,0,0,0,0,0,0,0,0,0,0,0,0,0,0,0,0,0,0,0,0,DJ78,0)~
';
    'VSS'<183>:'(0,0,0,0,0,0,0,0,0,0,0,0,0,0,0,0,0,0,0,0,0,0,0,0,0,0,0,0,DJ82,0)~
';
    'VSS'<182>:'(0,0,0,0,0,0,0,0,0,0,0,0,0,0,0,0,0,0,0,0,0,0,0,0,0,0,0,0,DJ84,0)~
';
    'VSS'<181>:'(0,0,0,0,0,0,0,0,0,0,0,0,0,0,0,0,0,0,0,0,0,0,0,0,0,0,0,0,DK7,0)';
    'VSS'<180>:'(0,0,0,0,0,0,0,0,0,0,0,0,0,0,0,0,0,0,0,0,0,0,0,0,0,0,0,0,DK23,0)~
';
    'VSS'<179>:'(0,0,0,0,0,0,0,0,0,0,0,0,0,0,0,0,0,0,0,0,0,0,0,0,0,0,0,0,DK29,0)~
';
    'VSS'<178>:'(0,0,0,0,0,0,0,0,0,0,0,0,0,0,0,0,0,0,0,0,0,0,0,0,0,0,0,0,DK35,0)~
';
    'VSS'<177>:'(0,0,0,0,0,0,0,0,0,0,0,0,0,0,0,0,0,0,0,0,0,0,0,0,0,0,0,0,DK39,0)~
';
    'VSS'<176>:'(0,0,0,0,0,0,0,0,0,0,0,0,0,0,0,0,0,0,0,0,0,0,0,0,0,0,0,0,DK41,0)~
';
    'VSS'<175>:'(0,0,0,0,0,0,0,0,0,0,0,0,0,0,0,0,0,0,0,0,0,0,0,0,0,0,0,0,DK73,0)~
';
    'VSS'<174>:'(0,0,0,0,0,0,0,0,0,0,0,0,0,0,0,0,0,0,0,0,0,0,0,0,0,0,0,0,DK75,0)~
';
    'VSS'<173>:'(0,0,0,0,0,0,0,0,0,0,0,0,0,0,0,0,0,0,0,0,0,0,0,0,0,0,0,0,DK77,0)~
';
    'VSS'<172>:'(0,0,0,0,0,0,0,0,0,0,0,0,0,0,0,0,0,0,0,0,0,0,0,0,0,0,0,0,DK83,0)~
';
    'VSS'<171>:'(0,0,0,0,0,0,0,0,0,0,0,0,0,0,0,0,0,0,0,0,0,0,0,0,0,0,0,0,DK85,0)~
';
    'VSS'<170>:'(0,0,0,0,0,0,0,0,0,0,0,0,0,0,0,0,0,0,0,0,0,0,0,0,0,0,0,0,DL16,0)~
';
    'VSS'<169>:'(0,0,0,0,0,0,0,0,0,0,0,0,0,0,0,0,0,0,0,0,0,0,0,0,0,0,0,0,DL18,0)~
';
    'VSS'<168>:'(0,0,0,0,0,0,0,0,0,0,0,0,0,0,0,0,0,0,0,0,0,0,0,0,0,0,0,0,DL4,0)';
    'VSS'<167>:'(0,0,0,0,0,0,0,0,0,0,0,0,0,0,0,0,0,0,0,0,0,0,0,0,0,0,0,0,DL22,0)~
';
    'VSS'<166>:'(0,0,0,0,0,0,0,0,0,0,0,0,0,0,0,0,0,0,0,0,0,0,0,0,0,0,0,0,DL24,0)~
';
    'VSS'<165>:'(0,0,0,0,0,0,0,0,0,0,0,0,0,0,0,0,0,0,0,0,0,0,0,0,0,0,0,0,DL28,0)~
';
    'VSS'<164>:'(0,0,0,0,0,0,0,0,0,0,0,0,0,0,0,0,0,0,0,0,0,0,0,0,0,0,0,0,DL30,0)~
';
    'VSS'<163>:'(0,0,0,0,0,0,0,0,0,0,0,0,0,0,0,0,0,0,0,0,0,0,0,0,0,0,0,0,DL34,0)~
';
    'VSS'<162>:'(0,0,0,0,0,0,0,0,0,0,0,0,0,0,0,0,0,0,0,0,0,0,0,0,0,0,0,0,DL36,0)~
';
    'VSS'<161>:'(0,0,0,0,0,0,0,0,0,0,0,0,0,0,0,0,0,0,0,0,0,0,0,0,0,0,0,0,DL40,0)~
';
    'VSS'<160>:'(0,0,0,0,0,0,0,0,0,0,0,0,0,0,0,0,0,0,0,0,0,0,0,0,0,0,0,0,DL68,0)~
';
    'VSS'<159>:'(0,0,0,0,0,0,0,0,0,0,0,0,0,0,0,0,0,0,0,0,0,0,0,0,0,0,0,0,DL70,0)~
';
    'VSS'<158>:'(0,0,0,0,0,0,0,0,0,0,0,0,0,0,0,0,0,0,0,0,0,0,0,0,0,0,0,0,DL74,0)~
';
    'VSS'<157>:'(0,0,0,0,0,0,0,0,0,0,0,0,0,0,0,0,0,0,0,0,0,0,0,0,0,0,0,0,DL76,0)~
';
    'VSS'<156>:'(0,0,0,0,0,0,0,0,0,0,0,0,0,0,0,0,0,0,0,0,0,0,0,0,0,0,0,0,DL78,0)~
';
    'VSS'<155>:'(0,0,0,0,0,0,0,0,0,0,0,0,0,0,0,0,0,0,0,0,0,0,0,0,0,0,0,0,DL80,0)~
';
    'VSS'<154>:'(0,0,0,0,0,0,0,0,0,0,0,0,0,0,0,0,0,0,0,0,0,0,0,0,0,0,0,0,DM15,0)~
';
    'VSS'<153>:'(0,0,0,0,0,0,0,0,0,0,0,0,0,0,0,0,0,0,0,0,0,0,0,0,0,0,0,0,H45,0)';
    'VSS'<152>:'(0,0,0,0,0,0,0,0,0,0,0,0,0,0,0,0,0,0,0,0,0,0,0,0,0,0,0,0,DM25,0)~
';
    'VSS'<151>:'(0,0,0,0,0,0,0,0,0,0,0,0,0,0,0,0,0,0,0,0,0,0,0,0,0,0,0,0,DM27,0)~
';
    'VSS'<150>:'(0,0,0,0,0,0,0,0,0,0,0,0,0,0,0,0,0,0,0,0,0,0,0,0,0,0,0,0,DM31,0)~
';
    'VSS'<149>:'(0,0,0,0,0,0,0,0,0,0,0,0,0,0,0,0,0,0,0,0,0,0,0,0,0,0,0,0,DM33,0)~
';
    'VSS'<148>:'(0,0,0,0,0,0,0,0,0,0,0,0,0,0,0,0,0,0,0,0,0,0,0,0,0,0,0,0,DM37,0)~
';
    'VSS'<147>:'(0,0,0,0,0,0,0,0,0,0,0,0,0,0,0,0,0,0,0,0,0,0,0,0,0,0,0,0,DM39,0)~
';
    'VSS'<146>:'(0,0,0,0,0,0,0,0,0,0,0,0,0,0,0,0,0,0,0,0,0,0,0,0,0,0,0,0,DM65,0)~
';
    'VSS'<145>:'(0,0,0,0,0,0,0,0,0,0,0,0,0,0,0,0,0,0,0,0,0,0,0,0,0,0,0,0,DM73,0)~
';
    'VSS'<144>:'(0,0,0,0,0,0,0,0,0,0,0,0,0,0,0,0,0,0,0,0,0,0,0,0,0,0,0,0,DM77,0)~
';
    'VSS'<143>:'(0,0,0,0,0,0,0,0,0,0,0,0,0,0,0,0,0,0,0,0,0,0,0,0,0,0,0,0,DM83,0)~
';
    'VSS'<142>:'(0,0,0,0,0,0,0,0,0,0,0,0,0,0,0,0,0,0,0,0,0,0,0,0,0,0,0,0,DN2,0)';
    'VSS'<141>:'(0,0,0,0,0,0,0,0,0,0,0,0,0,0,0,0,0,0,0,0,0,0,0,0,0,0,0,0,BH17,0)~
';
    'VSS'<140>:'(0,0,0,0,0,0,0,0,0,0,0,0,0,0,0,0,0,0,0,0,0,0,0,0,0,0,0,0,DN12,0)~
';
    'VSS'<139>:'(0,0,0,0,0,0,0,0,0,0,0,0,0,0,0,0,0,0,0,0,0,0,0,0,0,0,0,0,DN22,0)~
';
    'VSS'<138>:'(0,0,0,0,0,0,0,0,0,0,0,0,0,0,0,0,0,0,0,0,0,0,0,0,0,0,0,0,DN26,0)~
';
    'VSS'<137>:'(0,0,0,0,0,0,0,0,0,0,0,0,0,0,0,0,0,0,0,0,0,0,0,0,0,0,0,0,DN32,0)~
';
    'VSS'<136>:'(0,0,0,0,0,0,0,0,0,0,0,0,0,0,0,0,0,0,0,0,0,0,0,0,0,0,0,0,DN38,0)~
';
    'VSS'<135>:'(0,0,0,0,0,0,0,0,0,0,0,0,0,0,0,0,0,0,0,0,0,0,0,0,0,0,0,0,DN68,0)~
';
    'VSS'<134>:'(0,0,0,0,0,0,0,0,0,0,0,0,0,0,0,0,0,0,0,0,0,0,0,0,0,0,0,0,DN72,0)~
';
    'VSS'<133>:'(0,0,0,0,0,0,0,0,0,0,0,0,0,0,0,0,0,0,0,0,0,0,0,0,0,0,0,0,0,DN78)~
';
    'VSS'<132>:'(0,0,0,0,0,0,0,0,0,0,0,0,0,0,0,0,0,0,0,0,0,0,0,0,0,0,0,0,0,DP67)~
';
    'VSS'<131>:'(0,0,0,0,0,0,0,0,0,0,0,0,0,0,0,0,0,0,0,0,0,0,0,0,0,0,0,0,0,DP69)~
';
    'VSS'<130>:'(0,0,0,0,0,0,0,0,0,0,0,0,0,0,0,0,0,0,0,0,0,0,0,0,0,0,0,0,0,DP71)~
';
    'VSS'<129>:'(0,0,0,0,0,0,0,0,0,0,0,0,0,0,0,0,0,0,0,0,0,0,0,0,0,0,0,0,0,DP81)~
';
    'VSS'<128>:'(0,0,0,0,0,0,0,0,0,0,0,0,0,0,0,0,0,0,0,0,0,0,0,0,0,0,0,0,0,DP83)~
';
    'VSS'<127>:'(0,0,0,0,0,0,0,0,0,0,0,0,0,0,0,0,0,0,0,0,0,0,0,0,0,0,0,0,0,BR26)~
';
    'VSS'<126>:'(0,0,0,0,0,0,0,0,0,0,0,0,0,0,0,0,0,0,0,0,0,0,0,0,0,0,0,0,0,DR6)';
    'VSS'<125>:'(0,0,0,0,0,0,0,0,0,0,0,0,0,0,0,0,0,0,0,0,0,0,0,0,0,0,0,0,0,CA20)~
';
    'VSS'<124>:'(0,0,0,0,0,0,0,0,0,0,0,0,0,0,0,0,0,0,0,0,0,0,0,0,0,0,0,0,0,CL22)~
';
    'VSS'<123>:'(0,0,0,0,0,0,0,0,0,0,0,0,0,0,0,0,0,0,0,0,0,0,0,0,0,0,0,0,0,DR20)~
';
    'VSS'<122>:'(0,0,0,0,0,0,0,0,0,0,0,0,0,0,0,0,0,0,0,0,0,0,0,0,0,0,0,0,0,DR22)~
';
    'VSS'<121>:'(0,0,0,0,0,0,0,0,0,0,0,0,0,0,0,0,0,0,0,0,0,0,0,0,0,0,0,0,0,DR24)~
';
    'VSS'<120>:'(0,0,0,0,0,0,0,0,0,0,0,0,0,0,0,0,0,0,0,0,0,0,0,0,0,0,0,0,0,DR26)~
';
    'VSS'<119>:'(0,0,0,0,0,0,0,0,0,0,0,0,0,0,0,0,0,0,0,0,0,0,0,0,0,0,0,0,0,DR28)~
';
    'VSS'<118>:'(0,0,0,0,0,0,0,0,0,0,0,0,0,0,0,0,0,0,0,0,0,0,0,0,0,0,0,0,0,DR30)~
';
    'VSS'<117>:'(0,0,0,0,0,0,0,0,0,0,0,0,0,0,0,0,0,0,0,0,0,0,0,0,0,0,0,0,0,DR32)~
';
    'VSS'<116>:'(0,0,0,0,0,0,0,0,0,0,0,0,0,0,0,0,0,0,0,0,0,0,0,0,0,0,0,0,0,DR34)~
';
    'VSS'<115>:'(0,0,0,0,0,0,0,0,0,0,0,0,0,0,0,0,0,0,0,0,0,0,0,0,0,0,0,0,0,DR36)~
';
    'VSS'<114>:'(0,0,0,0,0,0,0,0,0,0,0,0,0,0,0,0,0,0,0,0,0,0,0,0,0,0,0,0,0,DR38)~
';
    'VSS'<113>:'(0,0,0,0,0,0,0,0,0,0,0,0,0,0,0,0,0,0,0,0,0,0,0,0,0,0,0,0,0,DR40)~
';
    'VSS'<112>:'(0,0,0,0,0,0,0,0,0,0,0,0,0,0,0,0,0,0,0,0,0,0,0,0,0,0,0,0,0,DR42)~
';
    'VSS'<111>:'(0,0,0,0,0,0,0,0,0,0,0,0,0,0,0,0,0,0,0,0,0,0,0,0,0,0,0,0,0,DR66)~
';
    'VSS'<110>:'(0,0,0,0,0,0,0,0,0,0,0,0,0,0,0,0,0,0,0,0,0,0,0,0,0,0,0,0,0,DR68)~
';
    'VSS'<109>:'(0,0,0,0,0,0,0,0,0,0,0,0,0,0,0,0,0,0,0,0,0,0,0,0,0,0,0,0,0,DR70)~
';
    'VSS'<108>:'(0,0,0,0,0,0,0,0,0,0,0,0,0,0,0,0,0,0,0,0,0,0,0,0,0,0,0,0,0,DR72)~
';
    'VSS'<107>:'(0,0,0,0,0,0,0,0,0,0,0,0,0,0,0,0,0,0,0,0,0,0,0,0,0,0,0,0,0,DR74)~
';
    'VSS'<106>:'(0,0,0,0,0,0,0,0,0,0,0,0,0,0,0,0,0,0,0,0,0,0,0,0,0,0,0,0,0,DR76)~
';
    'VSS'<105>:'(0,0,0,0,0,0,0,0,0,0,0,0,0,0,0,0,0,0,0,0,0,0,0,0,0,0,0,0,0,DR78)~
';
    'VSS'<104>:'(0,0,0,0,0,0,0,0,0,0,0,0,0,0,0,0,0,0,0,0,0,0,0,0,0,0,0,0,0,DT3)';
    'VSS'<103>:'(0,0,0,0,0,0,0,0,0,0,0,0,0,0,0,0,0,0,0,0,0,0,0,0,0,0,0,0,0,DT17)~
';
    'VSS'<102>:'(0,0,0,0,0,0,0,0,0,0,0,0,0,0,0,0,0,0,0,0,0,0,0,0,0,0,0,0,0,DH21)~
';
    'VSS'<101>:'(0,0,0,0,0,0,0,0,0,0,0,0,0,0,0,0,0,0,0,0,0,0,0,0,0,0,0,0,0,DT65)~
';
    'VSS'<100>:'(0,0,0,0,0,0,0,0,0,0,0,0,0,0,0,0,0,0,0,0,0,0,0,0,0,0,0,0,0,DT69)~
';
    'VSS'<99>:'(0,0,0,0,0,0,0,0,0,0,0,0,0,0,0,0,0,0,0,0,0,0,0,0,0,0,0,0,0,DT79)';
    'VSS'<98>:'(0,0,0,0,0,0,0,0,0,0,0,0,0,0,0,0,0,0,0,0,0,0,0,0,0,0,0,0,0,DT83)';
    'VSS'<97>:'(0,0,0,0,0,0,0,0,0,0,0,0,0,0,0,0,0,0,0,0,0,0,0,0,0,0,0,0,0,DT85)';
    'VSS'<96>:'(0,0,0,0,0,0,0,0,0,0,0,0,0,0,0,0,0,0,0,0,0,0,0,0,0,0,0,0,0,DU10)';
    'VSS'<95>:'(0,0,0,0,0,0,0,0,0,0,0,0,0,0,0,0,0,0,0,0,0,0,0,0,0,0,0,0,0,DU14)';
    'VSS'<94>:'(0,0,0,0,0,0,0,0,0,0,0,0,0,0,0,0,0,0,0,0,0,0,0,0,0,0,0,0,0,CN14)';
    'VSS'<93>:'(0,0,0,0,0,0,0,0,0,0,0,0,0,0,0,0,0,0,0,0,0,0,0,0,0,0,0,0,0,DU22)';
    'VSS'<92>:'(0,0,0,0,0,0,0,0,0,0,0,0,0,0,0,0,0,0,0,0,0,0,0,0,0,0,0,0,0,DU26)';
    'VSS'<91>:'(0,0,0,0,0,0,0,0,0,0,0,0,0,0,0,0,0,0,0,0,0,0,0,0,0,0,0,0,0,DU32)';
    'VSS'<90>:'(0,0,0,0,0,0,0,0,0,0,0,0,0,0,0,0,0,0,0,0,0,0,0,0,0,0,0,0,0,DU38)';
    'VSS'<89>:'(0,0,0,0,0,0,0,0,0,0,0,0,0,0,0,0,0,0,0,0,0,0,0,0,0,0,0,0,0,DU70)';
    'VSS'<88>:'(0,0,0,0,0,0,0,0,0,0,0,0,0,0,0,0,0,0,0,0,0,0,0,0,0,0,0,0,0,DU72)';
    'VSS'<87>:'(0,0,0,0,0,0,0,0,0,0,0,0,0,0,0,0,0,0,0,0,0,0,0,0,0,0,0,0,0,DU78)';
    'VSS'<86>:'(0,0,0,0,0,0,0,0,0,0,0,0,0,0,0,0,0,0,0,0,0,0,0,0,0,0,0,0,0,DU80)';
    'VSS'<85>:'(0,0,0,0,0,0,0,0,0,0,0,0,0,0,0,0,0,0,0,0,0,0,0,0,0,0,0,0,0,DU82)';
    'VSS'<84>:'(0,0,0,0,0,0,0,0,0,0,0,0,0,0,0,0,0,0,0,0,0,0,0,0,0,0,0,0,0,DU84)';
    'VSS'<83>:'(0,0,0,0,0,0,0,0,0,0,0,0,0,0,0,0,0,0,0,0,0,0,0,0,0,0,0,0,0,DV21)';
    'VSS'<82>:'(0,0,0,0,0,0,0,0,0,0,0,0,0,0,0,0,0,0,0,0,0,0,0,0,0,0,0,0,0,DV25)';
    'VSS'<81>:'(0,0,0,0,0,0,0,0,0,0,0,0,0,0,0,0,0,0,0,0,0,0,0,0,0,0,0,0,0,DV27)';
    'VSS'<80>:'(0,0,0,0,0,0,0,0,0,0,0,0,0,0,0,0,0,0,0,0,0,0,0,0,0,0,0,0,0,DV31)';
    'VSS'<79>:'(0,0,0,0,0,0,0,0,0,0,0,0,0,0,0,0,0,0,0,0,0,0,0,0,0,0,0,0,0,DV33)';
    'VSS'<78>:'(0,0,0,0,0,0,0,0,0,0,0,0,0,0,0,0,0,0,0,0,0,0,0,0,0,0,0,0,0,DV37)';
    'VSS'<77>:'(0,0,0,0,0,0,0,0,0,0,0,0,0,0,0,0,0,0,0,0,0,0,0,0,0,0,0,0,0,DV39)';
    'VSS'<76>:'(0,0,0,0,0,0,0,0,0,0,0,0,0,0,0,0,0,0,0,0,0,0,0,0,0,0,0,0,0,DV73)';
    'VSS'<75>:'(0,0,0,0,0,0,0,0,0,0,0,0,0,0,0,0,0,0,0,0,0,0,0,0,0,0,0,0,0,DV77)';
    'VSS'<74>:'(0,0,0,0,0,0,0,0,0,0,0,0,0,0,0,0,0,0,0,0,0,0,0,0,0,0,0,0,0,DV81)';
    'VSS'<73>:'(0,0,0,0,0,0,0,0,0,0,0,0,0,0,0,0,0,0,0,0,0,0,0,0,0,0,0,0,0,DW12)';
    'VSS'<72>:'(0,0,0,0,0,0,0,0,0,0,0,0,0,0,0,0,0,0,0,0,0,0,0,0,0,0,0,0,0,DW20)';
    'VSS'<71>:'(0,0,0,0,0,0,0,0,0,0,0,0,0,0,0,0,0,0,0,0,0,0,0,0,0,0,0,0,0,DW24)';
    'VSS'<70>:'(0,0,0,0,0,0,0,0,0,0,0,0,0,0,0,0,0,0,0,0,0,0,0,0,0,0,0,0,0,DW28)';
    'VSS'<69>:'(0,0,0,0,0,0,0,0,0,0,0,0,0,0,0,0,0,0,0,0,0,0,0,0,0,0,0,0,0,DW30)';
    'VSS'<68>:'(0,0,0,0,0,0,0,0,0,0,0,0,0,0,0,0,0,0,0,0,0,0,0,0,0,0,0,0,0,DW34)';
    'VSS'<67>:'(0,0,0,0,0,0,0,0,0,0,0,0,0,0,0,0,0,0,0,0,0,0,0,0,0,0,0,0,0,DW36)';
    'VSS'<66>:'(0,0,0,0,0,0,0,0,0,0,0,0,0,0,0,0,0,0,0,0,0,0,0,0,0,0,0,0,0,DW40)';
    'VSS'<65>:'(0,0,0,0,0,0,0,0,0,0,0,0,0,0,0,0,0,0,0,0,0,0,0,0,0,0,0,0,0,DW64)';
    'VSS'<64>:'(0,0,0,0,0,0,0,0,0,0,0,0,0,0,0,0,0,0,0,0,0,0,0,0,0,0,0,0,0,DW66)';
    'VSS'<63>:'(0,0,0,0,0,0,0,0,0,0,0,0,0,0,0,0,0,0,0,0,0,0,0,0,0,0,0,0,0,DW68)';
    'VSS'<62>:'(0,0,0,0,0,0,0,0,0,0,0,0,0,0,0,0,0,0,0,0,0,0,0,0,0,0,0,0,0,DW70)';
    'VSS'<61>:'(0,0,0,0,0,0,0,0,0,0,0,0,0,0,0,0,0,0,0,0,0,0,0,0,0,0,0,0,0,DW72)';
    'VSS'<60>:'(0,0,0,0,0,0,0,0,0,0,0,0,0,0,0,0,0,0,0,0,0,0,0,0,0,0,0,0,0,DW74)';
    'VSS'<59>:'(0,0,0,0,0,0,0,0,0,0,0,0,0,0,0,0,0,0,0,0,0,0,0,0,0,0,0,0,0,DW76)';
    'VSS'<58>:'(0,0,0,0,0,0,0,0,0,0,0,0,0,0,0,0,0,0,0,0,0,0,0,0,0,0,0,0,0,DW8)';~

    'VSS'<57>:'(0,0,0,0,0,0,0,0,0,0,0,0,0,0,0,0,0,0,0,0,0,0,0,0,0,0,0,0,0,DW82)';
    'VSS'<56>:'(0,0,0,0,0,0,0,0,0,0,0,0,0,0,0,0,0,0,0,0,0,0,0,0,0,0,0,0,0,DW84)';
    'VSS'<55>:'(0,0,0,0,0,0,0,0,0,0,0,0,0,0,0,0,0,0,0,0,0,0,0,0,0,0,0,0,0,DY5)';~

    'VSS'<54>:'(0,0,0,0,0,0,0,0,0,0,0,0,0,0,0,0,0,0,0,0,0,0,0,0,0,0,0,0,0,DY19)';
    'VSS'<53>:'(0,0,0,0,0,0,0,0,0,0,0,0,0,0,0,0,0,0,0,0,0,0,0,0,0,0,0,0,0,DY23)';
    'VSS'<52>:'(0,0,0,0,0,0,0,0,0,0,0,0,0,0,0,0,0,0,0,0,0,0,0,0,0,0,0,0,0,DY29)';
    'VSS'<51>:'(0,0,0,0,0,0,0,0,0,0,0,0,0,0,0,0,0,0,0,0,0,0,0,0,0,0,0,0,0,DY35)';
    'VSS'<50>:'(0,0,0,0,0,0,0,0,0,0,0,0,0,0,0,0,0,0,0,0,0,0,0,0,0,0,0,0,0,DY41)';
    'VSS'<49>:'(0,0,0,0,0,0,0,0,0,0,0,0,0,0,0,0,0,0,0,0,0,0,0,0,0,0,0,0,0,DY71)';
    'VSS'<48>:'(0,0,0,0,0,0,0,0,0,0,0,0,0,0,0,0,0,0,0,0,0,0,0,0,0,0,0,0,0,DY75)';
    'VSS'<47>:'(0,0,0,0,0,0,0,0,0,0,0,0,0,0,0,0,0,0,0,0,0,0,0,0,0,0,0,0,0,EA6)';~

    'VSS'<46>:'(0,0,0,0,0,0,0,0,0,0,0,0,0,0,0,0,0,0,0,0,0,0,0,0,0,0,0,0,0,J16)';~

    'VSS'<45>:'(0,0,0,0,0,0,0,0,0,0,0,0,0,0,0,0,0,0,0,0,0,0,0,0,0,0,0,0,0,EA16)';
    'VSS'<44>:'(0,0,0,0,0,0,0,0,0,0,0,0,0,0,0,0,0,0,0,0,0,0,0,0,0,0,0,0,0,EA20)';
    'VSS'<43>:'(0,0,0,0,0,0,0,0,0,0,0,0,0,0,0,0,0,0,0,0,0,0,0,0,0,0,0,0,0,EA22)';
    'VSS'<42>:'(0,0,0,0,0,0,0,0,0,0,0,0,0,0,0,0,0,0,0,0,0,0,0,0,0,0,0,0,0,EA42)';
    'VSS'<41>:'(0,0,0,0,0,0,0,0,0,0,0,0,0,0,0,0,0,0,0,0,0,0,0,0,0,0,0,0,0,EA64)';
    'VSS'<40>:'(0,0,0,0,0,0,0,0,0,0,0,0,0,0,0,0,0,0,0,0,0,0,0,0,0,0,0,0,0,EA70)';
    'VSS'<39>:'(0,0,0,0,0,0,0,0,0,0,0,0,0,0,0,0,0,0,0,0,0,0,0,0,0,0,0,0,0,EA76)';
    'VSS'<38>:'(0,0,0,0,0,0,0,0,0,0,0,0,0,0,0,0,0,0,0,0,0,0,0,0,0,0,0,0,0,EA78)';
    'VSS'<37>:'(0,0,0,0,0,0,0,0,0,0,0,0,0,0,0,0,0,0,0,0,0,0,0,0,0,0,0,0,0,EA80)';
    'VSS'<36>:'(0,0,0,0,0,0,0,0,0,0,0,0,0,0,0,0,0,0,0,0,0,0,0,0,0,0,0,0,0,EA82)';
    'VSS'<35>:'(0,0,0,0,0,0,0,0,0,0,0,0,0,0,0,0,0,0,0,0,0,0,0,0,0,0,0,0,0,EB13)';
    'VSS'<34>:'(0,0,0,0,0,0,0,0,0,0,0,0,0,0,0,0,0,0,0,0,0,0,0,0,0,0,0,0,0,BR18)';
    'VSS'<33>:'(0,0,0,0,0,0,0,0,0,0,0,0,0,0,0,0,0,0,0,0,0,0,0,0,0,0,0,0,0,EB23)';
    'VSS'<32>:'(0,0,0,0,0,0,0,0,0,0,0,0,0,0,0,0,0,0,0,0,0,0,0,0,0,0,0,0,0,EB25)';
    'VSS'<31>:'(0,0,0,0,0,0,0,0,0,0,0,0,0,0,0,0,0,0,0,0,0,0,0,0,0,0,0,0,0,EB27)';
    'VSS'<30>:'(0,0,0,0,0,0,0,0,0,0,0,0,0,0,0,0,0,0,0,0,0,0,0,0,0,0,0,0,0,EB29)';
    'VSS'<29>:'(0,0,0,0,0,0,0,0,0,0,0,0,0,0,0,0,0,0,0,0,0,0,0,0,0,0,0,0,0,EB31)';
    'VSS'<28>:'(0,0,0,0,0,0,0,0,0,0,0,0,0,0,0,0,0,0,0,0,0,0,0,0,0,0,0,0,0,EB33)';
    'VSS'<27>:'(0,0,0,0,0,0,0,0,0,0,0,0,0,0,0,0,0,0,0,0,0,0,0,0,0,0,0,0,0,EB35)';
    'VSS'<26>:'(0,0,0,0,0,0,0,0,0,0,0,0,0,0,0,0,0,0,0,0,0,0,0,0,0,0,0,0,0,EB37)';
    'VSS'<25>:'(0,0,0,0,0,0,0,0,0,0,0,0,0,0,0,0,0,0,0,0,0,0,0,0,0,0,0,0,0,EB39)';
    'VSS'<24>:'(0,0,0,0,0,0,0,0,0,0,0,0,0,0,0,0,0,0,0,0,0,0,0,0,0,0,0,0,0,EB41)';
    'VSS'<23>:'(0,0,0,0,0,0,0,0,0,0,0,0,0,0,0,0,0,0,0,0,0,0,0,0,0,0,0,0,0,EB65)';
    'VSS'<22>:'(0,0,0,0,0,0,0,0,0,0,0,0,0,0,0,0,0,0,0,0,0,0,0,0,0,0,0,0,0,EB69)';
    'VSS'<21>:'(0,0,0,0,0,0,0,0,0,0,0,0,0,0,0,0,0,0,0,0,0,0,0,0,0,0,0,0,0,EC10)';
    'VSS'<20>:'(0,0,0,0,0,0,0,0,0,0,0,0,0,0,0,0,0,0,0,0,0,0,0,0,0,0,0,0,0,EC70)';
    'VSS'<19>:'(0,0,0,0,0,0,0,0,0,0,0,0,0,0,0,0,0,0,0,0,0,0,0,0,0,0,0,0,0,EC72)';
    'VSS'<18>:'(0,0,0,0,0,0,0,0,0,0,0,0,0,0,0,0,0,0,0,0,0,0,0,0,0,0,0,0,0,EC74)';
    'VSS'<17>:'(0,0,0,0,0,0,0,0,0,0,0,0,0,0,0,0,0,0,0,0,0,0,0,0,0,0,0,0,0,EC76)';
    'VSS'<16>:'(0,0,0,0,0,0,0,0,0,0,0,0,0,0,0,0,0,0,0,0,0,0,0,0,0,0,0,0,0,ED11)';
    'VSS'<15>:'(0,0,0,0,0,0,0,0,0,0,0,0,0,0,0,0,0,0,0,0,0,0,0,0,0,0,0,0,0,ED15)';
    'VSS'<14>:'(0,0,0,0,0,0,0,0,0,0,0,0,0,0,0,0,0,0,0,0,0,0,0,0,0,0,0,0,0,ED23)';
    'VSS'<13>:'(0,0,0,0,0,0,0,0,0,0,0,0,0,0,0,0,0,0,0,0,0,0,0,0,0,0,0,0,0,ED29)';
    'VSS'<12>:'(0,0,0,0,0,0,0,0,0,0,0,0,0,0,0,0,0,0,0,0,0,0,0,0,0,0,0,0,0,ED35)';
    'VSS'<11>:'(0,0,0,0,0,0,0,0,0,0,0,0,0,0,0,0,0,0,0,0,0,0,0,0,0,0,0,0,0,ED77)';
    'VSS'<10>:'(0,0,0,0,0,0,0,0,0,0,0,0,0,0,0,0,0,0,0,0,0,0,0,0,0,0,0,0,0,EE24)';
    'VSS'<9>:'(0,0,0,0,0,0,0,0,0,0,0,0,0,0,0,0,0,0,0,0,0,0,0,0,0,0,0,0,0,EE28)';~

    'VSS'<8>:'(0,0,0,0,0,0,0,0,0,0,0,0,0,0,0,0,0,0,0,0,0,0,0,0,0,0,0,0,0,EE30)';~

    'VSS'<7>:'(0,0,0,0,0,0,0,0,0,0,0,0,0,0,0,0,0,0,0,0,0,0,0,0,0,0,0,0,0,EE34)';~

    'VSS'<6>:'(0,0,0,0,0,0,0,0,0,0,0,0,0,0,0,0,0,0,0,0,0,0,0,0,0,0,0,0,0,EE36)';~

    'VSS'<5>:'(0,0,0,0,0,0,0,0,0,0,0,0,0,0,0,0,0,0,0,0,0,0,0,0,0,0,0,0,0,EE70)';~

    'VSS'<4>:'(0,0,0,0,0,0,0,0,0,0,0,0,0,0,0,0,0,0,0,0,0,0,0,0,0,0,0,0,0,EE76)';~

    'VSS'<3>:'(0,0,0,0,0,0,0,0,0,0,0,0,0,0,0,0,0,0,0,0,0,0,0,0,0,0,0,0,0,EE78)';~

    'VSS'<2>:'(0,0,0,0,0,0,0,0,0,0,0,0,0,0,0,0,0,0,0,0,0,0,0,0,0,0,0,0,0,EF71)';~

    'VSS'<1>:'(0,0,0,0,0,0,0,0,0,0,0,0,0,0,0,0,0,0,0,0,0,0,0,0,0,0,0,0,0,EF75)';~

    'VSS'<0>:'(0,0,0,0,0,0,0,0,0,0,0,0,0,0,0,0,0,0,0,0,0,0,0,0,0,0,0,0,0,EF79)';~

    'VSS_VCCIN_SENSE':'(0,0,0,0,0,0,0,0,0,0,0,0,0,0,0,0,0,0,AY85,0,0,0,0,0,0,0,0~
,0,0,0)';$S;
    'VSS_VCCIO_SENSE':'(0,0,0,0,0,0,0,0,0,0,0,0,0,0,0,0,0,0,0,0,0,BF5,0,0,0,0,0,~
0,0,0)';$S;
    'VSS_VCCSA_SENSE':'(0,0,0,0,0,0,0,0,0,0,0,0,0,0,0,0,0,0,0,0,0,CG76,0,0,0,0,0~
,0,0,0)';$S;
end_primitive;
primitive 'SLG55021_SM-IC,G56246-001';body 'SLG55021';
    'GND':'(4)';
    'THPAD':'(9)';
    'VCC':'(1)';
    'ON':'(2)';IN;
    'SHDN_N':'(3)';IN;
    'D':'(5)';IN;
    'S':'(6)';IN;
    'G':'(7)';OUT;
    'PG':'(8)';OUT;
end_primitive;
primitive 'SMC-CONN60A-22-GP_CONN-G7-SMC-A';body 'SMC-CONN60A-22-GP';
    '1':'(1)';
    '3':'(3)';
    '5':'(5)';
    '7':'(7)';
    '2':'(2)';
    '4':'(4)';
    '6':'(6)';
    '8':'(8)';
    '9':'(9)';
    '11':'(11)';
    '13':'(13)';
    '15':'(15)';
    '17':'(17)';
    '19':'(19)';
    '21':'(21)';
    '23':'(23)';
    '25':'(25)';
    '27':'(27)';
    '29':'(29)';
    '31':'(31)';
    '33':'(33)';
    '35':'(35)';
    '37':'(37)';
    '39':'(39)';
    '41':'(41)';
    '43':'(43)';
    '45':'(45)';
    '47':'(47)';
    '49':'(49)';
    '51':'(51)';
    '53':'(53)';
    '55':'(55)';
    '57':'(57)';
    '59':'(59)';
    '10':'(10)';
    '12':'(12)';
    '14':'(14)';
    '16':'(16)';
    '18':'(18)';
    '20':'(20)';
    '22':'(22)';
    '24':'(24)';
    '26':'(26)';
    '28':'(28)';
    '30':'(30)';
    '32':'(32)';
    '34':'(34)';
    '36':'(36)';
    '38':'(38)';
    '40':'(40)';
    '42':'(42)';
    '44':'(44)';
    '46':'(46)';
    '48':'(48)';
    '50':'(50)';
    '52':'(52)';
    '54':'(54)';
    '56':'(56)';
    '58':'(58)';
    '60':'(60)';
    'NP1':'(NP1)';
    'NP2':'(NP2)';
    'PTH1':'(PTH1)';
    'PTH2':'(PTH2)';
end_primitive;
primitive 'SNLABEL_A_LABEL-EMPTY,N_A';body 'SNLABEL_A';
end_primitive;
primitive 'SOCKET_P_MECH_A_LEFT-P0,PLASTIA';body 'SOCKET_P_MECH_A';
end_primitive;
primitive 'SOCKET_P_MECH_A_RIGHT-P0,PLASTA';body 'SOCKET_P_MECH_A';
end_primitive;
primitive 'SPRINGVILLE_SM1-IC,G47144-004';body 'SPRINGVILLE';
    'CBOT':'(37)';
    'CTOP':'(40)';
    'DEV_OFF_N':'(28)';IN;
    'GND':'(65)';
    'JTAG_CLK':'(19)';IN;
    'JTAG_TDI':'(29)';IN;
    'JTAG_TDO':'(4)';OUT;
    'JTAG_TMS':'(18)';IN;
    'LAN_PWR_GOOD':'(1)';IN;
    'LED0':'(31)';OUT;
    'LED1':'(30)';OUT;
    'LED2':'(33)';OUT;
    'MDI_MINUS0_SFP_I2C_DATA':'(57)';BIDI;
    'MDI_MINUS1_SRDS_SIG_DET':'(54)';BIDI;
    'MDI_MINUS2_SETN':'(52)';BIDI;
    'MDI_MINUS3_SERN':'(49)';BIDI;
    'MDI_PLUS0_NC':'(58)';BIDI;
    'MDI_PLUS1_SFP_I2C_CLK':'(55)';BIDI;
    'MDI_PLUS2_SETP':'(53)';BIDI;
    'MDI_PLUS3_SERP':'(50)';BIDI;
    'NC':'(22)';IN;
    'NC_SI_ARB_IN':'(43)';IN;
    'NC_SI_ARB_OUT':'(44)';OUT;
    'NC_SI_CLK_IN':'(2)';IN;
    'NC_SI_CRS_DV':'(3)';OUT;
    'NC_SI_RXD0':'(6)';OUT;
    'NC_SI_RXD1':'(5)';OUT;
    'NC_SI_TXD0':'(9)';IN;
    'NC_SI_TXD1':'(8)';IN;
    'NC_SI_TX_EN':'(7)';IN;
    'NVM_CS_N':'(15)';OUT;
    'NVM_SI':'(12)';OUT;
    'NVM_SK':'(13)';OUT;
    'NVM_SO':'(14)';IN;
    'PECLKN':'(25)';IN;
    'PECLKP':'(26)';IN;
    'PE_RN':'(23)';IN;
    'PE_RP':'(24)';IN;
    'PE_RST_N':'(17)';IN;
    'PE_TN':'(20)';OUT;
    'PE_TP':'(21)';OUT;
    'PE_WAKE_N':'(16)';BIDI;
    'RSET':'(48)';
    'SDP0':'(63)';BIDI;
    'SDP1_PCIE_DIS_SDP1':'(61)';BIDI;
    'SDP2':'(62)';BIDI;
    'SDP3':'(60)';BIDI;
    'SMB_ALRT_N':'(35)';OUT;
    'SMB_CLK':'(34)';BIDI;
    'SMB_DATA':'(36)';BIDI;
    'VDD0P9'<3>:'(42)';
    'VDD0P9'<2>:'(11)';
    'VDD0P9'<1>:'(32)';
    'VDD0P9'<0>:'(59)';
    'VDD0P9_OUT':'(38)';
    'VDD1P5'<1>:'(47)';
    'VDD1P5'<0>:'(56)';
    'VDD1P5_OUT':'(39)';
    'VDD3P3'<4>:'(10)';
    'VDD3P3'<3>:'(27)';
    'VDD3P3'<2>:'(41)';
    'VDD3P3'<1>:'(51)';
    'VDD3P3'<0>:'(64)';
    'XTAL1':'(46)';IN;
    'XTAL2':'(45)';OUT;
end_primitive;
primitive 'STANDOFF_TH1-SO,H72821-001';body 'STANDOFF';
    'IO1':'(1)';BIDI;
end_primitive;
primitive 'SWITCH_D37771002_SM-IC,D37771-A';body 'SWITCH_D37771002';
    'PIN4':'(4)';
    'PIN3':'(3)';
    'PIN1':'(1)';
    'PIN2':'(2)';
end_primitive;
primitive 'SWITCH_D90553001_SMLF-IC,D9055A';body 'SWITCH_D90553001';
    'A':'(1)';IN;
    'B':'(2)';BIDI;
end_primitive;
primitive 'SW_H67881001_SM-IC,H67881-001';body 'SW_H67881001';
    'IO1':'(1)';BIDI;
    'IO2':'(2)';BIDI;
    'IO3':'(3)';BIDI;
    'IO4':'(4)';BIDI;
end_primitive;
primitive 'TMP421_TSSOP-IC,G62962-001';body 'TMP421';
    'A'<1>:'(3)';IN;
    'A'<0>:'(4)';IN;
    'DXN':'(2)';IN;
    'DXP':'(1)';IN;
    'GND':'(5)';
    'SCL':'(7)';BIDI;
    'SDA':'(6)';BIDI;
    'VP':'(8)';
end_primitive;
primitive 'TPS2061_SM-IC,H66405-001';body 'TPS2061';
    'EN_N':'(4)';IN;
    'GND':'(2)';
    'IN':'(5)';IN;
    'OC_N':'(3)';OUT;
    'OUT':'(1)';OUT;
end_primitive;
primitive 'TPS3700_SM-IC,H69492-001';body 'TPS3700';
    'GND':'(5)';
    'INAP':'(4)';BIDI;
    'INBN':'(3)';BIDI;
    'OUTA':'(6)';OUT;
    'OUTB':'(1)';OUT;
    'VDD':'(2)';
end_primitive;
primitive 'TPS54821_LCC-IC,H63269-001';body 'TPS54821';
    'BOOT':'(13)';
    'COMP':'(8)';BIDI;
    'EN':'(10)';IN;
    'GND'<1>:'(3)';
    'GND'<0>:'(2)';
    'PH'<1>:'(12)';OUT;
    'PH'<0>:'(11)';OUT;
    'PVIN'<1>:'(5)';IN;
    'PVIN'<0>:'(4)';IN;
    'PWRGD':'(14)';OUT;
    'RT_CLK':'(1)';IN;
    'SS_TR':'(9)';IN;
    'THPAD':'(15)';
    'VIN':'(6)';IN;
    'VSENSE':'(7)';IN;
end_primitive;
primitive 'TTL08_QFN15-74LVC08A,IC,D90404B';body 'TTL08';
    'Y'<0>:'(11,8,6,3)';$S;OUT;
    'B'<0>:'(13,10,5,2)';$S;IN;
    'A'<0>:'(12,9,4,1)';$S;IN;
end_primitive;
primitive 'TTL1G07_A_SOP-74LVC1G07,IC,C88B';body 'TTL1G07_A';
    'A':'(2)';IN;
    'Y':'(4)';OUT;
end_primitive;
primitive 'TTL1G08_SOTLF-NC7SZ08,IC,D1032B';body 'TTL1G08';
    'Y'<0>:'(4)';OUT;
    'A'<0>:'(1)';IN;
    'B'<0>:'(2)';IN;
end_primitive;
primitive 'TTL1G08_SOTLF-NC7SZ08,IC,D1032C';body 'TTL1G08';
    'Y'<0>:'(4)';OUT;
    'A'<0>:'(1)';IN;
    'B'<0>:'(2)';IN;
end_primitive;
primitive 'TTL1G126_A_SOT-74HC1G126,IC,A7B';body 'TTL1G126_A';
    'OE':'(1)';IN;
    'A':'(2)';IN;
    'Y':'(4)';OUT;
end_primitive;
primitive 'TTL1G32_A_SOT-74LVC1G32,IC,E60B';body 'TTL1G32_A';
    'A':'(1)';IN;
    'B':'(2)';IN;
    'Y':'(4)';OUT;
end_primitive;
primitive 'TTL1G86_SOTLF-74AHCT1G86,IC,D3B';body 'TTL1G86';
    'A':'(1)';IN;
    'B':'(2)';IN;
    'Y':'(4)';OUT;
end_primitive;
primitive 'TTL2G07_SOT23LF-74LVC2G07,IC,DB';body 'TTL2G07';
    '1A':'(1)';IN;
    '2A':'(3)';IN;
    '2Y':'(4)';OUT;
    '1Y':'(6)';OUT;
end_primitive;
primitive 'TTL2G14_SMLF-74LVC2G14,IC,D184B';body 'TTL2G14';
    'A'<0>:'(1,3)';$S;IN;
    'Y'<0>:'(6,4)';$S;OUT;
end_primitive;
primitive 'TTL3126_QFNLF-74CBTLV3126,IC,DB';body 'TTL3126';
    'OE'<0>:'(1,4,10,13)';$S;IN;
    'A'<0>:'(2,5,9,12)';$S;BIDI;
    'B'<0>:'(3,6,8,11)';$S;BIDI;
end_primitive;
primitive 'VERT_BATT_3PIN_PIP-3PVERT,C686A';body 'VERT_BATT_3PIN';
    'N':'(3)';
    'P1':'(1)';
    'P2':'(2)';
end_primitive;
primitive 'W25Q128_SKT16-IC,H12709-001';body 'W25Q128';
    'HOLD_N_IO'<3>:'(1)';BIDI;
    'VCC':'(2)';
    'RESET_N':'(3)';IN;
    'NC'<0>:'(4)';
    'NC'<1>:'(5)';
    'NC'<2>:'(6)';
    'CS_N':'(7)';IN;
    'DO_IO'<1>:'(8)';BIDI;
    'WP_N_IO'<2>:'(9)';BIDI;
    'GND':'(10)';
    'NC'<3>:'(11)';
    'NC'<4>:'(12)';
    'NC'<5>:'(13)';
    'NC'<6>:'(14)';
    'DI_IO'<0>:'(15)';BIDI;
    'CLK':'(16)';IN;
end_primitive;
primitive 'W25Q256_XSOI-IC,H25002-001';body 'W25Q256';
    'WP_N_IO'<2>:'(9)';BIDI;
    'NC'<0>:'(14)';
    'NC'<1>:'(13)';
    'NC'<2>:'(12)';
    'NC'<3>:'(11)';
    'NC'<4>:'(6)';
    'NC'<5>:'(5)';
    'NC'<6>:'(4)';
    'GND':'(10)';
    'DO_IO'<1>:'(8)';BIDI;
    'CLK':'(16)';IN;
    'VCC':'(2)';
    'CS_N':'(7)';IN;
    'DI_IO'<0>:'(15)';BIDI;
    'RESET_N':'(3)';IN;
    'HOLD_N_IO'<3>:'(1)';BIDI;
end_primitive;
primitive 'ZENER_SM-13V,IC,H69095-001';body 'ZENER';
    'A':'(2)';
    'C':'(1)';
end_primitive;
END.
